G04 ================== begin FILE IDENTIFICATION RECORD ==================*
G04 Layout Name:  9324_DA0F0TMBIJ0_F0T_Motherboard_J_v01_20230324_0910.brd*
G04 Film Name:    gnd3*
G04 File Format:  Gerber RS274X*
G04 File Origin:  Cadence Allegro 17.2-S081*
G04 Origin Date:  Sat Mar 25 08:45:07 2023*
G04 *
G04 Layer:  DRAWING FORMAT/TITLE_BLOCK_A*
G04 Layer:  PIN/SPECIAL_DRILL*
G04 Layer:  VIA CLASS/GND3*
G04 Layer:  PIN/GND3*
G04 Layer:  MANUFACTURING/PHOTOPLOT_OUTLINE*
G04 Layer:  ETCH/GND3*
G04 Layer:  DRAWING FORMAT/TITLE_BLOCK*
G04 Layer:  DRAWING FORMAT/TITLE_DATA_GND3*
G04 *
G04 Offset:    (0.00 0.00)*
G04 Mirror:    No*
G04 Mode:      Negative*
G04 Rotation:  0*
G04 FullContactRelief:  No*
G04 UndefLineWidth:     6.00*
G04 ================== end FILE IDENTIFICATION RECORD ====================*
%FSLAX25Y25*MOIN*%
%IR0*IPPOS*OFA0.00000B0.00000*MIA0B0*SFA1.00000B1.00000*%
%ADD15C,.03*%
%ADD31C,.06*%
%ADD45C,.061*%
%ADD27C,.07*%
%AMMACRO54*
4,1,36,0.0,.01,
-.001736,.009848,
-.00342,.009397,
-.005,.00866,
-.006428,.00766,
-.00766,.006428,
-.00866,.005,
-.009397,.00342,
-.009848,.001736,
-.01,0.0,
-.009848,-.001736,
-.009397,-.00342,
-.00866,-.005,
-.00766,-.006428,
-.006428,-.00766,
-.005,-.00866,
-.00342,-.009397,
-.001736,-.009848,
0.0,-.01,
.001736,-.009848,
.00342,-.009397,
.005,-.00866,
.006428,-.00766,
.00766,-.006428,
.00866,-.005,
.009397,-.00342,
.009848,-.001736,
.01,0.0,
.009848,.001736,
.009397,.00342,
.00866,.005,
.00766,.006428,
.006428,.00766,
.005,.00866,
.00342,.009397,
.001736,.009848,
0.0,.01,
0.0*
%
%ADD54MACRO54*%
%ADD51C,.071*%
%ADD29C,.062*%
%ADD17C,.026*%
%AMMACRO70*
4,1,36,.0025,0.0,
.002462,.000434,
.002349,.000855,
.002165,.00125,
.001915,.001607,
.001607,.001915,
.00125,.002165,
.000855,.002349,
.000434,.002462,
0.0,.0025,
-.000434,.002462,
-.000855,.002349,
-.00125,.002165,
-.001607,.001915,
-.001915,.001607,
-.002165,.00125,
-.002349,.000855,
-.002462,.000434,
-.0025,0.0,
-.002462,-.000434,
-.002349,-.000855,
-.002165,-.00125,
-.001915,-.001607,
-.001607,-.001915,
-.00125,-.002165,
-.000855,-.002349,
-.000434,-.002462,
0.0,-.0025,
.000434,-.002462,
.000855,-.002349,
.00125,-.002165,
.001607,-.001915,
.001915,-.001607,
.002165,-.00125,
.002349,-.000855,
.002462,-.000434,
.0025,0.0,
135.*
%
%ADD70MACRO70*%
%ADD66C,.064*%
%AMMACRO19*
4,1,36,.0025,0.0,
.002462,.000434,
.002349,.000855,
.002165,.00125,
.001915,.001607,
.001607,.001915,
.00125,.002165,
.000855,.002349,
.000434,.002462,
0.0,.0025,
-.000434,.002462,
-.000855,.002349,
-.00125,.002165,
-.001607,.001915,
-.001915,.001607,
-.002165,.00125,
-.002349,.000855,
-.002462,.000434,
-.0025,0.0,
-.002462,-.000434,
-.002349,-.000855,
-.002165,-.00125,
-.001915,-.001607,
-.001607,-.001915,
-.00125,-.002165,
-.000855,-.002349,
-.000434,-.002462,
0.0,-.0025,
.000434,-.002462,
.000855,-.002349,
.00125,-.002165,
.001607,-.001915,
.001915,-.001607,
.002165,-.00125,
.002349,-.000855,
.002462,-.000434,
.0025,0.0,
225.*
%
%ADD19MACRO19*%
%AMMACRO14*
4,1,36,.0025,0.0,
.002462,.000434,
.002349,.000855,
.002165,.00125,
.001915,.001607,
.001607,.001915,
.00125,.002165,
.000855,.002349,
.000434,.002462,
0.0,.0025,
-.000434,.002462,
-.000855,.002349,
-.00125,.002165,
-.001607,.001915,
-.001915,.001607,
-.002165,.00125,
-.002349,.000855,
-.002462,.000434,
-.0025,0.0,
-.002462,-.000434,
-.002349,-.000855,
-.002165,-.00125,
-.001915,-.001607,
-.001607,-.001915,
-.00125,-.002165,
-.000855,-.002349,
-.000434,-.002462,
0.0,-.0025,
.000434,-.002462,
.000855,-.002349,
.00125,-.002165,
.001607,-.001915,
.001915,-.001607,
.002165,-.00125,
.002349,-.000855,
.002462,-.000434,
.0025,0.0,
180.*
%
%ADD14MACRO14*%
%AMMACRO11*
4,1,36,.0025,0.0,
.002462,.000434,
.002349,.000855,
.002165,.00125,
.001915,.001607,
.001607,.001915,
.00125,.002165,
.000855,.002349,
.000434,.002462,
0.0,.0025,
-.000434,.002462,
-.000855,.002349,
-.00125,.002165,
-.001607,.001915,
-.001915,.001607,
-.002165,.00125,
-.002349,.000855,
-.002462,.000434,
-.0025,0.0,
-.002462,-.000434,
-.002349,-.000855,
-.002165,-.00125,
-.001915,-.001607,
-.001607,-.001915,
-.00125,-.002165,
-.000855,-.002349,
-.000434,-.002462,
0.0,-.0025,
.000434,-.002462,
.000855,-.002349,
.00125,-.002165,
.001607,-.001915,
.001915,-.001607,
.002165,-.00125,
.002349,-.000855,
.002462,-.000434,
.0025,0.0,
270.*
%
%ADD11MACRO11*%
%AMMACRO52*
4,1,36,-.0025,0.0,
-.002462,.000434,
-.002349,.000855,
-.002165,.00125,
-.001915,.001607,
-.001607,.001915,
-.00125,.002165,
-.000855,.002349,
-.000434,.002462,
0.0,.0025,
.000434,.002462,
.000855,.002349,
.00125,.002165,
.001607,.001915,
.001915,.001607,
.002165,.00125,
.002349,.000855,
.002462,.000434,
.0025,0.0,
.002462,-.000434,
.002349,-.000855,
.002165,-.00125,
.001915,-.001607,
.001607,-.001915,
.00125,-.002165,
.000855,-.002349,
.000434,-.002462,
0.0,-.0025,
-.000434,-.002462,
-.000855,-.002349,
-.00125,-.002165,
-.001607,-.001915,
-.001915,-.001607,
-.002165,-.00125,
-.002349,-.000855,
-.002462,-.000434,
-.0025,0.0,
180.*
%
%ADD52MACRO52*%
%AMMACRO43*
4,1,36,.003,0.0,
.002954,.000521,
.002819,.001026,
.002598,.0015,
.002298,.001928,
.001928,.002298,
.0015,.002598,
.001026,.002819,
.000521,.002954,
0.0,.003,
-.000521,.002954,
-.001026,.002819,
-.0015,.002598,
-.001928,.002298,
-.002298,.001928,
-.002598,.0015,
-.002819,.001026,
-.002954,.000521,
-.003,0.0,
-.002954,-.000521,
-.002819,-.001026,
-.002598,-.0015,
-.002298,-.001928,
-.001928,-.002298,
-.0015,-.002598,
-.001026,-.002819,
-.000521,-.002954,
0.0,-.003,
.000521,-.002954,
.001026,-.002819,
.0015,-.002598,
.001928,-.002298,
.002298,-.001928,
.002598,-.0015,
.002819,-.001026,
.002954,-.000521,
.003,0.0,
270.*
%
%ADD43MACRO43*%
%AMMACRO41*
4,1,36,.003,0.0,
.002954,.000521,
.002819,.001026,
.002598,.0015,
.002298,.001928,
.001928,.002298,
.0015,.002598,
.001026,.002819,
.000521,.002954,
0.0,.003,
-.000521,.002954,
-.001026,.002819,
-.0015,.002598,
-.001928,.002298,
-.002298,.001928,
-.002598,.0015,
-.002819,.001026,
-.002954,.000521,
-.003,0.0,
-.002954,-.000521,
-.002819,-.001026,
-.002598,-.0015,
-.002298,-.001928,
-.001928,-.002298,
-.0015,-.002598,
-.001026,-.002819,
-.000521,-.002954,
0.0,-.003,
.000521,-.002954,
.001026,-.002819,
.0015,-.002598,
.001928,-.002298,
.002298,-.001928,
.002598,-.0015,
.002819,-.001026,
.002954,-.000521,
.003,0.0,
180.*
%
%ADD41MACRO41*%
%ADD26C,.074*%
%AMMACRO73*
4,1,36,-.003,0.0,
-.002954,.000521,
-.002819,.001026,
-.002598,.0015,
-.002298,.001928,
-.001928,.002298,
-.0015,.002598,
-.001026,.002819,
-.000521,.002954,
0.0,.003,
.000521,.002954,
.001026,.002819,
.0015,.002598,
.001928,.002298,
.002298,.001928,
.002598,.0015,
.002819,.001026,
.002954,.000521,
.003,0.0,
.002954,-.000521,
.002819,-.001026,
.002598,-.0015,
.002298,-.001928,
.001928,-.002298,
.0015,-.002598,
.001026,-.002819,
.000521,-.002954,
0.0,-.003,
-.000521,-.002954,
-.001026,-.002819,
-.0015,-.002598,
-.001928,-.002298,
-.002298,-.001928,
-.002598,-.0015,
-.002819,-.001026,
-.002954,-.000521,
-.003,0.0,
270.*
%
%ADD73MACRO73*%
%ADD72C,.0435*%
%ADD62C,.06015*%
%ADD49C,.076*%
%ADD48C,.095*%
%ADD24C,.0257*%
%ADD75C,.087*%
%ADD35C,.03417*%
%ADD40C,.0259*%
%ADD22C,.0277*%
%AMMACRO39*
4,1,15,.06231,.03403,
.067273,.022693,
.070191,.010666,
.070977,-.001684,
.069606,-.013984,
.066121,-.025858,
.06231,-.03403,
.06745,-.03917,
.073227,-.026862,
.076779,-.013739,
.077998,-.000197,
.076848,.01335,
.073362,.026492,
.067647,.038828,
.06745,.03917,
.06231,.03403,
0.0*
4,1,15,.03403,-.06231,
.022693,-.067273,
.010666,-.070191,
-.001684,-.070977,
-.013984,-.069606,
-.025858,-.066121,
-.03403,-.06231,
-.03917,-.06745,
-.026862,-.073227,
-.013739,-.076779,
-.000197,-.077998,
.01335,-.076848,
.026492,-.073362,
.038828,-.067647,
.03917,-.06745,
.03403,-.06231,
0.0*
4,1,15,-.06231,-.03403,
-.067273,-.022693,
-.070191,-.010666,
-.070977,.001684,
-.069606,.013984,
-.066121,.025858,
-.06231,.03403,
-.06745,.03917,
-.073227,.026862,
-.076779,.013739,
-.077998,.000197,
-.076848,-.01335,
-.073362,-.026492,
-.067647,-.038828,
-.06745,-.03917,
-.06231,-.03403,
0.0*
4,1,15,-.03403,.06231,
-.022693,.067273,
-.010666,.070191,
.001684,.070977,
.013984,.069606,
.025858,.066121,
.03403,.06231,
.03917,.06745,
.026862,.073227,
.013739,.076779,
.000197,.077998,
-.01335,.076848,
-.026492,.073362,
-.038828,.067647,
-.03917,.06745,
-.03403,.06231,
0.0*
%
%ADD39MACRO39*%
%AMMACRO10*
4,1,18,.09673,.06845,
.107147,.050613,
.114308,.031238,
.117996,.010914,
.118098,-.009741,
.114613,-.030101,
.107644,-.049546,
.097406,-.067485,
.09673,-.06845,
.10175,-.07347,
.112962,-.054685,
.120742,-.034239,
.124853,-.012752,
.125171,.009122,
.121685,.030719,
.114502,.051383,
.10384,.070486,
.10175,.07347,
.09673,.06845,
0.0*
4,1,18,.06845,-.09673,
.050613,-.107147,
.031238,-.114308,
.010914,-.117996,
-.009741,-.118098,
-.030101,-.114613,
-.049546,-.107644,
-.067485,-.097406,
-.06845,-.09673,
-.07347,-.10175,
-.054685,-.112962,
-.034239,-.120742,
-.012752,-.124853,
.009122,-.125171,
.030719,-.121685,
.051383,-.114502,
.070486,-.10384,
.07347,-.10175,
.06845,-.09673,
0.0*
4,1,18,-.09673,-.06845,
-.107147,-.050613,
-.114308,-.031238,
-.117996,-.010914,
-.118098,.009741,
-.114613,.030101,
-.107644,.049546,
-.097406,.067485,
-.09673,.06845,
-.10175,.07347,
-.112962,.054685,
-.120742,.034239,
-.124853,.012752,
-.125171,-.009122,
-.121685,-.030719,
-.114502,-.051383,
-.10384,-.070486,
-.10175,-.07347,
-.09673,-.06845,
0.0*
4,1,18,-.06845,.09673,
-.050613,.107147,
-.031238,.114308,
-.010914,.117996,
.009741,.118098,
.030101,.114613,
.049546,.107644,
.067485,.097406,
.06845,.09673,
.07347,.10175,
.054685,.112962,
.034239,.120742,
.012752,.124853,
-.009122,.125171,
-.030719,.121685,
-.051383,.114502,
-.070486,.10384,
-.07347,.10175,
-.06845,.09673,
0.0*
%
%ADD10MACRO10*%
%AMMACRO36*
4,1,16,.0711,.04282,
.077455,.029823,
.081457,.01592,
.082984,.001533,
.08199,-.0129,
.078504,-.026942,
.072633,-.040164,
.0711,-.04282,
.07619,-.04791,
.083352,-.033952,
.087981,-.018962,
.089937,-.003396,
.089161,.012273,
.085675,.027569,
.079586,.042027,
.07619,.04791,
.0711,.04282,
0.0*
4,1,16,.04282,-.0711,
.029823,-.077455,
.01592,-.081457,
.001533,-.082984,
-.0129,-.08199,
-.026942,-.078504,
-.040164,-.072633,
-.04282,-.0711,
-.04791,-.07619,
-.033952,-.083352,
-.018962,-.087981,
-.003396,-.089937,
.012273,-.089161,
.027569,-.085675,
.042027,-.079586,
.04791,-.07619,
.04282,-.0711,
0.0*
4,1,16,-.0711,-.04282,
-.077455,-.029823,
-.081457,-.01592,
-.082984,-.001533,
-.08199,.0129,
-.078504,.026942,
-.072633,.040164,
-.0711,.04282,
-.07619,.04791,
-.083352,.033952,
-.087981,.018962,
-.089937,.003396,
-.089161,-.012273,
-.085675,-.027569,
-.079586,-.042027,
-.07619,-.04791,
-.0711,-.04282,
0.0*
4,1,16,-.04282,.0711,
-.029823,.077455,
-.01592,.081457,
-.001533,.082984,
.0129,.08199,
.026942,.078504,
.040164,.072633,
.04282,.0711,
.04791,.07619,
.033952,.083352,
.018962,.087981,
.003396,.089937,
-.012273,.089161,
-.027569,.085675,
-.042027,.079586,
-.04791,.07619,
-.04282,.0711,
0.0*
%
%ADD36MACRO36*%
%AMMACRO32*
4,1,15,.02438,.01377,
.026401,.009327,
.027619,.004601,
.027999,-.000265,
.027527,-.005123,
.02622,-.009825,
.02438,-.01377,
.02948,-.01887,
.032309,-.013464,
.034156,-.007649,
.034965,-.001602,
.034712,.004494,
.033405,.010454,
.031082,.016095,
.02948,.01887,
.02438,.01377,
90.*
4,1,15,.01377,-.02438,
.009327,-.026401,
.004601,-.027619,
-.000265,-.027999,
-.005123,-.027527,
-.009825,-.02622,
-.01377,-.02438,
-.01887,-.02948,
-.013464,-.032309,
-.007649,-.034156,
-.001602,-.034965,
.004494,-.034712,
.010454,-.033405,
.016095,-.031082,
.01887,-.02948,
.01377,-.02438,
90.*
4,1,15,-.02438,-.01377,
-.026401,-.009327,
-.027619,-.004601,
-.027999,.000265,
-.027527,.005123,
-.02622,.009825,
-.02438,.01377,
-.02948,.01887,
-.032309,.013464,
-.034156,.007649,
-.034965,.001602,
-.034712,-.004494,
-.033405,-.010454,
-.031082,-.016095,
-.02948,-.01887,
-.02438,-.01377,
90.*
4,1,15,-.01377,.02438,
-.009327,.026401,
-.004601,.027619,
.000265,.027999,
.005123,.027527,
.009825,.02622,
.01377,.02438,
.01887,.02948,
.013464,.032309,
.007649,.034156,
.001602,.034965,
-.004494,.034712,
-.010454,.033405,
-.016095,.031082,
-.01887,.02948,
-.01377,.02438,
90.*
%
%ADD32MACRO32*%
%AMMACRO30*
4,1,15,.02438,.01377,
.026401,.009327,
.027619,.004601,
.027999,-.000265,
.027527,-.005123,
.02622,-.009825,
.02438,-.01377,
.02948,-.01887,
.032309,-.013464,
.034156,-.007649,
.034965,-.001602,
.034712,.004494,
.033405,.010454,
.031082,.016095,
.02948,.01887,
.02438,.01377,
0.0*
4,1,15,.01377,-.02438,
.009327,-.026401,
.004601,-.027619,
-.000265,-.027999,
-.005123,-.027527,
-.009825,-.02622,
-.01377,-.02438,
-.01887,-.02948,
-.013464,-.032309,
-.007649,-.034156,
-.001602,-.034965,
.004494,-.034712,
.010454,-.033405,
.016095,-.031082,
.01887,-.02948,
.01377,-.02438,
0.0*
4,1,15,-.02438,-.01377,
-.026401,-.009327,
-.027619,-.004601,
-.027999,.000265,
-.027527,.005123,
-.02622,.009825,
-.02438,.01377,
-.02948,.01887,
-.032309,.013464,
-.034156,.007649,
-.034965,.001602,
-.034712,-.004494,
-.033405,-.010454,
-.031082,-.016095,
-.02948,-.01887,
-.02438,-.01377,
0.0*
4,1,15,-.01377,.02438,
-.009327,.026401,
-.004601,.027619,
.000265,.027999,
.005123,.027527,
.009825,.02622,
.01377,.02438,
.01887,.02948,
.013464,.032309,
.007649,.034156,
.001602,.034965,
-.004494,.034712,
-.010454,.033405,
-.016095,.031082,
-.01887,.02948,
-.01377,.02438,
0.0*
%
%ADD30MACRO30*%
%AMMACRO47*
4,1,15,.02475,.01414,
.026829,.009627,
.028094,.004822,
.028504,-.000129,
.028049,-.005077,
.026741,-.009871,
.02475,-.01414,
.02984,-.01923,
.032726,-.013756,
.034617,-.007864,
.035457,-.001734,
.03522,.00445,
.033912,.010498,
.031574,.016227,
.02984,.01923,
.02475,.01414,
90.*
4,1,15,.01414,-.02475,
.009627,-.026829,
.004822,-.028094,
-.000129,-.028504,
-.005077,-.028049,
-.009871,-.026741,
-.01414,-.02475,
-.01923,-.02984,
-.013756,-.032726,
-.007864,-.034617,
-.001734,-.035457,
.00445,-.03522,
.010498,-.033912,
.016227,-.031574,
.01923,-.02984,
.01414,-.02475,
90.*
4,1,15,-.02475,-.01414,
-.026829,-.009627,
-.028094,-.004822,
-.028504,.000129,
-.028049,.005077,
-.026741,.009871,
-.02475,.01414,
-.02984,.01923,
-.032726,.013756,
-.034617,.007864,
-.035457,.001734,
-.03522,-.00445,
-.033912,-.010498,
-.031574,-.016227,
-.02984,-.01923,
-.02475,-.01414,
90.*
4,1,15,-.01414,.02475,
-.009627,.026829,
-.004822,.028094,
.000129,.028504,
.005077,.028049,
.009871,.026741,
.01414,.02475,
.01923,.02984,
.013756,.032726,
.007864,.034617,
.001734,.035457,
-.00445,.03522,
-.010498,.033912,
-.016227,.031574,
-.01923,.02984,
-.01414,.02475,
90.*
%
%ADD47MACRO47*%
%AMMACRO65*
4,1,18,.07103,.05689,
.07983,.043691,
.086204,.029165,
.089959,.013753,
.09098,-.002077,
.089237,-.017844,
.084783,-.033069,
.077753,-.047289,
.07103,-.05689,
.07601,-.06186,
.085597,-.047721,
.092583,-.032132,
.096757,-.015567,
.09799,.001471,
.096246,.018464,
.091577,.034897,
.084126,.050269,
.07601,.06186,
.07103,.05689,
0.0*
4,1,18,.05689,-.07103,
.043691,-.07983,
.029165,-.086204,
.013753,-.089959,
-.002077,-.09098,
-.017844,-.089237,
-.033069,-.084783,
-.047289,-.077753,
-.05689,-.07103,
-.06186,-.07601,
-.047721,-.085597,
-.032132,-.092583,
-.015567,-.096757,
.001471,-.09799,
.018464,-.096246,
.034897,-.091577,
.050269,-.084126,
.06186,-.07601,
.05689,-.07103,
0.0*
4,1,18,-.07103,-.05689,
-.07983,-.043691,
-.086204,-.029165,
-.089959,-.013753,
-.09098,.002077,
-.089237,.017844,
-.084783,.033069,
-.077753,.047289,
-.07103,.05689,
-.07601,.06186,
-.085597,.047721,
-.092583,.032132,
-.096757,.015567,
-.09799,-.001471,
-.096246,-.018464,
-.091577,-.034897,
-.084126,-.050269,
-.07601,-.06186,
-.07103,-.05689,
0.0*
4,1,18,-.05689,.07103,
-.043691,.07983,
-.029165,.086204,
-.013753,.089959,
.002077,.09098,
.017844,.089237,
.033069,.084783,
.047289,.077753,
.05689,.07103,
.06186,.07601,
.047721,.085597,
.032132,.092583,
.015567,.096757,
-.001471,.09799,
-.018464,.096246,
-.034897,.091577,
-.050269,.084126,
-.06186,.07601,
-.05689,.07103,
0.0*
%
%ADD65MACRO65*%
%AMMACRO50*
4,1,15,.02475,.01414,
.026829,.009627,
.028094,.004822,
.028504,-.000129,
.028049,-.005077,
.026741,-.009871,
.02475,-.01414,
.02984,-.01923,
.032726,-.013756,
.034617,-.007864,
.035457,-.001734,
.03522,.00445,
.033912,.010498,
.031574,.016227,
.02984,.01923,
.02475,.01414,
0.0*
4,1,15,.01414,-.02475,
.009627,-.026829,
.004822,-.028094,
-.000129,-.028504,
-.005077,-.028049,
-.009871,-.026741,
-.01414,-.02475,
-.01923,-.02984,
-.013756,-.032726,
-.007864,-.034617,
-.001734,-.035457,
.00445,-.03522,
.010498,-.033912,
.016227,-.031574,
.01923,-.02984,
.01414,-.02475,
0.0*
4,1,15,-.02475,-.01414,
-.026829,-.009627,
-.028094,-.004822,
-.028504,.000129,
-.028049,.005077,
-.026741,.009871,
-.02475,.01414,
-.02984,.01923,
-.032726,.013756,
-.034617,.007864,
-.035457,.001734,
-.03522,-.00445,
-.033912,-.010498,
-.031574,-.016227,
-.02984,-.01923,
-.02475,-.01414,
0.0*
4,1,15,-.01414,.02475,
-.009627,.026829,
-.004822,.028094,
.000129,.028504,
.005077,.028049,
.009871,.026741,
.01414,.02475,
.01923,.02984,
.013756,.032726,
.007864,.034617,
.001734,.035457,
-.00445,.03522,
-.010498,.033912,
-.016227,.031574,
-.01923,.02984,
-.01414,.02475,
0.0*
%
%ADD50MACRO50*%
%AMMACRO37*
4,1,16,.02511,.01451,
.027248,.009929,
.028558,.005047,
.029001,.000011,
.028562,-.005025,
.027256,-.009909,
.025121,-.014491,
.02511,-.01451,
.0302,-.01959,
.033143,-.014048,
.035079,-.00808,
.035949,-.001865,
.035727,.004405,
.034419,.010542,
.032065,.016359,
.0302,.01959,
.02511,.01451,
90.*
4,1,16,.01451,-.02511,
.009929,-.027248,
.005047,-.028558,
.000011,-.029001,
-.005025,-.028562,
-.009909,-.027256,
-.014491,-.025121,
-.01451,-.02511,
-.01959,-.0302,
-.014048,-.033143,
-.00808,-.035079,
-.001865,-.035949,
.004405,-.035727,
.010542,-.034419,
.016359,-.032065,
.01959,-.0302,
.01451,-.02511,
90.*
4,1,16,-.02511,-.01451,
-.027248,-.009929,
-.028558,-.005047,
-.029001,-.000011,
-.028562,.005025,
-.027256,.009909,
-.025121,.014491,
-.02511,.01451,
-.0302,.01959,
-.033143,.014048,
-.035079,.00808,
-.035949,.001865,
-.035727,-.004405,
-.034419,-.010542,
-.032065,-.016359,
-.0302,-.01959,
-.02511,-.01451,
90.*
4,1,16,-.01451,.02511,
-.009929,.027248,
-.005047,.028558,
-.000011,.029001,
.005025,.028562,
.009909,.027256,
.014491,.025121,
.01451,.02511,
.01959,.0302,
.014048,.033143,
.00808,.035079,
.001865,.035949,
-.004405,.035727,
-.010542,.034419,
-.016359,.032065,
-.01959,.0302,
-.01451,.02511,
90.*
%
%ADD37MACRO37*%
%AMMACRO28*
4,1,16,.02511,.01451,
.027248,.009929,
.028558,.005047,
.029001,.000011,
.028562,-.005025,
.027256,-.009909,
.025121,-.014491,
.02511,-.01451,
.0302,-.01959,
.033143,-.014048,
.035079,-.00808,
.035949,-.001865,
.035727,.004405,
.034419,.010542,
.032065,.016359,
.0302,.01959,
.02511,.01451,
0.0*
4,1,16,.01451,-.02511,
.009929,-.027248,
.005047,-.028558,
.000011,-.029001,
-.005025,-.028562,
-.009909,-.027256,
-.014491,-.025121,
-.01451,-.02511,
-.01959,-.0302,
-.014048,-.033143,
-.00808,-.035079,
-.001865,-.035949,
.004405,-.035727,
.010542,-.034419,
.016359,-.032065,
.01959,-.0302,
.01451,-.02511,
0.0*
4,1,16,-.02511,-.01451,
-.027248,-.009929,
-.028558,-.005047,
-.029001,-.000011,
-.028562,.005025,
-.027256,.009909,
-.025121,.014491,
-.02511,.01451,
-.0302,.01959,
-.033143,.014048,
-.035079,.00808,
-.035949,.001865,
-.035727,-.004405,
-.034419,-.010542,
-.032065,-.016359,
-.0302,-.01959,
-.02511,-.01451,
0.0*
4,1,16,-.01451,.02511,
-.009929,.027248,
-.005047,.028558,
-.000011,.029001,
.005025,.028562,
.009909,.027256,
.014491,.025121,
.01451,.02511,
.01959,.0302,
.014048,.033143,
.00808,.035079,
.001865,.035949,
-.004405,.035727,
-.010542,.034419,
-.016359,.032065,
-.01959,.0302,
-.01451,.02511,
0.0*
%
%ADD28MACRO28*%
%AMMACRO77*
4,1,15,.03682,.01914,
.039584,.012455,
.041146,.005393,
.041457,-.001834,
.040509,-.009005,
.03833,-.015903,
.03682,-.01914,
.04197,-.0243,
.045552,-.016643,
.04775,-.00848,
.048497,-.000059,
.047771,.008363,
.045593,.016531,
.042029,.024197,
.04197,.0243,
.03682,.01914,
0.0*
4,1,15,.01914,-.03682,
.012455,-.039584,
.005393,-.041146,
-.001834,-.041457,
-.009005,-.040509,
-.015903,-.03833,
-.01914,-.03682,
-.0243,-.04197,
-.016643,-.045552,
-.00848,-.04775,
-.000059,-.048497,
.008363,-.047771,
.016531,-.045593,
.024197,-.042029,
.0243,-.04197,
.01914,-.03682,
0.0*
4,1,15,-.03682,-.01914,
-.039584,-.012455,
-.041146,-.005393,
-.041457,.001834,
-.040509,.009005,
-.03833,.015903,
-.03682,.01914,
-.04197,.0243,
-.045552,.016643,
-.04775,.00848,
-.048497,.000059,
-.047771,-.008363,
-.045593,-.016531,
-.042029,-.024197,
-.04197,-.0243,
-.03682,-.01914,
0.0*
4,1,15,-.01914,.03682,
-.012455,.039584,
-.005393,.041146,
.001834,.041457,
.009005,.040509,
.015903,.03833,
.01914,.03682,
.0243,.04197,
.016643,.045552,
.00848,.04775,
.000059,.048497,
-.008363,.047771,
-.016531,.045593,
-.024197,.042029,
-.0243,.04197,
-.01914,.03682,
0.0*
%
%ADD77MACRO77*%
%AMMACRO74*
4,1,15,-.03682,.01914,
-.039584,.012455,
-.041146,.005393,
-.041457,-.001834,
-.040509,-.009005,
-.03833,-.015903,
-.03682,-.01914,
-.04197,-.0243,
-.045552,-.016643,
-.04775,-.00848,
-.048497,-.000059,
-.047771,.008363,
-.045593,.016531,
-.042029,.024197,
-.04197,.0243,
-.03682,.01914,
0.0*
4,1,15,-.01914,-.03682,
-.012455,-.039584,
-.005393,-.041146,
.001834,-.041457,
.009005,-.040509,
.015903,-.03833,
.01914,-.03682,
.0243,-.04197,
.016643,-.045552,
.00848,-.04775,
.000059,-.048497,
-.008363,-.047771,
-.016531,-.045593,
-.024197,-.042029,
-.0243,-.04197,
-.01914,-.03682,
0.0*
4,1,15,.03682,-.01914,
.039584,-.012455,
.041146,-.005393,
.041457,.001834,
.040509,.009005,
.03833,.015903,
.03682,.01914,
.04197,.0243,
.045552,.016643,
.04775,.00848,
.048497,.000059,
.047771,-.008363,
.045593,-.016531,
.042029,-.024197,
.04197,-.0243,
.03682,-.01914,
0.0*
4,1,15,.01914,.03682,
.012455,.039584,
.005393,.041146,
-.001834,.041457,
-.009005,.040509,
-.015903,.03833,
-.01914,.03682,
-.0243,.04197,
-.016643,.045552,
-.00848,.04775,
-.000059,.048497,
.008363,.047771,
.016531,.045593,
.024197,.042029,
.0243,.04197,
.01914,.03682,
0.0*
%
%ADD74MACRO74*%
%AMMACRO23*
4,1,25,-.0605,.00499,
-.05909,.011105,
-.05664,.016881,
-.053224,.022145,
-.048946,.026736,
-.043935,.030513,
-.038345,.033364,
-.032345,.0352,
-.02985,.03564,
-.025195,.035958,
-.02422,.03599,
-.005,.03599,
-.005,.03099,
-.02474,.03099,
-.026534,.030943,
-.028322,.030793,
-.02985,.03058,
-.035086,.029247,
-.040011,.027025,
-.044475,.023982,
-.048343,.020209,
-.051497,.015823,
-.053842,.010955,
-.055305,.005754,
-.05544,.00499,
-.0605,.00499,
0.0*
4,1,27,.005,.03599,
.02451,.03599,
.026071,.035998,
.027631,.035916,
.029183,.035743,
.02985,.03564,
.035965,.03423,
.041741,.03178,
.047005,.028364,
.051596,.024086,
.055373,.019075,
.058224,.013485,
.06006,.007485,
.0605,.00499,
.05544,.00499,
.054107,.010226,
.051885,.015151,
.048842,.019615,
.045069,.023483,
.040683,.026637,
.035815,.028982,
.030614,.030445,
.02985,.03058,
.0281,.030818,
.02634,.030955,
.02482,.03099,
.005,.03099,
.005,.03599,
0.0*
4,1,25,-.0605,-.00501,
-.05544,-.00501,
-.054107,-.010246,
-.051885,-.015171,
-.048842,-.019635,
-.045069,-.023503,
-.040683,-.026657,
-.035815,-.029002,
-.030614,-.030465,
-.02985,-.0306,
-.028079,-.03084,
-.026298,-.030976,
-.02487,-.03101,
-.005,-.03101,
-.005,-.03601,
-.02375,-.03601,
-.028562,-.035772,
-.02985,-.03566,
-.035965,-.03425,
-.041741,-.0318,
-.047005,-.028384,
-.051596,-.024106,
-.055373,-.019095,
-.058224,-.013505,
-.06006,-.007505,
-.0605,-.00501,
0.0*
4,1,27,.005,-.03101,
.02485,-.03101,
.02659,-.030963,
.028324,-.030815,
.02985,-.0306,
.035086,-.029267,
.040011,-.027045,
.044475,-.024002,
.048343,-.020229,
.051497,-.015843,
.053842,-.010975,
.055305,-.005774,
.05544,-.00501,
.0605,-.00501,
.05909,-.011125,
.05664,-.016901,
.053224,-.022165,
.048946,-.026756,
.043935,-.030533,
.038345,-.033384,
.032345,-.03522,
.02985,-.03566,
.028758,-.035841,
.027658,-.035958,
.026553,-.036011,
.02578,-.03601,
.005,-.03601,
.005,-.03101,
0.0*
%
%ADD23MACRO23*%
%ADD60R,.285X.23*%
%ADD67C,.142*%
%AMMACRO61*
4,1,36,0.0,.01,
-.001736,.009848,
-.00342,.009397,
-.005,.00866,
-.006428,.00766,
-.00766,.006428,
-.00866,.005,
-.009397,.00342,
-.009848,.001736,
-.01,0.0,
-.009848,-.001736,
-.009397,-.00342,
-.00866,-.005,
-.00766,-.006428,
-.006428,-.00766,
-.005,-.00866,
-.00342,-.009397,
-.001736,-.009848,
0.0,-.01,
.001736,-.009848,
.00342,-.009397,
.005,-.00866,
.006428,-.00766,
.00766,-.006428,
.00866,-.005,
.009397,-.00342,
.009848,-.001736,
.01,0.0,
.009848,.001736,
.009397,.00342,
.00866,.005,
.00766,.006428,
.006428,.00766,
.005,.00866,
.00342,.009397,
.001736,.009848,
0.0,.01,
180.*
%
%ADD61MACRO61*%
%ADD33O,.219X.156*%
%ADD13C,.125*%
%AMMACRO68*
4,1,36,.0025,0.0,
.002462,.000434,
.002349,.000855,
.002165,.00125,
.001915,.001607,
.001607,.001915,
.00125,.002165,
.000855,.002349,
.000434,.002462,
0.0,.0025,
-.000434,.002462,
-.000855,.002349,
-.00125,.002165,
-.001607,.001915,
-.001915,.001607,
-.002165,.00125,
-.002349,.000855,
-.002462,.000434,
-.0025,0.0,
-.002462,-.000434,
-.002349,-.000855,
-.002165,-.00125,
-.001915,-.001607,
-.001607,-.001915,
-.00125,-.002165,
-.000855,-.002349,
-.000434,-.002462,
0.0,-.0025,
.000434,-.002462,
.000855,-.002349,
.00125,-.002165,
.001607,-.001915,
.001915,-.001607,
.002165,-.00125,
.002349,-.000855,
.002462,-.000434,
.0025,0.0,
30.*
%
%ADD68MACRO68*%
%ADD18C,.424*%
%ADD21C,.155*%
%ADD53C,.291*%
%ADD38C,.165*%
%ADD55C,.247*%
%ADD44C,.256*%
%AMMACRO34*
4,1,36,0.0,.0085,
.001476,.008371,
.002907,.007987,
.00425,.007361,
.005464,.006511,
.006511,.005464,
.007361,.00425,
.007987,.002907,
.008371,.001476,
.0085,0.0,
.008371,-.001476,
.007987,-.002907,
.007361,-.00425,
.006511,-.005464,
.005464,-.006511,
.00425,-.007361,
.002907,-.007987,
.001476,-.008371,
0.0,-.0085,
-.001476,-.008371,
-.002907,-.007987,
-.00425,-.007361,
-.005464,-.006511,
-.006511,-.005464,
-.007361,-.00425,
-.007987,-.002907,
-.008371,-.001476,
-.0085,0.0,
-.008371,.001476,
-.007987,.002907,
-.007361,.00425,
-.006511,.005464,
-.005464,.006511,
-.00425,.007361,
-.002907,.007987,
-.001476,.008371,
0.0,.0085,
180.*
%
%ADD34MACRO34*%
%AMMACRO59*
4,1,20,-.0075,-.05555,
-.0075,-.06273,
-.013677,-.060878,
-.019439,-.057981,
-.024611,-.054127,
-.029034,-.049434,
-.032576,-.044045,
-.035127,-.038122,
-.036612,-.031846,
-.037,-.0265,
-.037,-.0075,
-.03,-.0075,
-.03,-.0265,
-.029544,-.03171,
-.028191,-.036762,
-.02598,-.041502,
-.022981,-.045786,
-.019282,-.049484,
-.014998,-.052484,
-.010258,-.054694,
-.0075,-.05555,
90.*
4,1,20,.0075,-.06273,
.0075,-.05555,
.01243,-.053806,
.016983,-.051232,
.02102,-.047906,
.024418,-.043931,
.027073,-.039425,
.028906,-.034527,
.029861,-.029385,
.03,-.0265,
.03,-.0075,
.037,-.0075,
.037,-.0265,
.036438,-.032925,
.034769,-.039154,
.032043,-.044999,
.028344,-.050282,
.023784,-.054842,
.018501,-.058541,
.012656,-.061266,
.0075,-.06273,
90.*
4,1,20,-.0075,.06273,
-.0075,.05555,
-.01243,.053806,
-.016983,.051232,
-.02102,.047906,
-.024418,.043931,
-.027073,.039425,
-.028906,.034527,
-.029861,.029385,
-.03,.0265,
-.03,.0075,
-.037,.0075,
-.037,.0265,
-.036438,.032925,
-.034769,.039154,
-.032043,.044999,
-.028344,.050282,
-.023784,.054842,
-.018501,.058541,
-.012656,.061266,
-.0075,.06273,
90.*
4,1,20,.0075,.05555,
.0075,.06273,
.013677,.060878,
.019439,.057981,
.024611,.054127,
.029034,.049434,
.032576,.044045,
.035127,.038122,
.036612,.031846,
.037,.0265,
.037,.0075,
.03,.0075,
.03,.0265,
.029544,.03171,
.028191,.036762,
.02598,.041502,
.022981,.045786,
.019282,.049484,
.014998,.052484,
.010258,.054694,
.0075,.05555,
90.*
%
%ADD59MACRO59*%
%AMMACRO20*
4,1,36,.0025,0.0,
.002462,.000434,
.002349,.000855,
.002165,.00125,
.001915,.001607,
.001607,.001915,
.00125,.002165,
.000855,.002349,
.000434,.002462,
0.0,.0025,
-.000434,.002462,
-.000855,.002349,
-.00125,.002165,
-.001607,.001915,
-.001915,.001607,
-.002165,.00125,
-.002349,.000855,
-.002462,.000434,
-.0025,0.0,
-.002462,-.000434,
-.002349,-.000855,
-.002165,-.00125,
-.001915,-.001607,
-.001607,-.001915,
-.00125,-.002165,
-.000855,-.002349,
-.000434,-.002462,
0.0,-.0025,
.000434,-.002462,
.000855,-.002349,
.00125,-.002165,
.001607,-.001915,
.001915,-.001607,
.002165,-.00125,
.002349,-.000855,
.002462,-.000434,
.0025,0.0,
90.*
%
%ADD20MACRO20*%
%AMMACRO56*
4,1,36,0.0,.019,
-.003299,.018711,
-.006498,.017854,
-.0095,.016454,
-.012213,.014555,
-.014555,.012213,
-.016454,.0095,
-.017854,.006498,
-.018711,.003299,
-.019,0.0,
-.018711,-.003299,
-.017854,-.006498,
-.016454,-.0095,
-.014555,-.012213,
-.012213,-.014555,
-.0095,-.016454,
-.006498,-.017854,
-.003299,-.018711,
0.0,-.019,
.003299,-.018711,
.006498,-.017854,
.0095,-.016454,
.012213,-.014555,
.014555,-.012213,
.016454,-.0095,
.017854,-.006498,
.018711,-.003299,
.019,0.0,
.018711,.003299,
.017854,.006498,
.016454,.0095,
.014555,.012213,
.012213,.014555,
.0095,.016454,
.006498,.017854,
.003299,.018711,
0.0,.019,
270.*
%
%ADD56MACRO56*%
%AMMACRO42*
4,1,36,.003,0.0,
.002954,.000521,
.002819,.001026,
.002598,.0015,
.002298,.001928,
.001928,.002298,
.0015,.002598,
.001026,.002819,
.000521,.002954,
0.0,.003,
-.000521,.002954,
-.001026,.002819,
-.0015,.002598,
-.001928,.002298,
-.002298,.001928,
-.002598,.0015,
-.002819,.001026,
-.002954,.000521,
-.003,0.0,
-.002954,-.000521,
-.002819,-.001026,
-.002598,-.0015,
-.002298,-.001928,
-.001928,-.002298,
-.0015,-.002598,
-.001026,-.002819,
-.000521,-.002954,
0.0,-.003,
.000521,-.002954,
.001026,-.002819,
.0015,-.002598,
.001928,-.002298,
.002298,-.001928,
.002598,-.0015,
.002819,-.001026,
.002954,-.000521,
.003,0.0,
90.*
%
%ADD42MACRO42*%
%AMMACRO12*
4,1,36,.0025,0.0,
.002462,.000434,
.002349,.000855,
.002165,.00125,
.001915,.001607,
.001607,.001915,
.00125,.002165,
.000855,.002349,
.000434,.002462,
0.0,.0025,
-.000434,.002462,
-.000855,.002349,
-.00125,.002165,
-.001607,.001915,
-.001915,.001607,
-.002165,.00125,
-.002349,.000855,
-.002462,.000434,
-.0025,0.0,
-.002462,-.000434,
-.002349,-.000855,
-.002165,-.00125,
-.001915,-.001607,
-.001607,-.001915,
-.00125,-.002165,
-.000855,-.002349,
-.000434,-.002462,
0.0,-.0025,
.000434,-.002462,
.000855,-.002349,
.00125,-.002165,
.001607,-.001915,
.001915,-.001607,
.002165,-.00125,
.002349,-.000855,
.002462,-.000434,
.0025,0.0,
0.0*
%
%ADD12MACRO12*%
%AMMACRO71*
4,1,36,-.003,0.0,
-.002954,.000521,
-.002819,.001026,
-.002598,.0015,
-.002298,.001928,
-.001928,.002298,
-.0015,.002598,
-.001026,.002819,
-.000521,.002954,
0.0,.003,
.000521,.002954,
.001026,.002819,
.0015,.002598,
.001928,.002298,
.002298,.001928,
.002598,.0015,
.002819,.001026,
.002954,.000521,
.003,0.0,
.002954,-.000521,
.002819,-.001026,
.002598,-.0015,
.002298,-.001928,
.001928,-.002298,
.0015,-.002598,
.001026,-.002819,
.000521,-.002954,
0.0,-.003,
-.000521,-.002954,
-.001026,-.002819,
-.0015,-.002598,
-.001928,-.002298,
-.002298,-.001928,
-.002598,-.0015,
-.002819,-.001026,
-.002954,-.000521,
-.003,0.0,
90.*
%
%ADD71MACRO71*%
%AMMACRO63*
4,1,36,-.0025,0.0,
-.002462,.000434,
-.002349,.000855,
-.002165,.00125,
-.001915,.001607,
-.001607,.001915,
-.00125,.002165,
-.000855,.002349,
-.000434,.002462,
0.0,.0025,
.000434,.002462,
.000855,.002349,
.00125,.002165,
.001607,.001915,
.001915,.001607,
.002165,.00125,
.002349,.000855,
.002462,.000434,
.0025,0.0,
.002462,-.000434,
.002349,-.000855,
.002165,-.00125,
.001915,-.001607,
.001607,-.001915,
.00125,-.002165,
.000855,-.002349,
.000434,-.002462,
0.0,-.0025,
-.000434,-.002462,
-.000855,-.002349,
-.00125,-.002165,
-.001607,-.001915,
-.001915,-.001607,
-.002165,-.00125,
-.002349,-.000855,
-.002462,-.000434,
-.0025,0.0,
0.0*
%
%ADD63MACRO63*%
%ADD57C,.188*%
%AMMACRO16*
4,1,36,.003,0.0,
.002954,.000521,
.002819,.001026,
.002598,.0015,
.002298,.001928,
.001928,.002298,
.0015,.002598,
.001026,.002819,
.000521,.002954,
0.0,.003,
-.000521,.002954,
-.001026,.002819,
-.0015,.002598,
-.001928,.002298,
-.002298,.001928,
-.002598,.0015,
-.002819,.001026,
-.002954,.000521,
-.003,0.0,
-.002954,-.000521,
-.002819,-.001026,
-.002598,-.0015,
-.002298,-.001928,
-.001928,-.002298,
-.0015,-.002598,
-.001026,-.002819,
-.000521,-.002954,
0.0,-.003,
.000521,-.002954,
.001026,-.002819,
.0015,-.002598,
.001928,-.002298,
.002298,-.001928,
.002598,-.0015,
.002819,-.001026,
.002954,-.000521,
.003,0.0,
0.0*
%
%ADD16MACRO16*%
%AMMACRO25*
4,1,16,.02584,.01524,
.028094,.010521,
.029494,.005483,
.029998,.000278,
.029591,-.004935,
.028284,-.009999,
.026118,-.014758,
.02584,-.01524,
.03092,-.02032,
.033979,-.014642,
.036005,-.008519,
.036938,-.002138,
.036748,.004309,
.035441,.010625,
.033058,.016618,
.03092,.02032,
.02584,.01524,
180.*
4,1,16,.01524,-.02584,
.010521,-.028094,
.005483,-.029494,
.000278,-.029998,
-.004935,-.029591,
-.009999,-.028284,
-.014758,-.026118,
-.01524,-.02584,
-.02032,-.03092,
-.014642,-.033979,
-.008519,-.036005,
-.002138,-.036938,
.004309,-.036748,
.010625,-.035441,
.016618,-.033058,
.02032,-.03092,
.01524,-.02584,
180.*
4,1,16,-.02584,-.01524,
-.028094,-.010521,
-.029494,-.005483,
-.029998,-.000278,
-.029591,.004935,
-.028284,.009999,
-.026118,.014758,
-.02584,.01524,
-.03092,.02032,
-.033979,.014642,
-.036005,.008519,
-.036938,.002138,
-.036748,-.004309,
-.035441,-.010625,
-.033058,-.016618,
-.03092,-.02032,
-.02584,-.01524,
180.*
4,1,16,-.01524,.02584,
-.010521,.028094,
-.005483,.029494,
-.000278,.029998,
.004935,.029591,
.009999,.028284,
.014758,.026118,
.01524,.02584,
.02032,.03092,
.014642,.033979,
.008519,.036005,
.002138,.036938,
-.004309,.036748,
-.010625,.035441,
-.016618,.033058,
-.02032,.03092,
-.01524,.02584,
180.*
%
%ADD25MACRO25*%
%AMMACRO64*
4,1,15,.02438,.01377,
.026401,.009327,
.027619,.004601,
.027999,-.000265,
.027527,-.005123,
.02622,-.009825,
.02438,-.01377,
.02948,-.01887,
.032309,-.013464,
.034156,-.007649,
.034965,-.001602,
.034712,.004494,
.033405,.010454,
.031082,.016095,
.02948,.01887,
.02438,.01377,
270.*
4,1,15,.01377,-.02438,
.009327,-.026401,
.004601,-.027619,
-.000265,-.027999,
-.005123,-.027527,
-.009825,-.02622,
-.01377,-.02438,
-.01887,-.02948,
-.013464,-.032309,
-.007649,-.034156,
-.001602,-.034965,
.004494,-.034712,
.010454,-.033405,
.016095,-.031082,
.01887,-.02948,
.01377,-.02438,
270.*
4,1,15,-.02438,-.01377,
-.026401,-.009327,
-.027619,-.004601,
-.027999,.000265,
-.027527,.005123,
-.02622,.009825,
-.02438,.01377,
-.02948,.01887,
-.032309,.013464,
-.034156,.007649,
-.034965,.001602,
-.034712,-.004494,
-.033405,-.010454,
-.031082,-.016095,
-.02948,-.01887,
-.02438,-.01377,
270.*
4,1,15,-.01377,.02438,
-.009327,.026401,
-.004601,.027619,
.000265,.027999,
.005123,.027527,
.009825,.02622,
.01377,.02438,
.01887,.02948,
.013464,.032309,
.007649,.034156,
.001602,.034965,
-.004494,.034712,
-.010454,.033405,
-.016095,.031082,
-.01887,.02948,
-.01377,.02438,
270.*
%
%ADD64MACRO64*%
%AMMACRO69*
4,1,15,.02475,.01414,
.026829,.009627,
.028094,.004822,
.028504,-.000129,
.028049,-.005077,
.026741,-.009871,
.02475,-.01414,
.02984,-.01923,
.032726,-.013756,
.034617,-.007864,
.035457,-.001734,
.03522,.00445,
.033912,.010498,
.031574,.016227,
.02984,.01923,
.02475,.01414,
180.*
4,1,15,.01414,-.02475,
.009627,-.026829,
.004822,-.028094,
-.000129,-.028504,
-.005077,-.028049,
-.009871,-.026741,
-.01414,-.02475,
-.01923,-.02984,
-.013756,-.032726,
-.007864,-.034617,
-.001734,-.035457,
.00445,-.03522,
.010498,-.033912,
.016227,-.031574,
.01923,-.02984,
.01414,-.02475,
180.*
4,1,15,-.02475,-.01414,
-.026829,-.009627,
-.028094,-.004822,
-.028504,.000129,
-.028049,.005077,
-.026741,.009871,
-.02475,.01414,
-.02984,.01923,
-.032726,.013756,
-.034617,.007864,
-.035457,.001734,
-.03522,-.00445,
-.033912,-.010498,
-.031574,-.016227,
-.02984,-.01923,
-.02475,-.01414,
180.*
4,1,15,-.01414,.02475,
-.009627,.026829,
-.004822,.028094,
.000129,.028504,
.005077,.028049,
.009871,.026741,
.01414,.02475,
.01923,.02984,
.013756,.032726,
.007864,.034617,
.001734,.035457,
-.00445,.03522,
-.010498,.033912,
-.016227,.031574,
-.01923,.02984,
-.01414,.02475,
180.*
%
%ADD69MACRO69*%
%AMMACRO46*
4,1,15,.02475,.01414,
.026829,.009627,
.028094,.004822,
.028504,-.000129,
.028049,-.005077,
.026741,-.009871,
.02475,-.01414,
.02984,-.01923,
.032726,-.013756,
.034617,-.007864,
.035457,-.001734,
.03522,.00445,
.033912,.010498,
.031574,.016227,
.02984,.01923,
.02475,.01414,
270.*
4,1,15,.01414,-.02475,
.009627,-.026829,
.004822,-.028094,
-.000129,-.028504,
-.005077,-.028049,
-.009871,-.026741,
-.01414,-.02475,
-.01923,-.02984,
-.013756,-.032726,
-.007864,-.034617,
-.001734,-.035457,
.00445,-.03522,
.010498,-.033912,
.016227,-.031574,
.01923,-.02984,
.01414,-.02475,
270.*
4,1,15,-.02475,-.01414,
-.026829,-.009627,
-.028094,-.004822,
-.028504,.000129,
-.028049,.005077,
-.026741,.009871,
-.02475,.01414,
-.02984,.01923,
-.032726,.013756,
-.034617,.007864,
-.035457,.001734,
-.03522,-.00445,
-.033912,-.010498,
-.031574,-.016227,
-.02984,-.01923,
-.02475,-.01414,
270.*
4,1,15,-.01414,.02475,
-.009627,.026829,
-.004822,.028094,
.000129,.028504,
.005077,.028049,
.009871,.026741,
.01414,.02475,
.01923,.02984,
.013756,.032726,
.007864,.034617,
.001734,.035457,
-.00445,.03522,
-.010498,.033912,
-.016227,.031574,
-.01923,.02984,
-.01414,.02475,
270.*
%
%ADD46MACRO46*%
%AMMACRO58*
4,1,15,.04124,.02356,
.044705,.016041,
.046811,.008034,
.047495,-.000216,
.046736,-.008461,
.044557,-.016448,
.04124,-.02356,
.04635,-.02867,
.050624,-.020186,
.05336,-.011088,
.054475,-.001654,
.053935,.007831,
.051756,.017077,
.048004,.025805,
.04635,.02867,
.04124,.02356,
0.0*
4,1,15,.02356,-.04124,
.016041,-.044705,
.008034,-.046811,
-.000216,-.047495,
-.008461,-.046736,
-.016448,-.044557,
-.02356,-.04124,
-.02867,-.04635,
-.020186,-.050624,
-.011088,-.05336,
-.001654,-.054475,
.007831,-.053935,
.017077,-.051756,
.025805,-.048004,
.02867,-.04635,
.02356,-.04124,
0.0*
4,1,15,-.04124,-.02356,
-.044705,-.016041,
-.046811,-.008034,
-.047495,.000216,
-.046736,.008461,
-.044557,.016448,
-.04124,.02356,
-.04635,.02867,
-.050624,.020186,
-.05336,.011088,
-.054475,.001654,
-.053935,-.007831,
-.051756,-.017077,
-.048004,-.025805,
-.04635,-.02867,
-.04124,-.02356,
0.0*
4,1,15,-.02356,.04124,
-.016041,.044705,
-.008034,.046811,
.000216,.047495,
.008461,.046736,
.016448,.044557,
.02356,.04124,
.02867,.04635,
.020186,.050624,
.011088,.05336,
.001654,.054475,
-.007831,.053935,
-.017077,.051756,
-.025805,.048004,
-.02867,.04635,
-.02356,.04124,
0.0*
%
%ADD58MACRO58*%
%AMMACRO78*
4,1,15,.03682,.01914,
.039584,.012455,
.041146,.005393,
.041457,-.001834,
.040509,-.009005,
.03833,-.015903,
.03682,-.01914,
.04197,-.0243,
.045552,-.016643,
.04775,-.00848,
.048497,-.000059,
.047771,.008363,
.045593,.016531,
.042029,.024197,
.04197,.0243,
.03682,.01914,
180.*
4,1,15,.01914,-.03682,
.012455,-.039584,
.005393,-.041146,
-.001834,-.041457,
-.009005,-.040509,
-.015903,-.03833,
-.01914,-.03682,
-.0243,-.04197,
-.016643,-.045552,
-.00848,-.04775,
-.000059,-.048497,
.008363,-.047771,
.016531,-.045593,
.024197,-.042029,
.0243,-.04197,
.01914,-.03682,
180.*
4,1,15,-.03682,-.01914,
-.039584,-.012455,
-.041146,-.005393,
-.041457,.001834,
-.040509,.009005,
-.03833,.015903,
-.03682,.01914,
-.04197,.0243,
-.045552,.016643,
-.04775,.00848,
-.048497,.000059,
-.047771,-.008363,
-.045593,-.016531,
-.042029,-.024197,
-.04197,-.0243,
-.03682,-.01914,
180.*
4,1,15,-.01914,.03682,
-.012455,.039584,
-.005393,.041146,
.001834,.041457,
.009005,.040509,
.015903,.03833,
.01914,.03682,
.0243,.04197,
.016643,.045552,
.00848,.04775,
.000059,.048497,
-.008363,.047771,
-.016531,.045593,
-.024197,.042029,
-.0243,.04197,
-.01914,.03682,
180.*
%
%ADD78MACRO78*%
%AMMACRO76*
4,1,15,-.03682,.01914,
-.039584,.012455,
-.041146,.005393,
-.041457,-.001834,
-.040509,-.009005,
-.03833,-.015903,
-.03682,-.01914,
-.04197,-.0243,
-.045552,-.016643,
-.04775,-.00848,
-.048497,-.000059,
-.047771,.008363,
-.045593,.016531,
-.042029,.024197,
-.04197,.0243,
-.03682,.01914,
180.*
4,1,15,-.01914,-.03682,
-.012455,-.039584,
-.005393,-.041146,
.001834,-.041457,
.009005,-.040509,
.015903,-.03833,
.01914,-.03682,
.0243,-.04197,
.016643,-.045552,
.00848,-.04775,
.000059,-.048497,
-.008363,-.047771,
-.016531,-.045593,
-.024197,-.042029,
-.0243,-.04197,
-.01914,-.03682,
180.*
4,1,15,.03682,-.01914,
.039584,-.012455,
.041146,-.005393,
.041457,.001834,
.040509,.009005,
.03833,.015903,
.03682,.01914,
.04197,.0243,
.045552,.016643,
.04775,.00848,
.048497,.000059,
.047771,-.008363,
.045593,-.016531,
.042029,-.024197,
.04197,-.0243,
.03682,-.01914,
180.*
4,1,15,.01914,.03682,
.012455,.039584,
.005393,.041146,
-.001834,.041457,
-.009005,.040509,
-.015903,.03833,
-.01914,.03682,
-.0243,.04197,
-.016643,.045552,
-.00848,.04775,
-.000059,.048497,
.008363,.047771,
.016531,.045593,
.024197,.042029,
.0243,.04197,
.01914,.03682,
180.*
%
%ADD76MACRO76*%
%ADD79C,.006*%
%ADD104C,.04006*%
%ADD101C,.03016*%
%ADD97C,.03018*%
%ADD102C,.07008*%
%ADD82C,.07306*%
%ADD89C,.07208*%
%ADD93C,.07308*%
%ADD94C,.07608*%
%ADD92C,.07808*%
%ADD91C,.09708*%
%ADD88O,.1621X.2251*%
%ADD84C,.311*%
%ADD99C,.1621*%
%ADD81O,.03004X.06404*%
%ADD100C,.16211*%
%ADD96C,.1751*%
%ADD80O,.03006X.06406*%
%ADD95C,.43406*%
%ADD83C,.16506*%
%ADD90C,.25806*%
%ADD98C,.43376*%
%ADD103C,.19786*%
%ADD87O,.43374X.77626*%
%ADD85O,.43374X.69752*%
%ADD86O,.43376X.69754*%
G75*
%LPD*%
G75*
G36*
G01X-984580Y-698988D02*
X5868320D01*
Y4193602D01*
X-984580D01*
Y-698988D01*
G37*
%LPC*%
G75*
G36*
G01X1828062Y36504D02*
X1828081Y36500D01*
G03X1828470Y36462I388J1962D01*
G03X1828859Y36500I1J2000D01*
G01X1828878Y36504D01*
X1849606D01*
G02X1855480Y30630I0J-5874D01*
G01Y-40945D01*
G02X1849606Y-46819I-5874J0D01*
G01X7874D01*
G02X2000Y-40945I0J5874D01*
G01Y30630D01*
G02X7874Y36504I5874J0D01*
G01X35835D01*
G02X41709Y30630I0J-5874D01*
G01Y-3937D01*
G03X51583Y-13811I9874J0D01*
G01X321661D01*
G03X331535Y-3937I0J9874D01*
G01Y30630D01*
G02X337409Y36504I5874J0D01*
G01X480717D01*
G02X486591Y30630I0J-5874D01*
G01Y16850D01*
G03X496465Y6976I9874J0D01*
G01X766543D01*
G03X776417Y16850I0J9874D01*
G01Y30630D01*
G02X782291Y36504I5874J0D01*
G01X879134D01*
G03X889008Y46378I0J9874D01*
G01Y122824D01*
X895188Y129004D01*
X1002542D01*
X1009024Y122522D01*
Y46378D01*
G03X1018898Y36504I9874J0D01*
G01X1510244D01*
G02X1516118Y30630I0J-5874D01*
G01Y-3937D01*
G03X1525992Y-13811I9874J0D01*
G01X1796071D01*
G03X1805945Y-3937I0J9874D01*
G01Y30630D01*
G02X1811819Y36504I5874J0D01*
G01X1828062D01*
G37*
G36*
G01X1829886Y1650538D02*
X1829890D01*
Y1650237D01*
X1829889Y1650231D01*
G03X1829820Y1649712I1931J-521D01*
G03X1829886Y1649203I2000J1D01*
G01Y1612316D01*
G03X1832779Y1605332I9877J0D01*
G01X1839978Y1598133D01*
G02X1841697Y1593983I-4151J-4151D01*
G01Y326095D01*
G03X1844590Y319111I9878J1D01*
G01X1853757Y309944D01*
G02X1855476Y305794I-4151J-4151D01*
G01Y54252D01*
G02X1849606Y48382I-5870J0D01*
G01X1829186D01*
Y48378D01*
X1827844D01*
Y48382D01*
X1803945D01*
G03X1794067Y38504I0J-9878D01*
G01Y3937D01*
G02X1792134Y2004I-1933J0D01*
G01X1529929D01*
G02X1527996Y3937I0J1933D01*
G01Y38504D01*
G03X1518118Y48382I-9878J0D01*
G01X1026772D01*
G02X1020902Y54252I0J5870D01*
G01Y131004D01*
G03X1011024Y140882I-9878J0D01*
G01X887008D01*
G03X877130Y131004I0J-9878D01*
G01Y54252D01*
G02X871260Y48382I-5870J0D01*
G01X774417D01*
G03X764539Y38504I0J-9878D01*
G01Y24724D01*
G02X762606Y22791I-1933J0D01*
G01X500402D01*
G02X498469Y24724I0J1933D01*
G01Y38504D01*
G03X488591Y48382I-9878J0D01*
G01X329535D01*
G03X319657Y38504I0J-9878D01*
G01Y3937D01*
G02X317724Y2004I-1933J0D01*
G01X55520D01*
G02X53587Y3937I0J1933D01*
G01Y38504D01*
G03X43709Y48382I-9878J0D01*
G01X7874D01*
G02X2004Y54252I0J5870D01*
G01Y305794D01*
G02X3723Y309944I5870J-1D01*
G01X6985Y313206D01*
G03X9878Y320190I-6984J6984D01*
G01Y1588078D01*
G02X11597Y1592228I5870J-1D01*
G01X24701Y1605332D01*
G03X27595Y1612316I-6983J6985D01*
G01Y1732244D01*
G02X33465Y1738114I5870J0D01*
G01X765732D01*
Y1736890D01*
G03X769705Y1732917I3973J0D01*
G01X1087854D01*
G03X1091827Y1736890I0J3973D01*
G01Y1738114D01*
X1824016D01*
G02X1829886Y1732244I0J-5870D01*
G01Y1650538D01*
G37*
G36*
G01X1867354Y305795D02*
G03X1862156Y318343I-17746J-1D01*
G01X1855296Y325203D01*
G02X1853575Y329357I4153J4154D01*
G01Y1593984D01*
G03X1848377Y1606532I-17746J-1D01*
G01X1843484Y1611425D01*
G02X1841764Y1615579I4156J4154D01*
G01Y1732244D01*
G02X1847638Y1738118I5874J0D01*
G01X1857480D01*
G03X1867354Y1747992I0J9874D01*
G01Y1815072D01*
G02X1873228Y1820946I5874J0D01*
G01X2093700D01*
G02X2099574Y1815072I0J-5874D01*
G01Y1791450D01*
G02X2093700Y1785576I-5874J0D01*
G01X2031574D01*
G03X2021700Y1775702I0J-9874D01*
G01Y1229954D01*
G03X2031574Y1220080I9874J0D01*
G01X2093700D01*
G02X2099574Y1214206I0J-5874D01*
G01Y-40945D01*
G02X2093700Y-46819I-5874J0D01*
G01X1873228D01*
G02X1867354Y-40945I0J5874D01*
G01Y305795D01*
G37*
%LPD*%
G75*
G36*
G01X381207Y1105426D02*
G02X384015I1404J0D01*
G02X382796Y1104034I-1404J0D01*
G01X382698Y1104021D01*
X382019Y1102846D01*
G02X382166Y1102221I-1257J-625D01*
G02X379358I-1404J0D01*
G02X380672Y1103622I1404J0D01*
G01X381352Y1104797D01*
X381314Y1104889D01*
G02X381207Y1105426I1297J538D01*
G37*
G36*
G01X1357349D02*
G02X1360157I1404J0D01*
G02X1358938Y1104034I-1404J0D01*
G01X1358840Y1104021D01*
X1358161Y1102846D01*
G02X1358308Y1102221I-1257J-625D01*
G02X1355500I-1404J0D01*
G02X1356814Y1103622I1404J0D01*
G01X1357494Y1104797D01*
X1357456Y1104889D01*
G02X1357349Y1105426I1297J538D01*
G37*
G36*
G01X349758Y1108630D02*
G02X352566I1404J0D01*
G01Y1108629D01*
G02X352460Y1108093I-1404J-1D01*
G01X352422Y1108002D01*
X353101Y1106827D01*
G02X354415Y1105426I-90J-1401D01*
G02X351607I-1404J0D01*
G02X351754Y1106051I1404J0D01*
G01X351075Y1107225D01*
X350977Y1107238D01*
G02X349758Y1108630I185J1392D01*
G37*
G36*
G01X364557Y1108628D02*
Y1108630D01*
G02X367365I1404J0D01*
G02X366146Y1107238I-1404J0D01*
G01X366048Y1107225D01*
X365369Y1106051D01*
G02X365516Y1105426I-1257J-625D01*
G02X362708I-1404J0D01*
G02X364022Y1106827I1404J0D01*
G01X364701Y1108003D01*
X364663Y1108094D01*
G02X364557Y1108628I1298J535D01*
G37*
G36*
G01X1325900Y1108630D02*
G02X1328708I1404J0D01*
G01Y1108629D01*
G02X1328602Y1108093I-1404J-1D01*
G01X1328564Y1108002D01*
X1329243Y1106827D01*
G02X1330557Y1105426I-90J-1401D01*
G02X1327749I-1404J0D01*
G02X1327896Y1106051I1404J0D01*
G01X1327217Y1107225D01*
X1327119Y1107238D01*
G02X1325900Y1108630I185J1392D01*
G37*
G36*
G01X1340699Y1108628D02*
Y1108630D01*
G02X1343507I1404J0D01*
G02X1342288Y1107238I-1404J0D01*
G01X1342190Y1107225D01*
X1341511Y1106051D01*
G02X1341658Y1105426I-1257J-625D01*
G02X1338850I-1404J0D01*
G02X1340164Y1106827I1404J0D01*
G01X1340843Y1108003D01*
X1340805Y1108094D01*
G02X1340699Y1108628I1298J535D01*
G37*
G36*
G01X390458Y1115039D02*
G02X393266I1404J0D01*
G02X393159Y1114502I-1404J1D01*
G01X393121Y1114410D01*
X393801Y1113235D01*
G02X395115Y1111834I-90J-1401D01*
G02X392307I-1404J0D01*
G02X392454Y1112459I1404J0D01*
G01X391775Y1113634D01*
X391677Y1113647D01*
G02X390458Y1115039I185J1392D01*
G37*
G36*
G01X412658D02*
G02X415466I1404J0D01*
G02X415359Y1114502I-1404J1D01*
G01X415321Y1114410D01*
X416001Y1113235D01*
G02X417315Y1111834I-90J-1401D01*
G02X414507I-1404J0D01*
G02X414654Y1112459I1404J0D01*
G01X413975Y1113634D01*
X413877Y1113647D01*
G02X412658Y1115039I185J1392D01*
G37*
G36*
G01X1366600D02*
G02X1369408I1404J0D01*
G02X1369301Y1114502I-1404J1D01*
G01X1369263Y1114410D01*
X1369943Y1113235D01*
G02X1371257Y1111834I-90J-1401D01*
G02X1368449I-1404J0D01*
G02X1368596Y1112459I1404J0D01*
G01X1367917Y1113634D01*
X1367819Y1113647D01*
G02X1366600Y1115039I185J1392D01*
G37*
G36*
G01X1388800D02*
G02X1391608I1404J0D01*
G02X1391501Y1114502I-1404J1D01*
G01X1391463Y1114410D01*
X1392143Y1113235D01*
G02X1393457Y1111834I-90J-1401D01*
G02X1390649I-1404J0D01*
G02X1390796Y1112459I1404J0D01*
G01X1390117Y1113634D01*
X1390019Y1113647D01*
G02X1388800Y1115039I185J1392D01*
G37*
G36*
G01X1758669Y52153D02*
G02X1760173Y50649I0J-1504D01*
G01Y50648D01*
G02X1760172Y50593I-1504J0D01*
G02X1758669Y49100I-1503J10D01*
G01X1755269D01*
G02X1753766Y50593I0J1503D01*
G02X1753765Y50648I1503J55D01*
G01Y50649D01*
G02X1755269Y52153I1504J0D01*
G02X1755620Y52112I2J-1504D01*
G01X1755643Y52106D01*
X1758295D01*
X1758318Y52112D01*
G02X1758669Y52153I349J-1463D01*
G37*
G36*
G01X1394374Y172851D02*
G02X1395334Y173198I960J-1154D01*
G01X1398734D01*
G02X1400236Y171696I0J-1502D01*
G02X1398743Y170194I-1502J0D01*
G02X1398182Y170076I-561J1276D01*
G02X1397656Y170179I0J1394D01*
G01X1397620Y170194D01*
X1395334D01*
G02X1394882Y170264I1J1502D01*
G02X1394184Y170076I-699J1206D01*
G01X1394182D01*
G02Y172864I0J1394D01*
G02X1394374Y172851I2J-1394D01*
G37*
G36*
G01X880168Y504762D02*
Y508162D01*
G02X881670Y509664I1502J0D01*
G02X882945Y508955I0J-1501D01*
G02X883184Y508142I-1265J-813D01*
G01Y508141D01*
G02X883173Y507963I-1504J4D01*
G01X883172Y507952D01*
Y504897D01*
X883173Y504888D01*
G02X883180Y504743I-1493J-145D01*
G01Y504742D01*
G02X881680Y503242I-1500J0D01*
G02X880398Y503963I0J1500D01*
G02X880168Y504762I1273J799D01*
G37*
G36*
G01X356723Y844971D02*
G02X359531I1404J0D01*
G02X358310Y843579I-1404J0D01*
G01X358208Y843565D01*
X357485Y842193D01*
X357532Y842101D01*
G02X357683Y841468I-1252J-633D01*
G01Y841467D01*
G02X354875I-1404J0D01*
G02X356096Y842859I1404J0D01*
G01X356198Y842873D01*
X356921Y844245D01*
X356874Y844337D01*
G02X356723Y844970I1252J633D01*
G01Y844971D01*
G37*
G36*
G01X364123D02*
G02X366931I1404J0D01*
G02X365710Y843579I-1404J0D01*
G01X365608Y843565D01*
X364885Y842193D01*
X364932Y842101D01*
G02X365083Y841468I-1252J-633D01*
G01Y841467D01*
G02X362275I-1404J0D01*
G02X363496Y842859I1404J0D01*
G01X363598Y842873D01*
X364321Y844245D01*
X364274Y844337D01*
G02X364123Y844970I1252J633D01*
G01Y844971D01*
G37*
G36*
G01X371523D02*
G02X374331I1404J0D01*
G02X373110Y843579I-1404J0D01*
G01X373008Y843565D01*
X372285Y842193D01*
X372332Y842101D01*
G02X372483Y841468I-1252J-633D01*
G01Y841467D01*
G02X369675I-1404J0D01*
G02X370896Y842859I1404J0D01*
G01X370998Y842873D01*
X371721Y844245D01*
X371674Y844337D01*
G02X371523Y844970I1252J633D01*
G01Y844971D01*
G37*
G36*
G01X378923D02*
G02X381731I1404J0D01*
G02X380510Y843579I-1404J0D01*
G01X380408Y843565D01*
X379685Y842193D01*
X379732Y842101D01*
G02X379883Y841468I-1252J-633D01*
G01Y841467D01*
G02X377075I-1404J0D01*
G02X378296Y842859I1404J0D01*
G01X378398Y842873D01*
X379121Y844245D01*
X379074Y844337D01*
G02X378923Y844970I1252J633D01*
G01Y844971D01*
G37*
G36*
G01X386323D02*
G02X389131I1404J0D01*
G02X387910Y843579I-1404J0D01*
G01X387808Y843565D01*
X387085Y842193D01*
X387132Y842101D01*
G02X387283Y841468I-1252J-633D01*
G01Y841467D01*
G02X384475I-1404J0D01*
G02X385696Y842859I1404J0D01*
G01X385798Y842873D01*
X386521Y844245D01*
X386474Y844337D01*
G02X386323Y844970I1252J633D01*
G01Y844971D01*
G37*
G36*
G01X393723D02*
G02X396531I1404J0D01*
G02X395310Y843579I-1404J0D01*
G01X395208Y843565D01*
X394485Y842193D01*
X394532Y842101D01*
G02X394683Y841468I-1252J-633D01*
G01Y841467D01*
G02X391875I-1404J0D01*
G02X393096Y842859I1404J0D01*
G01X393198Y842873D01*
X393921Y844245D01*
X393874Y844337D01*
G02X393723Y844970I1252J633D01*
G01Y844971D01*
G37*
G36*
G01X401123D02*
G02X403931I1404J0D01*
G02X402710Y843579I-1404J0D01*
G01X402608Y843565D01*
X401885Y842193D01*
X401932Y842101D01*
G02X402083Y841468I-1252J-633D01*
G01Y841467D01*
G02X399275I-1404J0D01*
G02X400496Y842859I1404J0D01*
G01X400598Y842873D01*
X401321Y844245D01*
X401274Y844337D01*
G02X401123Y844970I1252J633D01*
G01Y844971D01*
G37*
G36*
G01X408523D02*
G02X411331I1404J0D01*
G02X410110Y843579I-1404J0D01*
G01X410008Y843565D01*
X409285Y842193D01*
X409332Y842101D01*
G02X409483Y841468I-1252J-633D01*
G01Y841467D01*
G02X406675I-1404J0D01*
G02X407896Y842859I1404J0D01*
G01X407998Y842873D01*
X408721Y844245D01*
X408674Y844337D01*
G02X408523Y844970I1252J633D01*
G01Y844971D01*
G37*
G36*
G01X415923D02*
G02X418731I1404J0D01*
G02X417510Y843579I-1404J0D01*
G01X417408Y843565D01*
X416685Y842193D01*
X416732Y842101D01*
G02X416883Y841468I-1252J-633D01*
G01Y841467D01*
G02X414075I-1404J0D01*
G02X415296Y842859I1404J0D01*
G01X415398Y842873D01*
X416121Y844245D01*
X416074Y844337D01*
G02X415923Y844970I1252J633D01*
G01Y844971D01*
G37*
G36*
G01X423323D02*
G02X426131I1404J0D01*
G02X424910Y843579I-1404J0D01*
G01X424808Y843565D01*
X424085Y842193D01*
X424132Y842101D01*
G02X424283Y841468I-1252J-633D01*
G01Y841467D01*
G02X421475I-1404J0D01*
G02X422696Y842859I1404J0D01*
G01X422798Y842873D01*
X423521Y844245D01*
X423474Y844337D01*
G02X423323Y844970I1252J633D01*
G01Y844971D01*
G37*
G36*
G01X452923D02*
G02X455731I1404J0D01*
G02X454510Y843579I-1404J0D01*
G01X454408Y843565D01*
X453685Y842193D01*
X453732Y842101D01*
G02X453883Y841468I-1252J-633D01*
G01Y841467D01*
G02X451075I-1404J0D01*
G02X452296Y842859I1404J0D01*
G01X452398Y842873D01*
X453121Y844245D01*
X453074Y844337D01*
G02X452923Y844970I1252J633D01*
G01Y844971D01*
G37*
G36*
G01X460323D02*
G02X463131I1404J0D01*
G02X461910Y843579I-1404J0D01*
G01X461808Y843565D01*
X461085Y842193D01*
X461132Y842101D01*
G02X461283Y841468I-1252J-633D01*
G01Y841467D01*
G02X458475I-1404J0D01*
G02X459696Y842859I1404J0D01*
G01X459798Y842873D01*
X460521Y844245D01*
X460474Y844337D01*
G02X460323Y844970I1252J633D01*
G01Y844971D01*
G37*
G36*
G01X467723D02*
G02X470531I1404J0D01*
G02X469310Y843579I-1404J0D01*
G01X469208Y843565D01*
X468485Y842193D01*
X468532Y842101D01*
G02X468683Y841468I-1252J-633D01*
G01Y841467D01*
G02X465875I-1404J0D01*
G02X467096Y842859I1404J0D01*
G01X467198Y842873D01*
X467921Y844245D01*
X467874Y844337D01*
G02X467723Y844970I1252J633D01*
G01Y844971D01*
G37*
G36*
G01X475123D02*
G02X477931I1404J0D01*
G02X476710Y843579I-1404J0D01*
G01X476608Y843565D01*
X475885Y842193D01*
X475932Y842101D01*
G02X476083Y841468I-1252J-633D01*
G01Y841467D01*
G02X473275I-1404J0D01*
G02X474496Y842859I1404J0D01*
G01X474598Y842873D01*
X475321Y844245D01*
X475274Y844337D01*
G02X475123Y844970I1252J633D01*
G01Y844971D01*
G37*
G36*
G01X482523D02*
G02X485331I1404J0D01*
G02X484110Y843579I-1404J0D01*
G01X484008Y843565D01*
X483285Y842193D01*
X483332Y842101D01*
G02X483483Y841468I-1252J-633D01*
G01Y841467D01*
G02X480675I-1404J0D01*
G02X481896Y842859I1404J0D01*
G01X481998Y842873D01*
X482721Y844245D01*
X482674Y844337D01*
G02X482523Y844970I1252J633D01*
G01Y844971D01*
G37*
G36*
G01X489923D02*
G02X492731I1404J0D01*
G02X491468Y843574I-1404J0D01*
G01X491361Y843563D01*
X490665Y842223D01*
X490715Y842130D01*
G02X490882Y841467I-1237J-664D01*
G02X488074I-1404J0D01*
G02X489366Y842867I1405J0D01*
G01X489476Y842875D01*
X490157Y844188D01*
X490104Y844282D01*
G02X489923Y844971I1223J689D01*
G37*
G36*
G01X497323D02*
G02X500131I1404J0D01*
G02X498910Y843579I-1404J0D01*
G01X498808Y843565D01*
X498084Y842193D01*
X498131Y842101D01*
G02X498282Y841468I-1252J-633D01*
G01Y841467D01*
G02X495474I-1404J0D01*
G02X496695Y842859I1404J0D01*
G01X496798Y842873D01*
X497521Y844245D01*
X497474Y844337D01*
G02X497323Y844970I1252J633D01*
G01Y844971D01*
G37*
G36*
G01X504723D02*
G02X507531I1404J0D01*
G02X506310Y843579I-1404J0D01*
G01X506208Y843565D01*
X505485Y842193D01*
X505532Y842101D01*
G02X505683Y841468I-1252J-633D01*
G01Y841467D01*
G02X502875I-1404J0D01*
G02X504096Y842859I1404J0D01*
G01X504198Y842873D01*
X504921Y844245D01*
X504874Y844337D01*
G02X504723Y844970I1252J633D01*
G01Y844971D01*
G37*
G36*
G01X512123D02*
G02X514931I1404J0D01*
G02X513710Y843579I-1404J0D01*
G01X513608Y843565D01*
X512885Y842193D01*
X512932Y842101D01*
G02X513083Y841468I-1252J-633D01*
G01Y841467D01*
G02X510275I-1404J0D01*
G02X511496Y842859I1404J0D01*
G01X511598Y842873D01*
X512321Y844245D01*
X512274Y844337D01*
G02X512123Y844970I1252J633D01*
G01Y844971D01*
G37*
G36*
G01X519523D02*
G02X522331I1404J0D01*
G02X521110Y843579I-1404J0D01*
G01X521008Y843565D01*
X520285Y842193D01*
X520332Y842101D01*
G02X520483Y841468I-1252J-633D01*
G01Y841467D01*
G02X517675I-1404J0D01*
G02X518896Y842859I1404J0D01*
G01X518998Y842873D01*
X519721Y844245D01*
X519674Y844337D01*
G02X519523Y844970I1252J633D01*
G01Y844971D01*
G37*
G36*
G01X1332865D02*
G02X1335673I1404J0D01*
G02X1334452Y843579I-1404J0D01*
G01X1334350Y843565D01*
X1333627Y842193D01*
X1333674Y842101D01*
G02X1333825Y841468I-1252J-633D01*
G01Y841467D01*
G02X1331017I-1404J0D01*
G02X1332238Y842859I1404J0D01*
G01X1332340Y842873D01*
X1333063Y844245D01*
X1333016Y844337D01*
G02X1332865Y844970I1252J633D01*
G01Y844971D01*
G37*
G36*
G01X1340265D02*
G02X1343073I1404J0D01*
G02X1341852Y843579I-1404J0D01*
G01X1341750Y843565D01*
X1341027Y842193D01*
X1341074Y842101D01*
G02X1341225Y841468I-1252J-633D01*
G01Y841467D01*
G02X1338417I-1404J0D01*
G02X1339638Y842859I1404J0D01*
G01X1339740Y842873D01*
X1340463Y844245D01*
X1340416Y844337D01*
G02X1340265Y844970I1252J633D01*
G01Y844971D01*
G37*
G36*
G01X1347665D02*
G02X1350473I1404J0D01*
G02X1349252Y843579I-1404J0D01*
G01X1349150Y843565D01*
X1348427Y842193D01*
X1348474Y842101D01*
G02X1348625Y841468I-1252J-633D01*
G01Y841467D01*
G02X1345817I-1404J0D01*
G02X1347038Y842859I1404J0D01*
G01X1347140Y842873D01*
X1347863Y844245D01*
X1347816Y844337D01*
G02X1347665Y844970I1252J633D01*
G01Y844971D01*
G37*
G36*
G01X1355065D02*
G02X1357873I1404J0D01*
G02X1356652Y843579I-1404J0D01*
G01X1356550Y843565D01*
X1355827Y842193D01*
X1355874Y842101D01*
G02X1356025Y841468I-1252J-633D01*
G01Y841467D01*
G02X1353217I-1404J0D01*
G02X1354438Y842859I1404J0D01*
G01X1354540Y842873D01*
X1355263Y844245D01*
X1355216Y844337D01*
G02X1355065Y844970I1252J633D01*
G01Y844971D01*
G37*
G36*
G01X1362465D02*
G02X1365273I1404J0D01*
G02X1364052Y843579I-1404J0D01*
G01X1363950Y843565D01*
X1363227Y842193D01*
X1363274Y842101D01*
G02X1363425Y841468I-1252J-633D01*
G01Y841467D01*
G02X1360617I-1404J0D01*
G02X1361838Y842859I1404J0D01*
G01X1361940Y842873D01*
X1362663Y844245D01*
X1362616Y844337D01*
G02X1362465Y844970I1252J633D01*
G01Y844971D01*
G37*
G36*
G01X1369865D02*
G02X1372673I1404J0D01*
G02X1371452Y843579I-1404J0D01*
G01X1371350Y843565D01*
X1370627Y842193D01*
X1370674Y842101D01*
G02X1370825Y841468I-1252J-633D01*
G01Y841467D01*
G02X1368017I-1404J0D01*
G02X1369238Y842859I1404J0D01*
G01X1369340Y842873D01*
X1370063Y844245D01*
X1370016Y844337D01*
G02X1369865Y844970I1252J633D01*
G01Y844971D01*
G37*
G36*
G01X1377265D02*
G02X1380073I1404J0D01*
G02X1378852Y843579I-1404J0D01*
G01X1378750Y843565D01*
X1378027Y842193D01*
X1378074Y842101D01*
G02X1378225Y841468I-1252J-633D01*
G01Y841467D01*
G02X1375417I-1404J0D01*
G02X1376638Y842859I1404J0D01*
G01X1376740Y842873D01*
X1377463Y844245D01*
X1377416Y844337D01*
G02X1377265Y844970I1252J633D01*
G01Y844971D01*
G37*
G36*
G01X1384665D02*
G02X1387473I1404J0D01*
G02X1386252Y843579I-1404J0D01*
G01X1386150Y843565D01*
X1385427Y842193D01*
X1385474Y842101D01*
G02X1385625Y841468I-1252J-633D01*
G01Y841467D01*
G02X1382817I-1404J0D01*
G02X1384038Y842859I1404J0D01*
G01X1384140Y842873D01*
X1384863Y844245D01*
X1384816Y844337D01*
G02X1384665Y844970I1252J633D01*
G01Y844971D01*
G37*
G36*
G01X1392065D02*
G02X1394873I1404J0D01*
G02X1393652Y843579I-1404J0D01*
G01X1393550Y843565D01*
X1392827Y842193D01*
X1392874Y842101D01*
G02X1393025Y841468I-1252J-633D01*
G01Y841467D01*
G02X1390217I-1404J0D01*
G02X1391438Y842859I1404J0D01*
G01X1391540Y842873D01*
X1392263Y844245D01*
X1392216Y844337D01*
G02X1392065Y844970I1252J633D01*
G01Y844971D01*
G37*
G36*
G01X1399465D02*
G02X1402273I1404J0D01*
G02X1401052Y843579I-1404J0D01*
G01X1400950Y843565D01*
X1400227Y842193D01*
X1400274Y842101D01*
G02X1400425Y841468I-1252J-633D01*
G01Y841467D01*
G02X1397617I-1404J0D01*
G02X1398838Y842859I1404J0D01*
G01X1398940Y842873D01*
X1399663Y844245D01*
X1399616Y844337D01*
G02X1399465Y844970I1252J633D01*
G01Y844971D01*
G37*
G36*
G01X351174Y848176D02*
G02X353982I1404J0D01*
G02X353875Y847639I-1404J1D01*
G01X353837Y847547D01*
X354514Y846376D01*
X354612Y846363D01*
G02X355831Y844971I-185J-1392D01*
G02X353023I-1404J0D01*
G02X353130Y845508I1404J-1D01*
G01X353168Y845600D01*
X352491Y846771D01*
X352393Y846784D01*
G02X351174Y848176I185J1392D01*
G37*
G36*
G01X358574D02*
G02X361382I1404J0D01*
G02X361275Y847639I-1404J1D01*
G01X361237Y847547D01*
X361914Y846376D01*
X362012Y846363D01*
G02X363231Y844971I-185J-1392D01*
G02X360423I-1404J0D01*
G02X360530Y845508I1404J-1D01*
G01X360568Y845600D01*
X359891Y846771D01*
X359793Y846784D01*
G02X358574Y848176I185J1392D01*
G37*
G36*
G01X365974D02*
G02X368782I1404J0D01*
G02X368675Y847639I-1404J1D01*
G01X368637Y847547D01*
X369314Y846376D01*
X369412Y846363D01*
G02X370631Y844971I-185J-1392D01*
G02X367823I-1404J0D01*
G02X367930Y845508I1404J-1D01*
G01X367968Y845600D01*
X367291Y846771D01*
X367193Y846784D01*
G02X365974Y848176I185J1392D01*
G37*
G36*
G01X373374D02*
G02X376182I1404J0D01*
G02X376075Y847639I-1404J1D01*
G01X376037Y847547D01*
X376714Y846376D01*
X376812Y846363D01*
G02X378031Y844971I-185J-1392D01*
G02X375223I-1404J0D01*
G02X375330Y845508I1404J-1D01*
G01X375368Y845600D01*
X374691Y846771D01*
X374593Y846784D01*
G02X373374Y848176I185J1392D01*
G37*
G36*
G01X380774D02*
G02X383582I1404J0D01*
G02X383475Y847639I-1404J1D01*
G01X383437Y847547D01*
X384114Y846376D01*
X384212Y846363D01*
G02X385431Y844971I-185J-1392D01*
G02X382623I-1404J0D01*
G02X382730Y845508I1404J-1D01*
G01X382768Y845600D01*
X382091Y846771D01*
X381993Y846784D01*
G02X380774Y848176I185J1392D01*
G37*
G36*
G01X388174D02*
G02X390982I1404J0D01*
G02X390875Y847639I-1404J1D01*
G01X390837Y847547D01*
X391514Y846376D01*
X391612Y846363D01*
G02X392831Y844971I-185J-1392D01*
G02X390023I-1404J0D01*
G02X390130Y845508I1404J-1D01*
G01X390168Y845600D01*
X389491Y846771D01*
X389393Y846784D01*
G02X388174Y848176I185J1392D01*
G37*
G36*
G01X395574D02*
G02X398382I1404J0D01*
G02X398275Y847639I-1404J1D01*
G01X398237Y847547D01*
X398914Y846376D01*
X399012Y846363D01*
G02X400231Y844971I-185J-1392D01*
G02X397423I-1404J0D01*
G02X397530Y845508I1404J-1D01*
G01X397568Y845600D01*
X396891Y846771D01*
X396793Y846784D01*
G02X395574Y848176I185J1392D01*
G37*
G36*
G01X402974D02*
G02X405782I1404J0D01*
G02X405675Y847639I-1404J1D01*
G01X405637Y847547D01*
X406314Y846376D01*
X406412Y846363D01*
G02X407631Y844971I-185J-1392D01*
G02X404823I-1404J0D01*
G02X404930Y845508I1404J-1D01*
G01X404968Y845600D01*
X404291Y846771D01*
X404193Y846784D01*
G02X402974Y848176I185J1392D01*
G37*
G36*
G01X410374D02*
G02X413182I1404J0D01*
G02X413075Y847639I-1404J1D01*
G01X413037Y847547D01*
X413714Y846376D01*
X413812Y846363D01*
G02X415031Y844971I-185J-1392D01*
G02X412223I-1404J0D01*
G02X412330Y845508I1404J-1D01*
G01X412368Y845600D01*
X411691Y846771D01*
X411593Y846784D01*
G02X410374Y848176I185J1392D01*
G37*
G36*
G01X417774D02*
G02X420582I1404J0D01*
G02X420475Y847639I-1404J1D01*
G01X420437Y847547D01*
X421114Y846376D01*
X421212Y846363D01*
G02X422431Y844971I-185J-1392D01*
G02X419623I-1404J0D01*
G02X419730Y845508I1404J-1D01*
G01X419768Y845600D01*
X419091Y846771D01*
X418993Y846784D01*
G02X417774Y848176I185J1392D01*
G37*
G36*
G01X425174D02*
G02X427982I1404J0D01*
G02X427875Y847639I-1404J1D01*
G01X427837Y847547D01*
X428514Y846376D01*
X428612Y846363D01*
G02X429831Y844971I-185J-1392D01*
G02X427023I-1404J0D01*
G02X427130Y845508I1404J-1D01*
G01X427168Y845600D01*
X426491Y846771D01*
X426393Y846784D01*
G02X425174Y848176I185J1392D01*
G37*
G36*
G01X436274D02*
G02X439082I1404J0D01*
G02X437861Y846784I-1404J0D01*
G01X437759Y846770D01*
X437035Y845397D01*
X437082Y845305D01*
G02X437233Y844672I-1252J-633D01*
G01Y844671D01*
G02X434425I-1404J0D01*
G02X435646Y846063I1404J0D01*
G01X435748Y846077D01*
X436472Y847450D01*
X436425Y847542D01*
G02X436274Y848175I1252J633D01*
G01Y848176D01*
G37*
G36*
G01X447374D02*
G02X450182I1404J0D01*
G02X450075Y847639I-1404J1D01*
G01X450037Y847547D01*
X450715Y846376D01*
X450812Y846363D01*
G02X452032Y844971I-184J-1392D01*
G02X449224I-1404J0D01*
G02X449331Y845508I1404J-1D01*
G01X449369Y845600D01*
X448691Y846771D01*
X448594Y846784D01*
G02X447374Y848176I184J1392D01*
G37*
G36*
G01X454774D02*
G02X457582I1404J0D01*
G02X457475Y847639I-1404J1D01*
G01X457437Y847547D01*
X458114Y846376D01*
X458212Y846363D01*
G02X459431Y844971I-185J-1392D01*
G02X456623I-1404J0D01*
G02X456730Y845508I1404J-1D01*
G01X456768Y845600D01*
X456091Y846771D01*
X455993Y846784D01*
G02X454774Y848176I185J1392D01*
G37*
G36*
G01X462174D02*
G02X464982I1404J0D01*
G02X464875Y847639I-1404J1D01*
G01X464837Y847547D01*
X465514Y846376D01*
X465612Y846363D01*
G02X466831Y844971I-185J-1392D01*
G02X464023I-1404J0D01*
G02X464130Y845508I1404J-1D01*
G01X464168Y845600D01*
X463491Y846771D01*
X463393Y846784D01*
G02X462174Y848176I185J1392D01*
G37*
G36*
G01X469574D02*
G02X472382I1404J0D01*
G02X472275Y847639I-1404J1D01*
G01X472237Y847547D01*
X472914Y846376D01*
X473012Y846363D01*
G02X474231Y844971I-185J-1392D01*
G02X471423I-1404J0D01*
G02X471530Y845508I1404J-1D01*
G01X471568Y845600D01*
X470891Y846771D01*
X470793Y846784D01*
G02X469574Y848176I185J1392D01*
G37*
G36*
G01X476974D02*
G02X479782I1404J0D01*
G02X479675Y847639I-1404J1D01*
G01X479637Y847547D01*
X480314Y846376D01*
X480412Y846363D01*
G02X481631Y844971I-185J-1392D01*
G02X478823I-1404J0D01*
G02X478930Y845508I1404J-1D01*
G01X478968Y845600D01*
X478291Y846771D01*
X478193Y846784D01*
G02X476974Y848176I185J1392D01*
G37*
G36*
G01X484374D02*
G02X487182I1404J0D01*
G02X487075Y847639I-1404J1D01*
G01X487037Y847547D01*
X487714Y846376D01*
X487812Y846363D01*
G02X489031Y844971I-185J-1392D01*
G02X486223I-1404J0D01*
G02X486330Y845508I1404J-1D01*
G01X486368Y845600D01*
X485691Y846771D01*
X485593Y846784D01*
G02X484374Y848176I185J1392D01*
G37*
G36*
G01X491774D02*
G02X494582I1404J0D01*
G02X494475Y847639I-1404J1D01*
G01X494437Y847547D01*
X495114Y846376D01*
X495212Y846363D01*
G02X496431Y844971I-185J-1392D01*
G02X493623I-1404J0D01*
G02X493730Y845508I1404J-1D01*
G01X493768Y845600D01*
X493091Y846771D01*
X492993Y846784D01*
G02X491774Y848176I185J1392D01*
G37*
G36*
G01X499174D02*
G02X501982I1404J0D01*
G02X501875Y847639I-1404J1D01*
G01X501837Y847547D01*
X502514Y846376D01*
X502612Y846363D01*
G02X503831Y844971I-185J-1392D01*
G02X501023I-1404J0D01*
G02X501130Y845508I1404J-1D01*
G01X501168Y845600D01*
X500491Y846771D01*
X500393Y846784D01*
G02X499174Y848176I185J1392D01*
G37*
G36*
G01X506574D02*
G02X509382I1404J0D01*
G02X509275Y847639I-1404J1D01*
G01X509237Y847547D01*
X509914Y846376D01*
X510012Y846363D01*
G02X511231Y844971I-185J-1392D01*
G02X508423I-1404J0D01*
G02X508530Y845508I1404J-1D01*
G01X508568Y845600D01*
X507891Y846771D01*
X507793Y846784D01*
G02X506574Y848176I185J1392D01*
G37*
G36*
G01X513974D02*
G02X516782I1404J0D01*
G02X516675Y847639I-1404J1D01*
G01X516637Y847547D01*
X517314Y846376D01*
X517412Y846363D01*
G02X518631Y844971I-185J-1392D01*
G02X515823I-1404J0D01*
G02X515930Y845508I1404J-1D01*
G01X515968Y845600D01*
X515291Y846771D01*
X515193Y846784D01*
G02X513974Y848176I185J1392D01*
G37*
G36*
G01X521374D02*
G02X524182I1404J0D01*
G02X524075Y847639I-1404J1D01*
G01X524037Y847547D01*
X524714Y846376D01*
X524812Y846363D01*
G02X526031Y844971I-185J-1392D01*
G02X523223I-1404J0D01*
G02X523330Y845508I1404J-1D01*
G01X523368Y845600D01*
X522691Y846771D01*
X522593Y846784D01*
G02X521374Y848176I185J1392D01*
G37*
G36*
G01X1327316D02*
G02X1330124I1404J0D01*
G02X1330017Y847639I-1404J1D01*
G01X1329979Y847547D01*
X1330656Y846376D01*
X1330754Y846363D01*
G02X1331973Y844971I-185J-1392D01*
G02X1329165I-1404J0D01*
G02X1329272Y845508I1404J-1D01*
G01X1329310Y845600D01*
X1328633Y846771D01*
X1328535Y846784D01*
G02X1327316Y848176I185J1392D01*
G37*
G36*
G01X1334716D02*
G02X1337524I1404J0D01*
G02X1337417Y847639I-1404J1D01*
G01X1337379Y847547D01*
X1338056Y846376D01*
X1338154Y846363D01*
G02X1339373Y844971I-185J-1392D01*
G02X1336565I-1404J0D01*
G02X1336672Y845508I1404J-1D01*
G01X1336710Y845600D01*
X1336033Y846771D01*
X1335935Y846784D01*
G02X1334716Y848176I185J1392D01*
G37*
G36*
G01X1342116D02*
G02X1344924I1404J0D01*
G02X1344817Y847639I-1404J1D01*
G01X1344779Y847547D01*
X1345456Y846376D01*
X1345554Y846363D01*
G02X1346773Y844971I-185J-1392D01*
G02X1343965I-1404J0D01*
G02X1344072Y845508I1404J-1D01*
G01X1344110Y845600D01*
X1343433Y846771D01*
X1343335Y846784D01*
G02X1342116Y848176I185J1392D01*
G37*
G36*
G01X1349516D02*
G02X1352324I1404J0D01*
G02X1352217Y847639I-1404J1D01*
G01X1352179Y847547D01*
X1352856Y846376D01*
X1352954Y846363D01*
G02X1354173Y844971I-185J-1392D01*
G02X1351365I-1404J0D01*
G02X1351472Y845508I1404J-1D01*
G01X1351510Y845600D01*
X1350833Y846771D01*
X1350735Y846784D01*
G02X1349516Y848176I185J1392D01*
G37*
G36*
G01X1356916D02*
G02X1359724I1404J0D01*
G02X1359617Y847639I-1404J1D01*
G01X1359579Y847547D01*
X1360256Y846376D01*
X1360354Y846363D01*
G02X1361573Y844971I-185J-1392D01*
G02X1358765I-1404J0D01*
G02X1358872Y845508I1404J-1D01*
G01X1358910Y845600D01*
X1358233Y846771D01*
X1358135Y846784D01*
G02X1356916Y848176I185J1392D01*
G37*
G36*
G01X1364316D02*
G02X1367124I1404J0D01*
G02X1367017Y847639I-1404J1D01*
G01X1366979Y847547D01*
X1367656Y846376D01*
X1367754Y846363D01*
G02X1368973Y844971I-185J-1392D01*
G02X1366165I-1404J0D01*
G02X1366272Y845508I1404J-1D01*
G01X1366310Y845600D01*
X1365633Y846771D01*
X1365535Y846784D01*
G02X1364316Y848176I185J1392D01*
G37*
G36*
G01X1371716D02*
G02X1374524I1404J0D01*
G02X1374417Y847639I-1404J1D01*
G01X1374379Y847547D01*
X1375056Y846376D01*
X1375154Y846363D01*
G02X1376373Y844971I-185J-1392D01*
G02X1373565I-1404J0D01*
G02X1373672Y845508I1404J-1D01*
G01X1373710Y845600D01*
X1373033Y846771D01*
X1372935Y846784D01*
G02X1371716Y848176I185J1392D01*
G37*
G36*
G01X1379116D02*
G02X1381924I1404J0D01*
G02X1381817Y847639I-1404J1D01*
G01X1381779Y847547D01*
X1382456Y846376D01*
X1382554Y846363D01*
G02X1383773Y844971I-185J-1392D01*
G02X1380965I-1404J0D01*
G02X1381072Y845508I1404J-1D01*
G01X1381110Y845600D01*
X1380433Y846771D01*
X1380335Y846784D01*
G02X1379116Y848176I185J1392D01*
G37*
G36*
G01X1386516D02*
G02X1389324I1404J0D01*
G02X1389217Y847639I-1404J1D01*
G01X1389179Y847547D01*
X1389856Y846376D01*
X1389954Y846363D01*
G02X1391173Y844971I-185J-1392D01*
G02X1388365I-1404J0D01*
G02X1388472Y845508I1404J-1D01*
G01X1388510Y845600D01*
X1387833Y846771D01*
X1387735Y846784D01*
G02X1386516Y848176I185J1392D01*
G37*
G36*
G01X1393916D02*
G02X1396724I1404J0D01*
G02X1396617Y847639I-1404J1D01*
G01X1396579Y847547D01*
X1397256Y846376D01*
X1397354Y846363D01*
G02X1398573Y844971I-185J-1392D01*
G02X1395765I-1404J0D01*
G02X1395872Y845508I1404J-1D01*
G01X1395910Y845600D01*
X1395233Y846771D01*
X1395135Y846784D01*
G02X1393916Y848176I185J1392D01*
G37*
G36*
G01X1401316D02*
G02X1404124I1404J0D01*
G02X1404017Y847639I-1404J1D01*
G01X1403979Y847547D01*
X1404656Y846376D01*
X1404754Y846363D01*
G02X1405973Y844971I-185J-1392D01*
G02X1403165I-1404J0D01*
G02X1403272Y845508I1404J-1D01*
G01X1403310Y845600D01*
X1402633Y846771D01*
X1402535Y846784D01*
G02X1401316Y848176I185J1392D01*
G37*
G36*
G01X1412416D02*
G02X1415224I1404J0D01*
G02X1414005Y846784I-1404J0D01*
G01X1413907Y846771D01*
X1413229Y845598D01*
X1413267Y845507D01*
G02X1413373Y844973I-1298J-535D01*
G01Y844971D01*
G02X1410565I-1404J0D01*
G02X1411785Y846363I1404J0D01*
G01X1411883Y846376D01*
X1412560Y847549D01*
X1412522Y847640D01*
G02X1412416Y848174I1298J535D01*
G01Y848176D01*
G37*
G36*
G01X349323Y851380D02*
G02X352131I1404J0D01*
G02X350912Y849988I-1404J0D01*
G01X350814Y849975D01*
X350137Y848805D01*
X350175Y848713D01*
G02X350282Y848176I-1297J-538D01*
G02X347474I-1404J0D01*
G02X348693Y849568I1404J0D01*
G01X348791Y849581D01*
X349468Y850751D01*
X349430Y850843D01*
G02X349323Y851380I1297J538D01*
G37*
G36*
G01X1325465D02*
G02X1328273I1404J0D01*
G02X1327054Y849988I-1404J0D01*
G01X1326956Y849975D01*
X1326279Y848805D01*
X1326317Y848713D01*
G02X1326424Y848176I-1297J-538D01*
G02X1323616I-1404J0D01*
G02X1324835Y849568I1404J0D01*
G01X1324933Y849581D01*
X1325610Y850751D01*
X1325572Y850843D01*
G02X1325465Y851380I1297J538D01*
G37*
G36*
G01X353025Y857789D02*
G02X355833I1404J0D01*
G02X355726Y857252I-1404J1D01*
G01X355688Y857160D01*
X356365Y855989D01*
X356463Y855976D01*
G02X357682Y854584I-185J-1392D01*
G02X354874I-1404J0D01*
G02X354981Y855121I1404J-1D01*
G01X355019Y855213D01*
X354342Y856384D01*
X354244Y856397D01*
G02X353025Y857789I185J1392D01*
G37*
G36*
G01X360425D02*
G02X363233I1404J0D01*
G02X363126Y857252I-1404J1D01*
G01X363088Y857160D01*
X363765Y855989D01*
X363863Y855976D01*
G02X365082Y854584I-185J-1392D01*
G02X362274I-1404J0D01*
G02X362381Y855121I1404J-1D01*
G01X362419Y855213D01*
X361742Y856384D01*
X361644Y856397D01*
G02X360425Y857789I185J1392D01*
G37*
G36*
G01X367825D02*
G02X370633I1404J0D01*
G02X370526Y857252I-1404J1D01*
G01X370488Y857160D01*
X371165Y855989D01*
X371263Y855976D01*
G02X372482Y854584I-185J-1392D01*
G02X369674I-1404J0D01*
G02X369781Y855121I1404J-1D01*
G01X369819Y855213D01*
X369142Y856384D01*
X369044Y856397D01*
G02X367825Y857789I185J1392D01*
G37*
G36*
G01X375225D02*
G02X378033I1404J0D01*
G02X377926Y857252I-1404J1D01*
G01X377888Y857160D01*
X378565Y855989D01*
X378663Y855976D01*
G02X379882Y854584I-185J-1392D01*
G02X377074I-1404J0D01*
G02X377181Y855121I1404J-1D01*
G01X377219Y855213D01*
X376542Y856384D01*
X376444Y856397D01*
G02X375225Y857789I185J1392D01*
G37*
G36*
G01X382625D02*
G02X385433I1404J0D01*
G02X385326Y857252I-1404J1D01*
G01X385288Y857160D01*
X385965Y855989D01*
X386063Y855976D01*
G02X387282Y854584I-185J-1392D01*
G02X384474I-1404J0D01*
G02X384581Y855121I1404J-1D01*
G01X384619Y855213D01*
X383942Y856384D01*
X383844Y856397D01*
G02X382625Y857789I185J1392D01*
G37*
G36*
G01X390025D02*
G02X392833I1404J0D01*
G02X392726Y857252I-1404J1D01*
G01X392688Y857160D01*
X393365Y855989D01*
X393463Y855976D01*
G02X394682Y854584I-185J-1392D01*
G02X391874I-1404J0D01*
G02X391981Y855121I1404J-1D01*
G01X392019Y855213D01*
X391342Y856384D01*
X391244Y856397D01*
G02X390025Y857789I185J1392D01*
G37*
G36*
G01X397425D02*
G02X400233I1404J0D01*
G02X400126Y857252I-1404J1D01*
G01X400088Y857160D01*
X400765Y855989D01*
X400863Y855976D01*
G02X402082Y854584I-185J-1392D01*
G02X399274I-1404J0D01*
G02X399381Y855121I1404J-1D01*
G01X399419Y855213D01*
X398742Y856384D01*
X398644Y856397D01*
G02X397425Y857789I185J1392D01*
G37*
G36*
G01X404825D02*
G02X407633I1404J0D01*
G02X407526Y857252I-1404J1D01*
G01X407488Y857160D01*
X408165Y855989D01*
X408263Y855976D01*
G02X409482Y854584I-185J-1392D01*
G02X406674I-1404J0D01*
G02X406781Y855121I1404J-1D01*
G01X406819Y855213D01*
X406142Y856384D01*
X406044Y856397D01*
G02X404825Y857789I185J1392D01*
G37*
G36*
G01X412225D02*
G02X415033I1404J0D01*
G02X414926Y857252I-1404J1D01*
G01X414888Y857160D01*
X415565Y855989D01*
X415663Y855976D01*
G02X416882Y854584I-185J-1392D01*
G02X414074I-1404J0D01*
G02X414181Y855121I1404J-1D01*
G01X414219Y855213D01*
X413542Y856384D01*
X413444Y856397D01*
G02X412225Y857789I185J1392D01*
G37*
G36*
G01X419625D02*
G02X422433I1404J0D01*
G02X422326Y857252I-1404J1D01*
G01X422288Y857160D01*
X422965Y855989D01*
X423063Y855976D01*
G02X424282Y854584I-185J-1392D01*
G02X421474I-1404J0D01*
G02X421581Y855121I1404J-1D01*
G01X421619Y855213D01*
X420942Y856384D01*
X420844Y856397D01*
G02X419625Y857789I185J1392D01*
G37*
G36*
G01X427025D02*
G02X429833I1404J0D01*
G02X429726Y857252I-1404J1D01*
G01X429688Y857160D01*
X430365Y855989D01*
X430463Y855976D01*
G02X431682Y854584I-185J-1392D01*
G02X428874I-1404J0D01*
G02X428981Y855121I1404J-1D01*
G01X429019Y855213D01*
X428342Y856384D01*
X428244Y856397D01*
G02X427025Y857789I185J1392D01*
G37*
G36*
G01X434425D02*
G02X437233I1404J0D01*
G02X437126Y857252I-1404J1D01*
G01X437088Y857160D01*
X437765Y855989D01*
X437863Y855976D01*
G02X439083Y854584I-184J-1392D01*
G02X436275I-1404J0D01*
G01Y854586D01*
G02X436381Y855120I1404J-1D01*
G01X436419Y855211D01*
X435742Y856384D01*
X435644Y856397D01*
G02X434425Y857789I185J1392D01*
G37*
G36*
G01X445525D02*
G02X448333I1404J0D01*
G02X447114Y856397I-1404J0D01*
G01X447016Y856384D01*
X446338Y855211D01*
X446376Y855120D01*
G02X446482Y854586I-1298J-535D01*
G01Y854584D01*
G02X443674I-1404J0D01*
G02X444896Y855976I1404J0D01*
G01X444994Y855989D01*
X445670Y857160D01*
X445632Y857252D01*
G02X445525Y857789I1297J538D01*
G37*
G36*
G01X452925D02*
G02X455733I1404J0D01*
G02X454514Y856397I-1404J0D01*
G01X454416Y856384D01*
X453738Y855211D01*
X453776Y855120D01*
G02X453882Y854586I-1298J-535D01*
G01Y854584D01*
G02X451074I-1404J0D01*
G02X452296Y855976I1404J0D01*
G01X452394Y855989D01*
X453070Y857160D01*
X453032Y857252D01*
G02X452925Y857789I1297J538D01*
G37*
G36*
G01X460325D02*
G02X463133I1404J0D01*
G02X461914Y856397I-1404J0D01*
G01X461816Y856384D01*
X461138Y855211D01*
X461176Y855120D01*
G02X461282Y854586I-1298J-535D01*
G01Y854584D01*
G02X458474I-1404J0D01*
G02X459696Y855976I1404J0D01*
G01X459794Y855989D01*
X460470Y857160D01*
X460432Y857252D01*
G02X460325Y857789I1297J538D01*
G37*
G36*
G01X467725D02*
G02X470533I1404J0D01*
G02X469314Y856397I-1404J0D01*
G01X469216Y856384D01*
X468538Y855211D01*
X468576Y855120D01*
G02X468682Y854586I-1298J-535D01*
G01Y854584D01*
G02X465874I-1404J0D01*
G02X467096Y855976I1404J0D01*
G01X467194Y855989D01*
X467870Y857160D01*
X467832Y857252D01*
G02X467725Y857789I1297J538D01*
G37*
G36*
G01X475125D02*
G02X477933I1404J0D01*
G02X476714Y856397I-1404J0D01*
G01X476616Y856384D01*
X475938Y855211D01*
X475976Y855120D01*
G02X476082Y854586I-1298J-535D01*
G01Y854584D01*
G02X473274I-1404J0D01*
G02X474496Y855976I1404J0D01*
G01X474594Y855989D01*
X475270Y857160D01*
X475232Y857252D01*
G02X475125Y857789I1297J538D01*
G37*
G36*
G01X482525D02*
G02X485333I1404J0D01*
G02X484114Y856397I-1404J0D01*
G01X484016Y856384D01*
X483338Y855211D01*
X483376Y855120D01*
G02X483482Y854586I-1298J-535D01*
G01Y854584D01*
G02X480674I-1404J0D01*
G02X481896Y855976I1404J0D01*
G01X481994Y855989D01*
X482670Y857160D01*
X482632Y857252D01*
G02X482525Y857789I1297J538D01*
G37*
G36*
G01X489925D02*
G02X492733I1404J0D01*
G02X491514Y856397I-1404J0D01*
G01X491416Y856384D01*
X490738Y855211D01*
X490776Y855120D01*
G02X490882Y854586I-1298J-535D01*
G01Y854584D01*
G02X488074I-1404J0D01*
G02X489296Y855976I1404J0D01*
G01X489394Y855989D01*
X490070Y857160D01*
X490032Y857252D01*
G02X489925Y857789I1297J538D01*
G37*
G36*
G01X497325D02*
G02X500133I1404J0D01*
G02X498914Y856397I-1404J0D01*
G01X498816Y856384D01*
X498138Y855211D01*
X498176Y855120D01*
G02X498282Y854586I-1298J-535D01*
G01Y854584D01*
G02X495474I-1404J0D01*
G02X496696Y855976I1404J0D01*
G01X496794Y855989D01*
X497470Y857160D01*
X497432Y857252D01*
G02X497325Y857789I1297J538D01*
G37*
G36*
G01X504725D02*
G02X507533I1404J0D01*
G02X506314Y856397I-1404J0D01*
G01X506216Y856384D01*
X505538Y855211D01*
X505576Y855120D01*
G02X505682Y854586I-1298J-535D01*
G01Y854584D01*
G02X502874I-1404J0D01*
G02X504096Y855976I1404J0D01*
G01X504194Y855989D01*
X504870Y857160D01*
X504832Y857252D01*
G02X504725Y857789I1297J538D01*
G37*
G36*
G01X512125D02*
G02X514933I1404J0D01*
G02X513714Y856397I-1404J0D01*
G01X513616Y856384D01*
X512938Y855211D01*
X512976Y855120D01*
G02X513082Y854586I-1298J-535D01*
G01Y854584D01*
G02X510274I-1404J0D01*
G02X511496Y855976I1404J0D01*
G01X511594Y855989D01*
X512270Y857160D01*
X512232Y857252D01*
G02X512125Y857789I1297J538D01*
G37*
G36*
G01X519525D02*
G02X522333I1404J0D01*
G02X521114Y856397I-1404J0D01*
G01X521016Y856384D01*
X520338Y855211D01*
X520376Y855120D01*
G02X520482Y854586I-1298J-535D01*
G01Y854584D01*
G02X517674I-1404J0D01*
G02X518896Y855976I1404J0D01*
G01X518994Y855989D01*
X519670Y857160D01*
X519632Y857252D01*
G02X519525Y857789I1297J538D01*
G37*
G36*
G01X526925D02*
G02X529733I1404J0D01*
G02X528514Y856397I-1404J0D01*
G01X528416Y856384D01*
X527738Y855211D01*
X527776Y855120D01*
G02X527882Y854586I-1298J-535D01*
G01Y854584D01*
G02X525074I-1404J0D01*
G02X526296Y855976I1404J0D01*
G01X526394Y855989D01*
X527070Y857160D01*
X527032Y857252D01*
G02X526925Y857789I1297J538D01*
G37*
G36*
G01X1329167D02*
G02X1331975I1404J0D01*
G02X1331868Y857252I-1404J1D01*
G01X1331830Y857160D01*
X1332507Y855989D01*
X1332605Y855976D01*
G02X1333824Y854584I-185J-1392D01*
G02X1331016I-1404J0D01*
G02X1331123Y855121I1404J-1D01*
G01X1331161Y855213D01*
X1330484Y856384D01*
X1330386Y856397D01*
G02X1329167Y857789I185J1392D01*
G37*
G36*
G01X1336567D02*
G02X1339375I1404J0D01*
G02X1339268Y857252I-1404J1D01*
G01X1339230Y857160D01*
X1339907Y855989D01*
X1340005Y855976D01*
G02X1341224Y854584I-185J-1392D01*
G02X1338416I-1404J0D01*
G02X1338523Y855121I1404J-1D01*
G01X1338561Y855213D01*
X1337884Y856384D01*
X1337786Y856397D01*
G02X1336567Y857789I185J1392D01*
G37*
G36*
G01X1343967D02*
G02X1346775I1404J0D01*
G02X1346668Y857252I-1404J1D01*
G01X1346630Y857160D01*
X1347307Y855989D01*
X1347405Y855976D01*
G02X1348624Y854584I-185J-1392D01*
G02X1345816I-1404J0D01*
G02X1345923Y855121I1404J-1D01*
G01X1345961Y855213D01*
X1345284Y856384D01*
X1345186Y856397D01*
G02X1343967Y857789I185J1392D01*
G37*
G36*
G01X1351367D02*
G02X1354175I1404J0D01*
G02X1354068Y857252I-1404J1D01*
G01X1354030Y857160D01*
X1354707Y855989D01*
X1354805Y855976D01*
G02X1356024Y854584I-185J-1392D01*
G02X1353216I-1404J0D01*
G02X1353323Y855121I1404J-1D01*
G01X1353361Y855213D01*
X1352684Y856384D01*
X1352586Y856397D01*
G02X1351367Y857789I185J1392D01*
G37*
G36*
G01X1358767D02*
G02X1361575I1404J0D01*
G02X1361468Y857252I-1404J1D01*
G01X1361430Y857160D01*
X1362107Y855989D01*
X1362205Y855976D01*
G02X1363424Y854584I-185J-1392D01*
G02X1360616I-1404J0D01*
G02X1360723Y855121I1404J-1D01*
G01X1360761Y855213D01*
X1360084Y856384D01*
X1359986Y856397D01*
G02X1358767Y857789I185J1392D01*
G37*
G36*
G01X1366167D02*
G02X1368975I1404J0D01*
G02X1368868Y857252I-1404J1D01*
G01X1368830Y857160D01*
X1369507Y855989D01*
X1369605Y855976D01*
G02X1370824Y854584I-185J-1392D01*
G02X1368016I-1404J0D01*
G02X1368123Y855121I1404J-1D01*
G01X1368161Y855213D01*
X1367484Y856384D01*
X1367386Y856397D01*
G02X1366167Y857789I185J1392D01*
G37*
G36*
G01X1373567D02*
G02X1376375I1404J0D01*
G02X1376268Y857252I-1404J1D01*
G01X1376230Y857160D01*
X1376907Y855989D01*
X1377005Y855976D01*
G02X1378224Y854584I-185J-1392D01*
G02X1375416I-1404J0D01*
G02X1375523Y855121I1404J-1D01*
G01X1375561Y855213D01*
X1374884Y856384D01*
X1374786Y856397D01*
G02X1373567Y857789I185J1392D01*
G37*
G36*
G01X1380967D02*
G02X1383775I1404J0D01*
G02X1383668Y857252I-1404J1D01*
G01X1383630Y857160D01*
X1384307Y855989D01*
X1384405Y855976D01*
G02X1385624Y854584I-185J-1392D01*
G02X1382816I-1404J0D01*
G02X1382923Y855121I1404J-1D01*
G01X1382961Y855213D01*
X1382284Y856384D01*
X1382186Y856397D01*
G02X1380967Y857789I185J1392D01*
G37*
G36*
G01X1388367D02*
G02X1391175I1404J0D01*
G02X1391068Y857252I-1404J1D01*
G01X1391030Y857160D01*
X1391707Y855989D01*
X1391805Y855976D01*
G02X1393024Y854584I-185J-1392D01*
G02X1390216I-1404J0D01*
G02X1390323Y855121I1404J-1D01*
G01X1390361Y855213D01*
X1389684Y856384D01*
X1389586Y856397D01*
G02X1388367Y857789I185J1392D01*
G37*
G36*
G01X1395767D02*
G02X1398575I1404J0D01*
G02X1398468Y857252I-1404J1D01*
G01X1398430Y857160D01*
X1399107Y855989D01*
X1399205Y855976D01*
G02X1400424Y854584I-185J-1392D01*
G02X1397616I-1404J0D01*
G02X1397723Y855121I1404J-1D01*
G01X1397761Y855213D01*
X1397084Y856384D01*
X1396986Y856397D01*
G02X1395767Y857789I185J1392D01*
G37*
G36*
G01X1403167D02*
G02X1405975I1404J0D01*
G02X1405868Y857252I-1404J1D01*
G01X1405830Y857160D01*
X1406507Y855989D01*
X1406605Y855976D01*
G02X1407824Y854584I-185J-1392D01*
G02X1405016I-1404J0D01*
G02X1405123Y855121I1404J-1D01*
G01X1405161Y855213D01*
X1404484Y856384D01*
X1404386Y856397D01*
G02X1403167Y857789I185J1392D01*
G37*
G36*
G01X1410567D02*
G02X1413375I1404J0D01*
G02X1413268Y857252I-1404J1D01*
G01X1413230Y857160D01*
X1413907Y855989D01*
X1414005Y855976D01*
G02X1415225Y854584I-184J-1392D01*
G02X1412417I-1404J0D01*
G01Y854586D01*
G02X1412523Y855120I1404J-1D01*
G01X1412561Y855211D01*
X1411884Y856384D01*
X1411786Y856397D01*
G02X1410567Y857789I185J1392D01*
G37*
G36*
G01X1421667D02*
G02X1424475I1404J0D01*
G02X1423256Y856397I-1404J0D01*
G01X1423158Y856384D01*
X1422480Y855211D01*
X1422518Y855120D01*
G02X1422624Y854586I-1298J-535D01*
G01Y854584D01*
G02X1419816I-1404J0D01*
G02X1421038Y855976I1404J0D01*
G01X1421136Y855989D01*
X1421812Y857160D01*
X1421774Y857252D01*
G02X1421667Y857789I1297J538D01*
G37*
G36*
G01X1429067D02*
G02X1431875I1404J0D01*
G02X1430656Y856397I-1404J0D01*
G01X1430558Y856384D01*
X1429880Y855211D01*
X1429918Y855120D01*
G02X1430024Y854586I-1298J-535D01*
G01Y854584D01*
G02X1427216I-1404J0D01*
G02X1428438Y855976I1404J0D01*
G01X1428536Y855989D01*
X1429212Y857160D01*
X1429174Y857252D01*
G02X1429067Y857789I1297J538D01*
G37*
G36*
G01X1436467D02*
G02X1439275I1404J0D01*
G02X1438056Y856397I-1404J0D01*
G01X1437958Y856384D01*
X1437280Y855211D01*
X1437318Y855120D01*
G02X1437424Y854586I-1298J-535D01*
G01Y854584D01*
G02X1434616I-1404J0D01*
G02X1435838Y855976I1404J0D01*
G01X1435936Y855989D01*
X1436612Y857160D01*
X1436574Y857252D01*
G02X1436467Y857789I1297J538D01*
G37*
G36*
G01X1443867D02*
G02X1446675I1404J0D01*
G02X1445456Y856397I-1404J0D01*
G01X1445358Y856384D01*
X1444680Y855211D01*
X1444718Y855120D01*
G02X1444824Y854586I-1298J-535D01*
G01Y854584D01*
G02X1442016I-1404J0D01*
G02X1443238Y855976I1404J0D01*
G01X1443336Y855989D01*
X1444012Y857160D01*
X1443974Y857252D01*
G02X1443867Y857789I1297J538D01*
G37*
G36*
G01X1451267D02*
G02X1454075I1404J0D01*
G02X1452856Y856397I-1404J0D01*
G01X1452758Y856384D01*
X1452080Y855211D01*
X1452118Y855120D01*
G02X1452224Y854586I-1298J-535D01*
G01Y854584D01*
G02X1449416I-1404J0D01*
G02X1450638Y855976I1404J0D01*
G01X1450736Y855989D01*
X1451412Y857160D01*
X1451374Y857252D01*
G02X1451267Y857789I1297J538D01*
G37*
G36*
G01X1458667D02*
G02X1461475I1404J0D01*
G02X1460256Y856397I-1404J0D01*
G01X1460158Y856384D01*
X1459480Y855211D01*
X1459518Y855120D01*
G02X1459624Y854586I-1298J-535D01*
G01Y854584D01*
G02X1456816I-1404J0D01*
G02X1458038Y855976I1404J0D01*
G01X1458136Y855989D01*
X1458812Y857160D01*
X1458774Y857252D01*
G02X1458667Y857789I1297J538D01*
G37*
G36*
G01X1466067D02*
G02X1468875I1404J0D01*
G02X1467656Y856397I-1404J0D01*
G01X1467558Y856384D01*
X1466880Y855211D01*
X1466918Y855120D01*
G02X1467024Y854586I-1298J-535D01*
G01Y854584D01*
G02X1464216I-1404J0D01*
G02X1465438Y855976I1404J0D01*
G01X1465536Y855989D01*
X1466212Y857160D01*
X1466174Y857252D01*
G02X1466067Y857789I1297J538D01*
G37*
G36*
G01X1473467D02*
G02X1476275I1404J0D01*
G02X1475056Y856397I-1404J0D01*
G01X1474958Y856384D01*
X1474280Y855211D01*
X1474318Y855120D01*
G02X1474424Y854586I-1298J-535D01*
G01Y854584D01*
G02X1471616I-1404J0D01*
G02X1472838Y855976I1404J0D01*
G01X1472936Y855989D01*
X1473612Y857160D01*
X1473574Y857252D01*
G02X1473467Y857789I1297J538D01*
G37*
G36*
G01X1480867D02*
G02X1483675I1404J0D01*
G02X1482456Y856397I-1404J0D01*
G01X1482358Y856384D01*
X1481680Y855211D01*
X1481718Y855120D01*
G02X1481824Y854586I-1298J-535D01*
G01Y854584D01*
G02X1479016I-1404J0D01*
G02X1480238Y855976I1404J0D01*
G01X1480336Y855989D01*
X1481012Y857160D01*
X1480974Y857252D01*
G02X1480867Y857789I1297J538D01*
G37*
G36*
G01X1488267D02*
G02X1491075I1404J0D01*
G02X1489856Y856397I-1404J0D01*
G01X1489758Y856384D01*
X1489080Y855211D01*
X1489118Y855120D01*
G02X1489224Y854586I-1298J-535D01*
G01Y854584D01*
G02X1486416I-1404J0D01*
G02X1487638Y855976I1404J0D01*
G01X1487736Y855989D01*
X1488412Y857160D01*
X1488374Y857252D01*
G02X1488267Y857789I1297J538D01*
G37*
G36*
G01X1495667D02*
G02X1498475I1404J0D01*
G02X1497256Y856397I-1404J0D01*
G01X1497158Y856384D01*
X1496480Y855211D01*
X1496518Y855120D01*
G02X1496624Y854586I-1298J-535D01*
G01Y854584D01*
G02X1493816I-1404J0D01*
G02X1495038Y855976I1404J0D01*
G01X1495136Y855989D01*
X1495812Y857160D01*
X1495774Y857252D01*
G02X1495667Y857789I1297J538D01*
G37*
G36*
G01X1503067D02*
G02X1505875I1404J0D01*
G02X1504656Y856397I-1404J0D01*
G01X1504558Y856384D01*
X1503880Y855211D01*
X1503918Y855120D01*
G02X1504024Y854586I-1298J-535D01*
G01Y854584D01*
G02X1501216I-1404J0D01*
G02X1502438Y855976I1404J0D01*
G01X1502536Y855989D01*
X1503212Y857160D01*
X1503174Y857252D01*
G02X1503067Y857789I1297J538D01*
G37*
G36*
G01X351174Y860993D02*
G02X353982I1404J0D01*
G02X352763Y859601I-1404J0D01*
G01X352665Y859588D01*
X351988Y858418D01*
X352026Y858326D01*
G02X352133Y857789I-1297J-538D01*
G02X349325I-1404J0D01*
G02X350544Y859181I1404J0D01*
G01X350642Y859194D01*
X351319Y860364D01*
X351281Y860456D01*
G02X351174Y860993I1297J538D01*
G37*
G36*
G01X358574D02*
G02X361382I1404J0D01*
G02X360163Y859601I-1404J0D01*
G01X360065Y859588D01*
X359388Y858418D01*
X359426Y858326D01*
G02X359533Y857789I-1297J-538D01*
G02X356725I-1404J0D01*
G02X357944Y859181I1404J0D01*
G01X358042Y859194D01*
X358719Y860364D01*
X358681Y860456D01*
G02X358574Y860993I1297J538D01*
G37*
G36*
G01X365974D02*
G02X368782I1404J0D01*
G02X367563Y859601I-1404J0D01*
G01X367465Y859588D01*
X366788Y858418D01*
X366826Y858326D01*
G02X366933Y857789I-1297J-538D01*
G02X364125I-1404J0D01*
G02X365344Y859181I1404J0D01*
G01X365442Y859194D01*
X366119Y860364D01*
X366081Y860456D01*
G02X365974Y860993I1297J538D01*
G37*
G36*
G01X373374D02*
G02X376182I1404J0D01*
G02X374963Y859601I-1404J0D01*
G01X374865Y859588D01*
X374188Y858418D01*
X374226Y858326D01*
G02X374333Y857789I-1297J-538D01*
G02X371525I-1404J0D01*
G02X372744Y859181I1404J0D01*
G01X372842Y859194D01*
X373519Y860364D01*
X373481Y860456D01*
G02X373374Y860993I1297J538D01*
G37*
G36*
G01X380774D02*
G02X383582I1404J0D01*
G02X382363Y859601I-1404J0D01*
G01X382265Y859588D01*
X381588Y858418D01*
X381626Y858326D01*
G02X381733Y857789I-1297J-538D01*
G02X378925I-1404J0D01*
G02X380144Y859181I1404J0D01*
G01X380242Y859194D01*
X380919Y860364D01*
X380881Y860456D01*
G02X380774Y860993I1297J538D01*
G37*
G36*
G01X388174D02*
G02X390982I1404J0D01*
G02X389763Y859601I-1404J0D01*
G01X389665Y859588D01*
X388988Y858418D01*
X389026Y858326D01*
G02X389133Y857789I-1297J-538D01*
G02X386325I-1404J0D01*
G02X387544Y859181I1404J0D01*
G01X387642Y859194D01*
X388319Y860364D01*
X388281Y860456D01*
G02X388174Y860993I1297J538D01*
G37*
G36*
G01X395574D02*
G02X398382I1404J0D01*
G02X397163Y859601I-1404J0D01*
G01X397065Y859588D01*
X396388Y858418D01*
X396426Y858326D01*
G02X396533Y857789I-1297J-538D01*
G02X393725I-1404J0D01*
G02X394944Y859181I1404J0D01*
G01X395042Y859194D01*
X395719Y860364D01*
X395681Y860456D01*
G02X395574Y860993I1297J538D01*
G37*
G36*
G01X402974D02*
G02X405782I1404J0D01*
G02X404563Y859601I-1404J0D01*
G01X404465Y859588D01*
X403788Y858418D01*
X403826Y858326D01*
G02X403933Y857789I-1297J-538D01*
G02X401125I-1404J0D01*
G02X402344Y859181I1404J0D01*
G01X402442Y859194D01*
X403119Y860364D01*
X403081Y860456D01*
G02X402974Y860993I1297J538D01*
G37*
G36*
G01X410374D02*
G02X413182I1404J0D01*
G02X411963Y859601I-1404J0D01*
G01X411865Y859588D01*
X411188Y858418D01*
X411226Y858326D01*
G02X411333Y857789I-1297J-538D01*
G02X408525I-1404J0D01*
G02X409744Y859181I1404J0D01*
G01X409842Y859194D01*
X410519Y860364D01*
X410481Y860456D01*
G02X410374Y860993I1297J538D01*
G37*
G36*
G01X417774D02*
G02X420582I1404J0D01*
G02X419363Y859601I-1404J0D01*
G01X419265Y859588D01*
X418588Y858418D01*
X418626Y858326D01*
G02X418733Y857789I-1297J-538D01*
G02X415925I-1404J0D01*
G02X417144Y859181I1404J0D01*
G01X417242Y859194D01*
X417919Y860364D01*
X417881Y860456D01*
G02X417774Y860993I1297J538D01*
G37*
G36*
G01X425174D02*
G02X427982I1404J0D01*
G02X426763Y859601I-1404J0D01*
G01X426665Y859588D01*
X425988Y858418D01*
X426026Y858326D01*
G02X426133Y857789I-1297J-538D01*
G02X423325I-1404J0D01*
G02X424544Y859181I1404J0D01*
G01X424642Y859194D01*
X425319Y860364D01*
X425281Y860456D01*
G02X425174Y860993I1297J538D01*
G37*
G36*
G01X432575D02*
G02X435383I1404J0D01*
G02X434164Y859601I-1404J0D01*
G01X434066Y859588D01*
X433389Y858416D01*
X433427Y858325D01*
G02X433533Y857791I-1298J-535D01*
G01Y857789D01*
G02X430725I-1404J0D01*
G02X431945Y859181I1404J0D01*
G01X432043Y859194D01*
X432720Y860364D01*
X432682Y860456D01*
G02X432575Y860993I1297J538D01*
G37*
G36*
G01X439974D02*
G02X442782I1404J0D01*
G01Y860992D01*
G02X442675Y860455I-1404J1D01*
G01X442637Y860364D01*
X443312Y859194D01*
X443410Y859181D01*
G02X444633Y857789I-181J-1392D01*
G02X441825I-1404J0D01*
G01Y857791D01*
G02X441931Y858325I1404J-1D01*
G01X441969Y858416D01*
X441291Y859588D01*
X441193Y859601D01*
G02X439974Y860993I185J1392D01*
G37*
G36*
G01X447375D02*
G02X450183I1404J0D01*
G02X450076Y860456I-1404J1D01*
G01X450038Y860364D01*
X450714Y859194D01*
X450812Y859181D01*
G02X452033Y857789I-183J-1392D01*
G02X449225I-1404J0D01*
G01Y857791D01*
G02X449331Y858325I1404J-1D01*
G01X449369Y858416D01*
X448692Y859588D01*
X448594Y859601D01*
G02X447375Y860993I185J1392D01*
G37*
G36*
G01X454774D02*
G02X457582I1404J0D01*
G01Y860992D01*
G02X457475Y860455I-1404J1D01*
G01X457437Y860364D01*
X458112Y859194D01*
X458210Y859181D01*
G02X459433Y857789I-181J-1392D01*
G02X456625I-1404J0D01*
G01Y857791D01*
G02X456731Y858325I1404J-1D01*
G01X456769Y858416D01*
X456091Y859588D01*
X455993Y859601D01*
G02X454774Y860993I185J1392D01*
G37*
G36*
G01X462174D02*
G02X464982I1404J0D01*
G01Y860992D01*
G02X464875Y860455I-1404J1D01*
G01X464837Y860364D01*
X465512Y859194D01*
X465610Y859181D01*
G02X466833Y857789I-181J-1392D01*
G02X464025I-1404J0D01*
G01Y857791D01*
G02X464131Y858325I1404J-1D01*
G01X464169Y858416D01*
X463491Y859588D01*
X463393Y859601D01*
G02X462174Y860993I185J1392D01*
G37*
G36*
G01X469574D02*
G02X472382I1404J0D01*
G01Y860992D01*
G02X472275Y860455I-1404J1D01*
G01X472237Y860364D01*
X472912Y859194D01*
X473010Y859181D01*
G02X474233Y857789I-181J-1392D01*
G02X471425I-1404J0D01*
G01Y857791D01*
G02X471531Y858325I1404J-1D01*
G01X471569Y858416D01*
X470891Y859588D01*
X470793Y859601D01*
G02X469574Y860993I185J1392D01*
G37*
G36*
G01X476974D02*
G02X479782I1404J0D01*
G01Y860992D01*
G02X479675Y860455I-1404J1D01*
G01X479637Y860364D01*
X480312Y859194D01*
X480410Y859181D01*
G02X481633Y857789I-181J-1392D01*
G02X478825I-1404J0D01*
G01Y857791D01*
G02X478931Y858325I1404J-1D01*
G01X478969Y858416D01*
X478291Y859588D01*
X478193Y859601D01*
G02X476974Y860993I185J1392D01*
G37*
G36*
G01X484374D02*
G02X487182I1404J0D01*
G01Y860992D01*
G02X487075Y860455I-1404J1D01*
G01X487037Y860364D01*
X487712Y859194D01*
X487810Y859181D01*
G02X489033Y857789I-181J-1392D01*
G02X486225I-1404J0D01*
G01Y857791D01*
G02X486331Y858325I1404J-1D01*
G01X486369Y858416D01*
X485691Y859588D01*
X485593Y859601D01*
G02X484374Y860993I185J1392D01*
G37*
G36*
G01X491774D02*
G02X494582I1404J0D01*
G01Y860992D01*
G02X494475Y860455I-1404J1D01*
G01X494437Y860364D01*
X495112Y859194D01*
X495210Y859181D01*
G02X496433Y857789I-181J-1392D01*
G02X493625I-1404J0D01*
G01Y857791D01*
G02X493731Y858325I1404J-1D01*
G01X493769Y858416D01*
X493091Y859588D01*
X492993Y859601D01*
G02X491774Y860993I185J1392D01*
G37*
G36*
G01X499174D02*
G02X501982I1404J0D01*
G01Y860992D01*
G02X501875Y860455I-1404J1D01*
G01X501837Y860364D01*
X502512Y859194D01*
X502610Y859181D01*
G02X503833Y857789I-181J-1392D01*
G02X501025I-1404J0D01*
G01Y857791D01*
G02X501131Y858325I1404J-1D01*
G01X501169Y858416D01*
X500491Y859588D01*
X500393Y859601D01*
G02X499174Y860993I185J1392D01*
G37*
G36*
G01X506574D02*
G02X509382I1404J0D01*
G01Y860992D01*
G02X509275Y860455I-1404J1D01*
G01X509237Y860364D01*
X509912Y859194D01*
X510010Y859181D01*
G02X511233Y857789I-181J-1392D01*
G02X508425I-1404J0D01*
G01Y857791D01*
G02X508531Y858325I1404J-1D01*
G01X508569Y858416D01*
X507891Y859588D01*
X507793Y859601D01*
G02X506574Y860993I185J1392D01*
G37*
G36*
G01X513974D02*
G02X516782I1404J0D01*
G01Y860992D01*
G02X516675Y860455I-1404J1D01*
G01X516637Y860364D01*
X517312Y859194D01*
X517410Y859181D01*
G02X518633Y857789I-181J-1392D01*
G02X515825I-1404J0D01*
G01Y857791D01*
G02X515931Y858325I1404J-1D01*
G01X515969Y858416D01*
X515291Y859588D01*
X515193Y859601D01*
G02X513974Y860993I185J1392D01*
G37*
G36*
G01X521374D02*
G02X524182I1404J0D01*
G01Y860992D01*
G02X524075Y860455I-1404J1D01*
G01X524037Y860364D01*
X524712Y859194D01*
X524810Y859181D01*
G02X526033Y857789I-181J-1392D01*
G02X523225I-1404J0D01*
G01Y857791D01*
G02X523331Y858325I1404J-1D01*
G01X523369Y858416D01*
X522691Y859588D01*
X522593Y859601D01*
G02X521374Y860993I185J1392D01*
G37*
G36*
G01X1327316D02*
G02X1330124I1404J0D01*
G02X1328905Y859601I-1404J0D01*
G01X1328807Y859588D01*
X1328130Y858418D01*
X1328168Y858326D01*
G02X1328275Y857789I-1297J-538D01*
G02X1325467I-1404J0D01*
G02X1326686Y859181I1404J0D01*
G01X1326784Y859194D01*
X1327461Y860364D01*
X1327423Y860456D01*
G02X1327316Y860993I1297J538D01*
G37*
G36*
G01X1334716D02*
G02X1337524I1404J0D01*
G02X1336305Y859601I-1404J0D01*
G01X1336207Y859588D01*
X1335530Y858418D01*
X1335568Y858326D01*
G02X1335675Y857789I-1297J-538D01*
G02X1332867I-1404J0D01*
G02X1334086Y859181I1404J0D01*
G01X1334184Y859194D01*
X1334861Y860364D01*
X1334823Y860456D01*
G02X1334716Y860993I1297J538D01*
G37*
G36*
G01X1342116D02*
G02X1344924I1404J0D01*
G02X1343705Y859601I-1404J0D01*
G01X1343607Y859588D01*
X1342930Y858418D01*
X1342968Y858326D01*
G02X1343075Y857789I-1297J-538D01*
G02X1340267I-1404J0D01*
G02X1341486Y859181I1404J0D01*
G01X1341584Y859194D01*
X1342261Y860364D01*
X1342223Y860456D01*
G02X1342116Y860993I1297J538D01*
G37*
G36*
G01X1349516D02*
G02X1352324I1404J0D01*
G02X1351105Y859601I-1404J0D01*
G01X1351007Y859588D01*
X1350330Y858418D01*
X1350368Y858326D01*
G02X1350475Y857789I-1297J-538D01*
G02X1347667I-1404J0D01*
G02X1348886Y859181I1404J0D01*
G01X1348984Y859194D01*
X1349661Y860364D01*
X1349623Y860456D01*
G02X1349516Y860993I1297J538D01*
G37*
G36*
G01X1356916D02*
G02X1359724I1404J0D01*
G02X1358505Y859601I-1404J0D01*
G01X1358407Y859588D01*
X1357730Y858418D01*
X1357768Y858326D01*
G02X1357875Y857789I-1297J-538D01*
G02X1355067I-1404J0D01*
G02X1356286Y859181I1404J0D01*
G01X1356384Y859194D01*
X1357061Y860364D01*
X1357023Y860456D01*
G02X1356916Y860993I1297J538D01*
G37*
G36*
G01X1364316D02*
G02X1367124I1404J0D01*
G02X1365905Y859601I-1404J0D01*
G01X1365807Y859588D01*
X1365130Y858418D01*
X1365168Y858326D01*
G02X1365275Y857789I-1297J-538D01*
G02X1362467I-1404J0D01*
G02X1363686Y859181I1404J0D01*
G01X1363784Y859194D01*
X1364461Y860364D01*
X1364423Y860456D01*
G02X1364316Y860993I1297J538D01*
G37*
G36*
G01X1371716D02*
G02X1374524I1404J0D01*
G02X1373305Y859601I-1404J0D01*
G01X1373207Y859588D01*
X1372530Y858418D01*
X1372568Y858326D01*
G02X1372675Y857789I-1297J-538D01*
G02X1369867I-1404J0D01*
G02X1371086Y859181I1404J0D01*
G01X1371184Y859194D01*
X1371861Y860364D01*
X1371823Y860456D01*
G02X1371716Y860993I1297J538D01*
G37*
G36*
G01X1379116D02*
G02X1381924I1404J0D01*
G02X1380705Y859601I-1404J0D01*
G01X1380607Y859588D01*
X1379930Y858418D01*
X1379968Y858326D01*
G02X1380075Y857789I-1297J-538D01*
G02X1377267I-1404J0D01*
G02X1378486Y859181I1404J0D01*
G01X1378584Y859194D01*
X1379261Y860364D01*
X1379223Y860456D01*
G02X1379116Y860993I1297J538D01*
G37*
G36*
G01X1386516D02*
G02X1389324I1404J0D01*
G02X1388105Y859601I-1404J0D01*
G01X1388007Y859588D01*
X1387330Y858418D01*
X1387368Y858326D01*
G02X1387475Y857789I-1297J-538D01*
G02X1384667I-1404J0D01*
G02X1385886Y859181I1404J0D01*
G01X1385984Y859194D01*
X1386661Y860364D01*
X1386623Y860456D01*
G02X1386516Y860993I1297J538D01*
G37*
G36*
G01X1393916D02*
G02X1396724I1404J0D01*
G02X1395505Y859601I-1404J0D01*
G01X1395407Y859588D01*
X1394730Y858418D01*
X1394768Y858326D01*
G02X1394875Y857789I-1297J-538D01*
G02X1392067I-1404J0D01*
G02X1393286Y859181I1404J0D01*
G01X1393384Y859194D01*
X1394061Y860364D01*
X1394023Y860456D01*
G02X1393916Y860993I1297J538D01*
G37*
G36*
G01X1401316D02*
G02X1404124I1404J0D01*
G02X1402905Y859601I-1404J0D01*
G01X1402807Y859588D01*
X1402130Y858418D01*
X1402168Y858326D01*
G02X1402275Y857789I-1297J-538D01*
G02X1399467I-1404J0D01*
G02X1400686Y859181I1404J0D01*
G01X1400784Y859194D01*
X1401461Y860364D01*
X1401423Y860456D01*
G02X1401316Y860993I1297J538D01*
G37*
G36*
G01X1408717D02*
G02X1411525I1404J0D01*
G02X1410306Y859601I-1404J0D01*
G01X1410208Y859588D01*
X1409531Y858416D01*
X1409569Y858325D01*
G02X1409675Y857791I-1298J-535D01*
G01Y857789D01*
G02X1406867I-1404J0D01*
G02X1408087Y859181I1404J0D01*
G01X1408185Y859194D01*
X1408862Y860364D01*
X1408824Y860456D01*
G02X1408717Y860993I1297J538D01*
G37*
G36*
G01X1416116D02*
G02X1418924I1404J0D01*
G01Y860992D01*
G02X1418817Y860455I-1404J1D01*
G01X1418779Y860364D01*
X1419454Y859194D01*
X1419552Y859181D01*
G02X1420775Y857789I-181J-1392D01*
G02X1417967I-1404J0D01*
G01Y857791D01*
G02X1418073Y858325I1404J-1D01*
G01X1418111Y858416D01*
X1417433Y859588D01*
X1417335Y859601D01*
G02X1416116Y860993I185J1392D01*
G37*
G36*
G01X1423517D02*
G02X1426325I1404J0D01*
G02X1426218Y860456I-1404J1D01*
G01X1426180Y860364D01*
X1426856Y859194D01*
X1426954Y859181D01*
G02X1428175Y857789I-183J-1392D01*
G02X1425367I-1404J0D01*
G01Y857791D01*
G02X1425473Y858325I1404J-1D01*
G01X1425511Y858416D01*
X1424834Y859588D01*
X1424736Y859601D01*
G02X1423517Y860993I185J1392D01*
G37*
G36*
G01X1430916D02*
G02X1433724I1404J0D01*
G01Y860992D01*
G02X1433617Y860455I-1404J1D01*
G01X1433579Y860364D01*
X1434254Y859194D01*
X1434352Y859181D01*
G02X1435575Y857789I-181J-1392D01*
G02X1432767I-1404J0D01*
G01Y857791D01*
G02X1432873Y858325I1404J-1D01*
G01X1432911Y858416D01*
X1432233Y859588D01*
X1432135Y859601D01*
G02X1430916Y860993I185J1392D01*
G37*
G36*
G01X1438316D02*
G02X1441124I1404J0D01*
G01Y860992D01*
G02X1441017Y860455I-1404J1D01*
G01X1440979Y860364D01*
X1441654Y859194D01*
X1441752Y859181D01*
G02X1442975Y857789I-181J-1392D01*
G02X1440167I-1404J0D01*
G01Y857791D01*
G02X1440273Y858325I1404J-1D01*
G01X1440311Y858416D01*
X1439633Y859588D01*
X1439535Y859601D01*
G02X1438316Y860993I185J1392D01*
G37*
G36*
G01X1445716D02*
G02X1448524I1404J0D01*
G01Y860992D01*
G02X1448417Y860455I-1404J1D01*
G01X1448379Y860364D01*
X1449054Y859194D01*
X1449152Y859181D01*
G02X1450375Y857789I-181J-1392D01*
G02X1447567I-1404J0D01*
G01Y857791D01*
G02X1447673Y858325I1404J-1D01*
G01X1447711Y858416D01*
X1447033Y859588D01*
X1446935Y859601D01*
G02X1445716Y860993I185J1392D01*
G37*
G36*
G01X1453116D02*
G02X1455924I1404J0D01*
G01Y860992D01*
G02X1455817Y860455I-1404J1D01*
G01X1455779Y860364D01*
X1456454Y859194D01*
X1456552Y859181D01*
G02X1457775Y857789I-181J-1392D01*
G02X1454967I-1404J0D01*
G01Y857791D01*
G02X1455073Y858325I1404J-1D01*
G01X1455111Y858416D01*
X1454433Y859588D01*
X1454335Y859601D01*
G02X1453116Y860993I185J1392D01*
G37*
G36*
G01X1460516D02*
G02X1463324I1404J0D01*
G01Y860992D01*
G02X1463217Y860455I-1404J1D01*
G01X1463179Y860364D01*
X1463854Y859194D01*
X1463952Y859181D01*
G02X1465175Y857789I-181J-1392D01*
G02X1462367I-1404J0D01*
G01Y857791D01*
G02X1462473Y858325I1404J-1D01*
G01X1462511Y858416D01*
X1461833Y859588D01*
X1461735Y859601D01*
G02X1460516Y860993I185J1392D01*
G37*
G36*
G01X1467916D02*
G02X1470724I1404J0D01*
G01Y860992D01*
G02X1470617Y860455I-1404J1D01*
G01X1470579Y860364D01*
X1471254Y859194D01*
X1471352Y859181D01*
G02X1472575Y857789I-181J-1392D01*
G02X1469767I-1404J0D01*
G01Y857791D01*
G02X1469873Y858325I1404J-1D01*
G01X1469911Y858416D01*
X1469233Y859588D01*
X1469135Y859601D01*
G02X1467916Y860993I185J1392D01*
G37*
G36*
G01X1475316D02*
G02X1478124I1404J0D01*
G01Y860992D01*
G02X1478017Y860455I-1404J1D01*
G01X1477979Y860364D01*
X1478654Y859194D01*
X1478752Y859181D01*
G02X1479975Y857789I-181J-1392D01*
G02X1477167I-1404J0D01*
G01Y857791D01*
G02X1477273Y858325I1404J-1D01*
G01X1477311Y858416D01*
X1476633Y859588D01*
X1476535Y859601D01*
G02X1475316Y860993I185J1392D01*
G37*
G36*
G01X1482716D02*
G02X1485524I1404J0D01*
G01Y860992D01*
G02X1485417Y860455I-1404J1D01*
G01X1485379Y860364D01*
X1486054Y859194D01*
X1486152Y859181D01*
G02X1487375Y857789I-181J-1392D01*
G02X1484567I-1404J0D01*
G01Y857791D01*
G02X1484673Y858325I1404J-1D01*
G01X1484711Y858416D01*
X1484033Y859588D01*
X1483935Y859601D01*
G02X1482716Y860993I185J1392D01*
G37*
G36*
G01X1490116D02*
G02X1492924I1404J0D01*
G01Y860992D01*
G02X1492817Y860455I-1404J1D01*
G01X1492779Y860364D01*
X1493454Y859194D01*
X1493552Y859181D01*
G02X1494775Y857789I-181J-1392D01*
G02X1491967I-1404J0D01*
G01Y857791D01*
G02X1492073Y858325I1404J-1D01*
G01X1492111Y858416D01*
X1491433Y859588D01*
X1491335Y859601D01*
G02X1490116Y860993I185J1392D01*
G37*
G36*
G01X1497516D02*
G02X1500324I1404J0D01*
G01Y860992D01*
G02X1500217Y860455I-1404J1D01*
G01X1500179Y860364D01*
X1500854Y859194D01*
X1500952Y859181D01*
G02X1502175Y857789I-181J-1392D01*
G02X1499367I-1404J0D01*
G01Y857791D01*
G02X1499473Y858325I1404J-1D01*
G01X1499511Y858416D01*
X1498833Y859588D01*
X1498735Y859601D01*
G02X1497516Y860993I185J1392D01*
G37*
G36*
G01X429307Y1079791D02*
G02X432115I1404J0D01*
G02X430896Y1078399I-1404J0D01*
G01X430798Y1078386D01*
X430121Y1077214D01*
X430159Y1077123D01*
G02X430265Y1076589I-1298J-535D01*
G01Y1076587D01*
G02X427457I-1404J0D01*
G02X428677Y1077979I1404J0D01*
G01X428775Y1077992D01*
X429452Y1079162D01*
X429414Y1079254D01*
G02X429307Y1079791I1297J538D01*
G37*
G36*
G01X1405449D02*
G02X1408257I1404J0D01*
G02X1407038Y1078399I-1404J0D01*
G01X1406940Y1078386D01*
X1406263Y1077214D01*
X1406301Y1077123D01*
G02X1406407Y1076589I-1298J-535D01*
G01Y1076587D01*
G02X1403599I-1404J0D01*
G02X1404819Y1077979I1404J0D01*
G01X1404917Y1077992D01*
X1405594Y1079162D01*
X1405556Y1079254D01*
G02X1405449Y1079791I1297J538D01*
G37*
G36*
G01X408958Y1082995D02*
G02X411766I1404J0D01*
G02X410547Y1081603I-1404J0D01*
G01X410449Y1081590D01*
X409771Y1080418D01*
X409809Y1080327D01*
G02X409915Y1079793I-1298J-535D01*
G01Y1079791D01*
G02X407107I-1404J0D01*
G02X408329Y1081183I1404J0D01*
G01X408427Y1081196D01*
X409103Y1082366D01*
X409065Y1082458D01*
G02X408958Y1082995I1297J538D01*
G37*
G36*
G01X1385100D02*
G02X1387908I1404J0D01*
G02X1386689Y1081603I-1404J0D01*
G01X1386591Y1081590D01*
X1385913Y1080418D01*
X1385951Y1080327D01*
G02X1386057Y1079793I-1298J-535D01*
G01Y1079791D01*
G02X1383249I-1404J0D01*
G02X1384471Y1081183I1404J0D01*
G01X1384569Y1081196D01*
X1385245Y1082366D01*
X1385207Y1082458D01*
G02X1385100Y1082995I1297J538D01*
G37*
G36*
G01X410807Y1086200D02*
G02X413615I1404J0D01*
G02X413508Y1085663I-1404J1D01*
G01X413470Y1085571D01*
X414146Y1084400D01*
X414244Y1084387D01*
G02X415466Y1082995I-182J-1392D01*
G02X412658I-1404J0D01*
G01Y1082997D01*
G02X412764Y1083531I1404J-1D01*
G01X412802Y1083622D01*
X412124Y1084795D01*
X412026Y1084808D01*
G02X410807Y1086200I185J1392D01*
G37*
G36*
G01X425608D02*
G02X428416I1404J0D01*
G02X427196Y1084808I-1404J0D01*
G01X427099Y1084795D01*
X426421Y1083624D01*
X426459Y1083532D01*
G02X426566Y1082995I-1297J-538D01*
G02X423758I-1404J0D01*
G02X424978Y1084387I1404J0D01*
G01X425075Y1084400D01*
X425753Y1085571D01*
X425715Y1085663D01*
G02X425608Y1086200I1297J538D01*
G37*
G36*
G01X1386949D02*
G02X1389757I1404J0D01*
G02X1389650Y1085663I-1404J1D01*
G01X1389612Y1085571D01*
X1390288Y1084400D01*
X1390386Y1084387D01*
G02X1391608Y1082995I-182J-1392D01*
G02X1388800I-1404J0D01*
G01Y1082997D01*
G02X1388906Y1083531I1404J-1D01*
G01X1388944Y1083622D01*
X1388266Y1084795D01*
X1388168Y1084808D01*
G02X1386949Y1086200I185J1392D01*
G37*
G36*
G01X1401750D02*
G02X1404558I1404J0D01*
G02X1403338Y1084808I-1404J0D01*
G01X1403241Y1084795D01*
X1402563Y1083624D01*
X1402601Y1083532D01*
G02X1402708Y1082995I-1297J-538D01*
G02X1399900I-1404J0D01*
G02X1401120Y1084387I1404J0D01*
G01X1401217Y1084400D01*
X1401895Y1085571D01*
X1401857Y1085663D01*
G02X1401750Y1086200I1297J538D01*
G37*
G36*
G01X401557Y1089404D02*
G02X404365I1404J0D01*
G02X404258Y1088867I-1404J1D01*
G01X404220Y1088775D01*
X404897Y1087605D01*
X404995Y1087592D01*
G02X406215Y1086200I-184J-1392D01*
G02X403407I-1404J0D01*
G01Y1086202D01*
G02X403513Y1086736I1404J-1D01*
G01X403551Y1086827D01*
X402874Y1087999D01*
X402776Y1088012D01*
G02X401557Y1089404I185J1392D01*
G37*
G36*
G01X427457D02*
G02X430265I1404J0D01*
G02X430158Y1088867I-1404J1D01*
G01X430120Y1088775D01*
X430797Y1087605D01*
X430895Y1087592D01*
G02X432114Y1086200I-185J-1392D01*
G02X429306I-1404J0D01*
G02X429413Y1086737I1404J-1D01*
G01X429451Y1086829D01*
X428774Y1087999D01*
X428676Y1088012D01*
G02X427457Y1089404I185J1392D01*
G37*
G36*
G01X1377699D02*
G02X1380507I1404J0D01*
G02X1380400Y1088867I-1404J1D01*
G01X1380362Y1088775D01*
X1381039Y1087605D01*
X1381137Y1087592D01*
G02X1382357Y1086200I-184J-1392D01*
G02X1379549I-1404J0D01*
G01Y1086202D01*
G02X1379655Y1086736I1404J-1D01*
G01X1379693Y1086827D01*
X1379016Y1087999D01*
X1378918Y1088012D01*
G02X1377699Y1089404I185J1392D01*
G37*
G36*
G01X1403599D02*
G02X1406407I1404J0D01*
G02X1406300Y1088867I-1404J1D01*
G01X1406262Y1088775D01*
X1406939Y1087605D01*
X1407037Y1087592D01*
G02X1408256Y1086200I-185J-1392D01*
G02X1405448I-1404J0D01*
G02X1405555Y1086737I1404J-1D01*
G01X1405593Y1086829D01*
X1404916Y1087999D01*
X1404818Y1088012D01*
G02X1403599Y1089404I185J1392D01*
G37*
G36*
G01X407107Y1092608D02*
G02X409915I1404J0D01*
G02X408696Y1091216I-1404J0D01*
G01X408598Y1091203D01*
X407921Y1090033D01*
X407959Y1089941D01*
G02X408066Y1089404I-1297J-538D01*
G02X405258I-1404J0D01*
G02X406477Y1090796I1404J0D01*
G01X406575Y1090809D01*
X407252Y1091979D01*
X407214Y1092071D01*
G02X407107Y1092608I1297J538D01*
G37*
G36*
G01X418207D02*
G02X421015I1404J0D01*
G02X420908Y1092071I-1404J1D01*
G01X420870Y1091979D01*
X421546Y1090809D01*
X421644Y1090796D01*
G02X422866Y1089404I-182J-1392D01*
G02X420058I-1404J0D01*
G01Y1089406D01*
G02X420164Y1089940I1404J-1D01*
G01X420202Y1090031D01*
X419524Y1091203D01*
X419426Y1091216D01*
G02X418207Y1092608I185J1392D01*
G37*
G36*
G01X1383249D02*
G02X1386057I1404J0D01*
G02X1384838Y1091216I-1404J0D01*
G01X1384740Y1091203D01*
X1384063Y1090033D01*
X1384101Y1089941D01*
G02X1384208Y1089404I-1297J-538D01*
G02X1381400I-1404J0D01*
G02X1382619Y1090796I1404J0D01*
G01X1382717Y1090809D01*
X1383394Y1091979D01*
X1383356Y1092071D01*
G02X1383249Y1092608I1297J538D01*
G37*
G36*
G01X1394349D02*
G02X1397157I1404J0D01*
G02X1397050Y1092071I-1404J1D01*
G01X1397012Y1091979D01*
X1397688Y1090809D01*
X1397786Y1090796D01*
G02X1399008Y1089404I-182J-1392D01*
G02X1396200I-1404J0D01*
G01Y1089406D01*
G02X1396306Y1089940I1404J-1D01*
G01X1396344Y1090031D01*
X1395666Y1091203D01*
X1395568Y1091216D01*
G02X1394349Y1092608I185J1392D01*
G37*
G36*
G01X423758Y1095813D02*
G02X426566I1404J0D01*
G02X425347Y1094421I-1404J0D01*
G01X425249Y1094408D01*
X424571Y1093235D01*
X424609Y1093144D01*
G02X424715Y1092610I-1298J-535D01*
G01Y1092608D01*
G02X421907I-1404J0D01*
G02X423129Y1094000I1404J0D01*
G01X423227Y1094013D01*
X423903Y1095184D01*
X423865Y1095276D01*
G02X423758Y1095813I1297J538D01*
G37*
G36*
G01X1399900D02*
G02X1402708I1404J0D01*
G02X1401489Y1094421I-1404J0D01*
G01X1401391Y1094408D01*
X1400713Y1093235D01*
X1400751Y1093144D01*
G02X1400857Y1092610I-1298J-535D01*
G01Y1092608D01*
G02X1398049I-1404J0D01*
G02X1399271Y1094000I1404J0D01*
G01X1399369Y1094013D01*
X1400045Y1095184D01*
X1400007Y1095276D01*
G02X1399900Y1095813I1297J538D01*
G37*
G36*
G01X401558Y1102221D02*
G02X404366I1404J0D01*
G02X403147Y1100829I-1404J0D01*
G01X403049Y1100816D01*
X402371Y1099644D01*
X402409Y1099553D01*
G02X402515Y1099019I-1298J-535D01*
G01Y1099017D01*
G02X399707I-1404J0D01*
G02X400929Y1100409I1404J0D01*
G01X401027Y1100422D01*
X401703Y1101592D01*
X401665Y1101684D01*
G02X401558Y1102221I1297J538D01*
G37*
G36*
G01X1377700D02*
G02X1380508I1404J0D01*
G02X1379289Y1100829I-1404J0D01*
G01X1379191Y1100816D01*
X1378513Y1099644D01*
X1378551Y1099553D01*
G02X1378657Y1099019I-1298J-535D01*
G01Y1099017D01*
G02X1375849I-1404J0D01*
G02X1377071Y1100409I1404J0D01*
G01X1377169Y1100422D01*
X1377845Y1101592D01*
X1377807Y1101684D01*
G02X1377700Y1102221I1297J538D01*
G37*
G36*
G01X410807Y1105426D02*
G02X413615I1404J0D01*
G02X413508Y1104889I-1404J1D01*
G01X413470Y1104797D01*
X414146Y1103626D01*
X414244Y1103613D01*
G02X415466Y1102221I-182J-1392D01*
G02X412658I-1404J0D01*
G01Y1102223D01*
G02X412764Y1102757I1404J-1D01*
G01X412802Y1102848D01*
X412124Y1104021D01*
X412026Y1104034D01*
G02X410807Y1105426I185J1392D01*
G37*
G36*
G01X1386949D02*
G02X1389757I1404J0D01*
G02X1389650Y1104889I-1404J1D01*
G01X1389612Y1104797D01*
X1390288Y1103626D01*
X1390386Y1103613D01*
G02X1391608Y1102221I-182J-1392D01*
G02X1388800I-1404J0D01*
G01Y1102223D01*
G02X1388906Y1102757I1404J-1D01*
G01X1388944Y1102848D01*
X1388266Y1104021D01*
X1388168Y1104034D01*
G02X1386949Y1105426I185J1392D01*
G37*
G36*
G01X383058Y1108630D02*
G02X385866I1404J0D01*
G02X385759Y1108093I-1404J1D01*
G01X385721Y1108001D01*
X386398Y1106831D01*
X386496Y1106818D01*
G02X387715Y1105426I-185J-1392D01*
G02X384907I-1404J0D01*
G02X385014Y1105963I1404J-1D01*
G01X385052Y1106055D01*
X384375Y1107225D01*
X384277Y1107238D01*
G02X383058Y1108630I185J1392D01*
G37*
G36*
G01X397858D02*
G02X400666I1404J0D01*
G02X399447Y1107238I-1404J0D01*
G01X399349Y1107225D01*
X398671Y1106053D01*
X398709Y1105962D01*
G02X398815Y1105428I-1298J-535D01*
G01Y1105426D01*
G02X396007I-1404J0D01*
G02X397229Y1106818I1404J0D01*
G01X397327Y1106831D01*
X398003Y1108001D01*
X397965Y1108093D01*
G02X397858Y1108630I1297J538D01*
G37*
G36*
G01X408958D02*
G02X411766I1404J0D01*
G02X410547Y1107238I-1404J0D01*
G01X410449Y1107225D01*
X409771Y1106053D01*
X409809Y1105962D01*
G02X409915Y1105428I-1298J-535D01*
G01Y1105426D01*
G02X407107I-1404J0D01*
G02X408329Y1106818I1404J0D01*
G01X408427Y1106831D01*
X409103Y1108001D01*
X409065Y1108093D01*
G02X408958Y1108630I1297J538D01*
G37*
G36*
G01X1359200D02*
G02X1362008I1404J0D01*
G02X1361901Y1108093I-1404J1D01*
G01X1361863Y1108001D01*
X1362540Y1106831D01*
X1362638Y1106818D01*
G02X1363857Y1105426I-185J-1392D01*
G02X1361049I-1404J0D01*
G02X1361156Y1105963I1404J-1D01*
G01X1361194Y1106055D01*
X1360517Y1107225D01*
X1360419Y1107238D01*
G02X1359200Y1108630I185J1392D01*
G37*
G36*
G01X1374000D02*
G02X1376808I1404J0D01*
G02X1375589Y1107238I-1404J0D01*
G01X1375491Y1107225D01*
X1374813Y1106053D01*
X1374851Y1105962D01*
G02X1374957Y1105428I-1298J-535D01*
G01Y1105426D01*
G02X1372149I-1404J0D01*
G02X1373371Y1106818I1404J0D01*
G01X1373469Y1106831D01*
X1374145Y1108001D01*
X1374107Y1108093D01*
G02X1374000Y1108630I1297J538D01*
G37*
G36*
G01X1385100D02*
G02X1387908I1404J0D01*
G02X1386689Y1107238I-1404J0D01*
G01X1386591Y1107225D01*
X1385913Y1106053D01*
X1385951Y1105962D01*
G02X1386057Y1105428I-1298J-535D01*
G01Y1105426D01*
G02X1383249I-1404J0D01*
G02X1384471Y1106818I1404J0D01*
G01X1384569Y1106831D01*
X1385245Y1108001D01*
X1385207Y1108093D01*
G02X1385100Y1108630I1297J538D01*
G37*
G36*
G01X340508Y1111834D02*
G02X343316I1404J0D01*
G01Y1111832D01*
G02X343210Y1111298I-1404J1D01*
G01X343172Y1111207D01*
X343849Y1110035D01*
X343947Y1110022D01*
G02X345166Y1108630I-185J-1392D01*
G02X342358I-1404J0D01*
G01Y1108632D01*
G02X342464Y1109166I1404J-1D01*
G01X342502Y1109257D01*
X341825Y1110429D01*
X341727Y1110442D01*
G02X340508Y1111834I185J1392D01*
G37*
G36*
G01X366408D02*
G02X369216I1404J0D01*
G02X369109Y1111297I-1404J1D01*
G01X369071Y1111205D01*
X369748Y1110035D01*
X369846Y1110022D01*
G02X371065Y1108630I-185J-1392D01*
G02X368257I-1404J0D01*
G02X368364Y1109167I1404J-1D01*
G01X368402Y1109259D01*
X367725Y1110429D01*
X367627Y1110442D01*
G02X366408Y1111834I185J1392D01*
G37*
G36*
G01X373807D02*
G02X376615I1404J0D01*
G02X376508Y1111297I-1404J1D01*
G01X376470Y1111205D01*
X377146Y1110035D01*
X377244Y1110022D01*
G02X378466Y1108630I-182J-1392D01*
G02X375658I-1404J0D01*
G01Y1108632D01*
G02X375764Y1109166I1404J-1D01*
G01X375802Y1109257D01*
X375124Y1110429D01*
X375026Y1110442D01*
G02X373807Y1111834I185J1392D01*
G37*
G36*
G01X399707D02*
G02X402515I1404J0D01*
G02X402408Y1111297I-1404J1D01*
G01X402370Y1111205D01*
X403046Y1110035D01*
X403144Y1110022D01*
G02X404366Y1108630I-182J-1392D01*
G02X401558I-1404J0D01*
G01Y1108632D01*
G02X401664Y1109166I1404J-1D01*
G01X401702Y1109257D01*
X401024Y1110429D01*
X400926Y1110442D01*
G02X399707Y1111834I185J1392D01*
G37*
G36*
G01X418207D02*
G02X421015I1404J0D01*
G02X419796Y1110442I-1404J0D01*
G01X419698Y1110429D01*
X419021Y1109259D01*
X419059Y1109167D01*
G02X419166Y1108630I-1297J-538D01*
G02X416358I-1404J0D01*
G02X417577Y1110022I1404J0D01*
G01X417675Y1110035D01*
X418352Y1111205D01*
X418314Y1111297D01*
G02X418207Y1111834I1297J538D01*
G37*
G36*
G01X1316650D02*
G02X1319458I1404J0D01*
G01Y1111832D01*
G02X1319352Y1111298I-1404J1D01*
G01X1319314Y1111207D01*
X1319991Y1110035D01*
X1320089Y1110022D01*
G02X1321308Y1108630I-185J-1392D01*
G02X1318500I-1404J0D01*
G01Y1108632D01*
G02X1318606Y1109166I1404J-1D01*
G01X1318644Y1109257D01*
X1317967Y1110429D01*
X1317869Y1110442D01*
G02X1316650Y1111834I185J1392D01*
G37*
G36*
G01X1342550D02*
G02X1345358I1404J0D01*
G02X1345251Y1111297I-1404J1D01*
G01X1345213Y1111205D01*
X1345890Y1110035D01*
X1345988Y1110022D01*
G02X1347207Y1108630I-185J-1392D01*
G02X1344399I-1404J0D01*
G02X1344506Y1109167I1404J-1D01*
G01X1344544Y1109259D01*
X1343867Y1110429D01*
X1343769Y1110442D01*
G02X1342550Y1111834I185J1392D01*
G37*
G36*
G01X1349949D02*
G02X1352757I1404J0D01*
G02X1352650Y1111297I-1404J1D01*
G01X1352612Y1111205D01*
X1353288Y1110035D01*
X1353386Y1110022D01*
G02X1354608Y1108630I-182J-1392D01*
G02X1351800I-1404J0D01*
G01Y1108632D01*
G02X1351906Y1109166I1404J-1D01*
G01X1351944Y1109257D01*
X1351266Y1110429D01*
X1351168Y1110442D01*
G02X1349949Y1111834I185J1392D01*
G37*
G36*
G01X1375849D02*
G02X1378657I1404J0D01*
G02X1378550Y1111297I-1404J1D01*
G01X1378512Y1111205D01*
X1379188Y1110035D01*
X1379286Y1110022D01*
G02X1380508Y1108630I-182J-1392D01*
G02X1377700I-1404J0D01*
G01Y1108632D01*
G02X1377806Y1109166I1404J-1D01*
G01X1377844Y1109257D01*
X1377166Y1110429D01*
X1377068Y1110442D01*
G02X1375849Y1111834I185J1392D01*
G37*
G36*
G01X1394349D02*
G02X1397157I1404J0D01*
G02X1395938Y1110442I-1404J0D01*
G01X1395840Y1110429D01*
X1395163Y1109259D01*
X1395201Y1109167D01*
G02X1395308Y1108630I-1297J-538D01*
G02X1392500I-1404J0D01*
G02X1393719Y1110022I1404J0D01*
G01X1393817Y1110035D01*
X1394494Y1111205D01*
X1394456Y1111297D01*
G02X1394349Y1111834I1297J538D01*
G37*
G36*
G01X346057Y1115039D02*
G02X348865I1404J0D01*
G02X347645Y1113647I-1404J0D01*
G01X347548Y1113634D01*
X346870Y1112463D01*
X346908Y1112371D01*
G02X347015Y1111834I-1297J-538D01*
G02X344207I-1404J0D01*
G02X345427Y1113226I1404J0D01*
G01X345524Y1113239D01*
X346202Y1114410D01*
X346164Y1114502D01*
G02X346057Y1115039I1297J538D01*
G37*
G36*
G01X357157D02*
G02X359965I1404J0D01*
G01Y1115038D01*
G02X359859Y1114502I-1404J-1D01*
G01X359821Y1114411D01*
X360498Y1113239D01*
X360596Y1113226D01*
G02X361816Y1111834I-184J-1392D01*
G02X359008I-1404J0D01*
G01Y1111836D01*
G02X359114Y1112370I1404J-1D01*
G01X359152Y1112461D01*
X358474Y1113634D01*
X358376Y1113647D01*
G02X357157Y1115039I185J1392D01*
G37*
G36*
G01X379358D02*
G02X382166I1404J0D01*
G02X380947Y1113647I-1404J0D01*
G01X380849Y1113634D01*
X380171Y1112461D01*
X380209Y1112370D01*
G02X380315Y1111836I-1298J-535D01*
G01Y1111834D01*
G02X377507I-1404J0D01*
G02X378729Y1113226I1404J0D01*
G01X378827Y1113239D01*
X379503Y1114410D01*
X379465Y1114502D01*
G02X379358Y1115039I1297J538D01*
G37*
G36*
G01X1322199D02*
G02X1325007I1404J0D01*
G02X1323787Y1113647I-1404J0D01*
G01X1323690Y1113634D01*
X1323012Y1112463D01*
X1323050Y1112371D01*
G02X1323157Y1111834I-1297J-538D01*
G02X1320349I-1404J0D01*
G02X1321569Y1113226I1404J0D01*
G01X1321666Y1113239D01*
X1322344Y1114410D01*
X1322306Y1114502D01*
G02X1322199Y1115039I1297J538D01*
G37*
G36*
G01X1333299D02*
G02X1336107I1404J0D01*
G01Y1115038D01*
G02X1336001Y1114502I-1404J-1D01*
G01X1335963Y1114411D01*
X1336640Y1113239D01*
X1336738Y1113226D01*
G02X1337958Y1111834I-184J-1392D01*
G02X1335150I-1404J0D01*
G01Y1111836D01*
G02X1335256Y1112370I1404J-1D01*
G01X1335294Y1112461D01*
X1334616Y1113634D01*
X1334518Y1113647D01*
G02X1333299Y1115039I185J1392D01*
G37*
G36*
G01X1355500D02*
G02X1358308I1404J0D01*
G02X1357089Y1113647I-1404J0D01*
G01X1356991Y1113634D01*
X1356313Y1112461D01*
X1356351Y1112370D01*
G02X1356457Y1111836I-1298J-535D01*
G01Y1111834D01*
G02X1353649I-1404J0D01*
G02X1354871Y1113226I1404J0D01*
G01X1354969Y1113239D01*
X1355645Y1114410D01*
X1355607Y1114502D01*
G02X1355500Y1115039I1297J538D01*
G37*
G36*
G01X342357Y1121447D02*
G02X345165I1404J0D01*
G02X343946Y1120055I-1404J0D01*
G01X343848Y1120042D01*
X343171Y1118872D01*
X343209Y1118780D01*
G02X343316Y1118243I-1297J-538D01*
G02X340508I-1404J0D01*
G02X341727Y1119635I1404J0D01*
G01X341825Y1119648D01*
X342502Y1120818D01*
X342464Y1120910D01*
G02X342357Y1121447I1297J538D01*
G37*
G36*
G01X1318499D02*
G02X1321307I1404J0D01*
G02X1320088Y1120055I-1404J0D01*
G01X1319990Y1120042D01*
X1319313Y1118872D01*
X1319351Y1118780D01*
G02X1319458Y1118243I-1297J-538D01*
G02X1316650I-1404J0D01*
G02X1317869Y1119635I1404J0D01*
G01X1317967Y1119648D01*
X1318644Y1120818D01*
X1318606Y1120910D01*
G02X1318499Y1121447I1297J538D01*
G37*
G36*
G01X344207Y1124651D02*
G02X347015I1404J0D01*
G01Y1124649D01*
G02X346909Y1124115I-1404J1D01*
G01X346871Y1124024D01*
X347548Y1122852D01*
X347646Y1122839D01*
G02X348865Y1121447I-185J-1392D01*
G02X346057I-1404J0D01*
G01Y1121449D01*
G02X346163Y1121983I1404J-1D01*
G01X346201Y1122074D01*
X345524Y1123246D01*
X345426Y1123259D01*
G02X344207Y1124651I185J1392D01*
G37*
G36*
G01X1320349D02*
G02X1323157I1404J0D01*
G01Y1124649D01*
G02X1323051Y1124115I-1404J1D01*
G01X1323013Y1124024D01*
X1323690Y1122852D01*
X1323788Y1122839D01*
G02X1325007Y1121447I-185J-1392D01*
G02X1322199I-1404J0D01*
G01Y1121449D01*
G02X1322305Y1121983I1404J-1D01*
G01X1322343Y1122074D01*
X1321666Y1123246D01*
X1321568Y1123259D01*
G02X1320349Y1124651I185J1392D01*
G37*
G36*
G01X340507Y1131060D02*
G02X343315I1404J0D01*
G02X342096Y1129668I-1404J0D01*
G01X341998Y1129655D01*
X341321Y1128483D01*
X341359Y1128392D01*
G02X341465Y1127858I-1298J-535D01*
G01Y1127856D01*
G02X338657I-1404J0D01*
G02X339876Y1129248I1404J0D01*
G01X339974Y1129261D01*
X340651Y1130433D01*
X340613Y1130524D01*
G02X340507Y1131058I1298J535D01*
G01Y1131060D01*
G37*
G36*
G01X1316649D02*
G02X1319457I1404J0D01*
G02X1318238Y1129668I-1404J0D01*
G01X1318140Y1129655D01*
X1317463Y1128483D01*
X1317501Y1128392D01*
G02X1317607Y1127858I-1298J-535D01*
G01Y1127856D01*
G02X1314799I-1404J0D01*
G02X1316018Y1129248I1404J0D01*
G01X1316116Y1129261D01*
X1316793Y1130433D01*
X1316755Y1130524D01*
G02X1316649Y1131058I1298J535D01*
G01Y1131060D01*
G37*
G36*
G01X963269Y1556947D02*
G03X963539I135J148D01*
G02X965904Y1557866I2365J-2584D01*
G02X969115Y1555762I0J-3502D01*
G02X970504Y1554262I-115J-1500D01*
G02X969016Y1552758I-1504J0D01*
G02X965904Y1550862I-3112J1606D01*
G02X963539Y1551781I0J3503D01*
G03X963269I-135J-148D01*
G02X960904Y1550862I-2365J2584D01*
G02Y1557866I0J3502D01*
G02X963269Y1556947I0J-3503D01*
G37*
G36*
G01X1010001D02*
G03X1010271I135J148D01*
G02X1012636Y1557866I2365J-2584D01*
G02X1015849Y1555757I0J-3502D01*
G02X1016012Y1555766I164J-1495D01*
G02Y1552758I0J-1504D01*
G02X1015759Y1552779I-3J1504D01*
G02X1012636Y1550862I-3123J1585D01*
G02X1010271Y1551781I0J3503D01*
G03X1010001I-135J-148D01*
G02X1007636Y1550862I-2365J2584D01*
G02Y1557866I0J3502D01*
G02X1010001Y1556947I0J-3503D01*
G37*
G36*
G01X1056733D02*
G03X1057003I135J148D01*
G02X1059368Y1557866I2365J-2584D01*
G02X1062579Y1555762I0J-3502D01*
G02X1063968Y1554262I-115J-1500D01*
G02X1062480Y1552758I-1504J0D01*
G02X1059368Y1550862I-3112J1606D01*
G02X1057003Y1551781I0J3503D01*
G03X1056733I-135J-148D01*
G02X1054368Y1550862I-2365J2584D01*
G02Y1557866I0J3502D01*
G02X1056733Y1556947I0J-3503D01*
G37*
G36*
G01X1080099D02*
G03X1080369I135J148D01*
G02X1082734Y1557866I2365J-2584D01*
G02X1085945Y1555762I0J-3502D01*
G02X1087334Y1554262I-115J-1500D01*
G02X1085846Y1552758I-1504J0D01*
G02X1082734Y1550862I-3112J1606D01*
G02X1080369Y1551781I0J3503D01*
G03X1080099I-135J-148D01*
G02X1077734Y1550862I-2365J2584D01*
G02Y1557866I0J3502D01*
G02X1080099Y1556947I0J-3503D01*
G37*
G36*
G01X444392Y845448D02*
X445762D01*
G02X446927Y846071I1165J-778D01*
G02Y843271I0J-1400D01*
G02X445762Y843894I0J1401D01*
G01X444392D01*
G02X443227Y843271I-1165J778D01*
G02Y846071I0J1400D01*
G02X444392Y845448I0J-1401D01*
G37*
G36*
G01X431442Y848954D02*
X432814D01*
G02X433978Y849576I1164J-778D01*
G02Y846776I0J-1400D01*
G02X432814Y847398I0J1400D01*
G01X431442D01*
G02X430278Y846776I-1164J778D01*
G02Y849576I0J1400D01*
G02X431442Y848954I0J-1400D01*
G37*
G36*
G01X527642D02*
X529014D01*
G02X530178Y849576I1164J-778D01*
G02Y846776I0J-1400D01*
G02X529014Y847398I0J1400D01*
G01X527642D01*
G02X526478Y846776I-1164J778D01*
G02Y849576I0J1400D01*
G02X527642Y848954I0J-1400D01*
G37*
G36*
G01X532478Y848176D02*
G02X535278I1400J0D01*
G02X534022Y846783I-1400J0D01*
G01X533259Y845338D01*
G02X533428Y844671I-1232J-667D01*
G02X530628I-1400J0D01*
G02X531884Y846064I1400J0D01*
G01X532647Y847509D01*
G02X532478Y848176I1232J667D01*
G37*
G36*
G01X1407584Y848954D02*
X1408956D01*
G02X1410120Y849576I1164J-778D01*
G02Y846776I0J-1400D01*
G02X1408956Y847398I0J1400D01*
G01X1407584D01*
G02X1406420Y846776I-1164J778D01*
G02Y849576I0J1400D01*
G02X1407584Y848954I0J-1400D01*
G37*
G36*
G01X404127Y1083772D02*
X405497D01*
G02X406662Y1084395I1165J-778D01*
G02Y1081595I0J-1400D01*
G02X405497Y1082218I0J1401D01*
G01X404127D01*
G02X402962Y1081595I-1165J778D01*
G02Y1084395I0J1400D01*
G02X404127Y1083772I0J-1401D01*
G37*
G36*
G01X1380269D02*
X1381639D01*
G02X1382804Y1084395I1165J-778D01*
G02Y1081595I0J-1400D01*
G02X1381639Y1082218I0J1401D01*
G01X1380269D01*
G02X1379104Y1081595I-1165J778D01*
G02Y1084395I0J1400D01*
G02X1380269Y1083772I0J-1401D01*
G37*
G36*
G01X420775Y1086978D02*
X422147D01*
G02X423311Y1087600I1164J-778D01*
G02Y1084800I0J-1400D01*
G02X422147Y1085422I0J1400D01*
G01X420775D01*
G02X419611Y1084800I-1164J778D01*
G02Y1087600I0J1400D01*
G02X420775Y1086978I0J-1400D01*
G37*
G36*
G01X1396917D02*
X1398289D01*
G02X1399453Y1087600I1164J-778D01*
G02Y1084800I0J-1400D01*
G02X1398289Y1085422I0J1400D01*
G01X1396917D01*
G02X1395753Y1084800I-1164J778D01*
G02Y1087600I0J1400D01*
G02X1396917Y1086978I0J-1400D01*
G37*
G36*
G01X411526Y1090182D02*
X412898D01*
G02X414062Y1090804I1164J-778D01*
G02Y1088004I0J-1400D01*
G02X412898Y1088626I0J1400D01*
G01X411526D01*
G02X410362Y1088004I-1164J778D01*
G02Y1090804I0J1400D01*
G02X411526Y1090182I0J-1400D01*
G37*
G36*
G01X1387668D02*
X1389040D01*
G02X1390204Y1090804I1164J-778D01*
G02Y1088004I0J-1400D01*
G02X1389040Y1088626I0J1400D01*
G01X1387668D01*
G02X1386504Y1088004I-1164J778D01*
G02Y1090804I0J1400D01*
G02X1387668Y1090182I0J-1400D01*
G37*
G36*
G01X428175Y1093386D02*
X429547D01*
G02X430711Y1094008I1164J-778D01*
G02Y1091208I0J-1400D01*
G02X429547Y1091830I0J1400D01*
G01X428175D01*
G02X427011Y1091208I-1164J778D01*
G02Y1094008I0J1400D01*
G02X428175Y1093386I0J-1400D01*
G37*
G36*
G01X1404317D02*
X1405689D01*
G02X1406853Y1094008I1164J-778D01*
G02Y1091208I0J-1400D01*
G02X1405689Y1091830I0J1400D01*
G01X1404317D01*
G02X1403153Y1091208I-1164J778D01*
G02Y1094008I0J1400D01*
G02X1404317Y1093386I0J-1400D01*
G37*
G36*
G01X405976Y1099794D02*
X407346D01*
G02X408511Y1100417I1165J-778D01*
G02Y1097617I0J-1400D01*
G02X407346Y1098240I0J1401D01*
G01X405976D01*
G02X404811Y1097617I-1165J778D01*
G02Y1100417I0J1400D01*
G02X405976Y1099794I0J-1401D01*
G37*
G36*
G01X1382118D02*
X1383488D01*
G02X1384653Y1100417I1165J-778D01*
G02Y1097617I0J-1400D01*
G02X1383488Y1098240I0J1401D01*
G01X1382118D01*
G02X1380953Y1097617I-1165J778D01*
G02Y1100417I0J1400D01*
G02X1382118Y1099794I0J-1401D01*
G37*
G36*
G01X352326Y1102998D02*
X353696D01*
G02X354861Y1103621I1165J-778D01*
G02Y1100821I0J-1400D01*
G02X353696Y1101444I0J1401D01*
G01X352326D01*
G02X351161Y1100821I-1165J778D01*
G02Y1103621I0J1400D01*
G02X352326Y1102998I0J-1401D01*
G37*
G36*
G01X1328468D02*
X1329838D01*
G02X1331003Y1103621I1165J-778D01*
G02Y1100821I0J-1400D01*
G02X1329838Y1101444I0J1401D01*
G01X1328468D01*
G02X1327303Y1100821I-1165J778D01*
G02Y1103621I0J1400D01*
G02X1328468Y1102998I0J-1401D01*
G37*
G36*
G01X343075Y1106204D02*
X344447D01*
G02X345611Y1106826I1164J-778D01*
G02Y1104026I0J-1400D01*
G02X344447Y1104648I0J1400D01*
G01X343075D01*
G02X341911Y1104026I-1164J778D01*
G02Y1106826I0J1400D01*
G02X343075Y1106204I0J-1400D01*
G37*
G36*
G01X376375D02*
X377748D01*
G02X378912Y1106826I1164J-778D01*
G02Y1104026I0J-1400D01*
G02X377748Y1104648I0J1400D01*
G01X376375D01*
G02X375211Y1104026I-1164J778D01*
G02Y1106826I0J1400D01*
G02X376375Y1106204I0J-1400D01*
G37*
G36*
G01X417075D02*
X418447D01*
G02X419611Y1106826I1164J-778D01*
G02Y1104026I0J-1400D01*
G02X418447Y1104648I0J1400D01*
G01X417075D01*
G02X415911Y1104026I-1164J778D01*
G02Y1106826I0J1400D01*
G02X417075Y1106204I0J-1400D01*
G37*
G36*
G01X1319217D02*
X1320589D01*
G02X1321753Y1106826I1164J-778D01*
G02Y1104026I0J-1400D01*
G02X1320589Y1104648I0J1400D01*
G01X1319217D01*
G02X1318053Y1104026I-1164J778D01*
G02Y1106826I0J1400D01*
G02X1319217Y1106204I0J-1400D01*
G37*
G36*
G01X1352517D02*
X1353890D01*
G02X1355054Y1106826I1164J-778D01*
G02Y1104026I0J-1400D01*
G02X1353890Y1104648I0J1400D01*
G01X1352517D01*
G02X1351353Y1104026I-1164J778D01*
G02Y1106826I0J1400D01*
G02X1352517Y1106204I0J-1400D01*
G37*
G36*
G01X1393217D02*
X1394589D01*
G02X1395753Y1106826I1164J-778D01*
G02Y1104026I0J-1400D01*
G02X1394589Y1104648I0J1400D01*
G01X1393217D01*
G02X1392053Y1104026I-1164J778D01*
G02Y1106826I0J1400D01*
G02X1393217Y1106204I0J-1400D01*
G37*
G36*
G01X359725Y1109408D02*
X361097D01*
G02X362261Y1110030I1164J-778D01*
G02Y1107230I0J-1400D01*
G02X361097Y1107852I0J1400D01*
G01X359725D01*
G02X358561Y1107230I-1164J778D01*
G02Y1110030I0J1400D01*
G02X359725Y1109408I0J-1400D01*
G37*
G36*
G01X393026D02*
X394398D01*
G02X395562Y1110030I1164J-778D01*
G02Y1107230I0J-1400D01*
G02X394398Y1107852I0J1400D01*
G01X393026D01*
G02X391862Y1107230I-1164J778D01*
G02Y1110030I0J1400D01*
G02X393026Y1109408I0J-1400D01*
G37*
G36*
G01X1335867D02*
X1337239D01*
G02X1338403Y1110030I1164J-778D01*
G02Y1107230I0J-1400D01*
G02X1337239Y1107852I0J1400D01*
G01X1335867D01*
G02X1334703Y1107230I-1164J778D01*
G02Y1110030I0J1400D01*
G02X1335867Y1109408I0J-1400D01*
G37*
G36*
G01X1369168D02*
X1370540D01*
G02X1371704Y1110030I1164J-778D01*
G02Y1107230I0J-1400D01*
G02X1370540Y1107852I0J1400D01*
G01X1369168D01*
G02X1368004Y1107230I-1164J778D01*
G02Y1110030I0J1400D01*
G02X1369168Y1109408I0J-1400D01*
G37*
G36*
G01X350476Y1112612D02*
X351848D01*
G02X353012Y1113234I1164J-778D01*
G02Y1110434I0J-1400D01*
G02X351848Y1111056I0J1400D01*
G01X350476D01*
G02X349312Y1110434I-1164J778D01*
G02Y1113234I0J1400D01*
G02X350476Y1112612I0J-1400D01*
G37*
G36*
G01X383775D02*
X385147D01*
G02X386311Y1113234I1164J-778D01*
G02Y1110434I0J-1400D01*
G02X385147Y1111056I0J1400D01*
G01X383775D01*
G02X382611Y1110434I-1164J778D01*
G02Y1113234I0J1400D01*
G02X383775Y1112612I0J-1400D01*
G37*
G36*
G01X409675D02*
X411047D01*
G02X412211Y1113234I1164J-778D01*
G02Y1110434I0J-1400D01*
G02X411047Y1111056I0J1400D01*
G01X409675D01*
G02X408511Y1110434I-1164J778D01*
G02Y1113234I0J1400D01*
G02X409675Y1112612I0J-1400D01*
G37*
G36*
G01X1326618D02*
X1327990D01*
G02X1329154Y1113234I1164J-778D01*
G02Y1110434I0J-1400D01*
G02X1327990Y1111056I0J1400D01*
G01X1326618D01*
G02X1325454Y1110434I-1164J778D01*
G02Y1113234I0J1400D01*
G02X1326618Y1112612I0J-1400D01*
G37*
G36*
G01X1359917D02*
X1361289D01*
G02X1362453Y1113234I1164J-778D01*
G02Y1110434I0J-1400D01*
G02X1361289Y1111056I0J1400D01*
G01X1359917D01*
G02X1358753Y1110434I-1164J778D01*
G02Y1113234I0J1400D01*
G02X1359917Y1112612I0J-1400D01*
G37*
G36*
G01X1385817D02*
X1387189D01*
G02X1388353Y1113234I1164J-778D01*
G02Y1110434I0J-1400D01*
G02X1387189Y1111056I0J1400D01*
G01X1385817D01*
G02X1384653Y1110434I-1164J778D01*
G02Y1113234I0J1400D01*
G02X1385817Y1112612I0J-1400D01*
G37*
G36*
G01X367126Y1115816D02*
X368496D01*
G02X369661Y1116439I1165J-778D01*
G02Y1113639I0J-1400D01*
G02X368496Y1114262I0J1401D01*
G01X367126D01*
G02X365961Y1113639I-1165J778D01*
G02Y1116439I0J1400D01*
G02X367126Y1115816I0J-1401D01*
G37*
G36*
G01X400427D02*
X401797D01*
G02X402962Y1116439I1165J-778D01*
G02Y1113639I0J-1400D01*
G02X401797Y1114262I0J1401D01*
G01X400427D01*
G02X399262Y1113639I-1165J778D01*
G02Y1116439I0J1400D01*
G02X400427Y1115816I0J-1401D01*
G37*
G36*
G01X1343268D02*
X1344638D01*
G02X1345803Y1116439I1165J-778D01*
G02Y1113639I0J-1400D01*
G02X1344638Y1114262I0J1401D01*
G01X1343268D01*
G02X1342103Y1113639I-1165J778D01*
G02Y1116439I0J1400D01*
G02X1343268Y1115816I0J-1401D01*
G37*
G36*
G01X1376569D02*
X1377939D01*
G02X1379104Y1116439I1165J-778D01*
G02Y1113639I0J-1400D01*
G02X1377939Y1114262I0J1401D01*
G01X1376569D01*
G02X1375404Y1113639I-1165J778D01*
G02Y1116439I0J1400D01*
G02X1376569Y1115816I0J-1401D01*
G37*
G36*
G01X337526Y1122224D02*
X338896D01*
G02X340061Y1122847I1165J-778D01*
G02Y1120047I0J-1400D01*
G02X338896Y1120670I0J1401D01*
G01X337526D01*
G02X336361Y1120047I-1165J778D01*
G02Y1122847I0J1400D01*
G02X337526Y1122224I0J-1401D01*
G37*
G36*
G01X1313668D02*
X1315038D01*
G02X1316203Y1122847I1165J-778D01*
G02Y1120047I0J-1400D01*
G02X1315038Y1120670I0J1401D01*
G01X1313668D01*
G02X1312503Y1120047I-1165J778D01*
G02Y1122847I0J1400D01*
G02X1313668Y1122224I0J-1401D01*
G37*
G36*
G01X344925Y1128634D02*
X346297D01*
G02X347461Y1129256I1164J-778D01*
G02Y1126456I0J-1400D01*
G02X346297Y1127078I0J1400D01*
G01X344925D01*
G02X343761Y1126456I-1164J778D01*
G02Y1129256I0J1400D01*
G02X344925Y1128634I0J-1400D01*
G37*
G36*
G01X1321067D02*
X1322439D01*
G02X1323603Y1129256I1164J-778D01*
G02Y1126456I0J-1400D01*
G02X1322439Y1127078I0J1400D01*
G01X1321067D01*
G02X1319903Y1126456I-1164J778D01*
G02Y1129256I0J1400D01*
G02X1321067Y1128634I0J-1400D01*
G37*
G36*
G01X986635Y1556947D02*
G03X986905I135J148D01*
G02X989270Y1557866I2365J-2584D01*
G02X992481Y1555762I0J-3502D01*
G02X993966Y1554262I-15J-1500D01*
G02X992466Y1552762I-1500J0D01*
G02X992385Y1552764I-3J1500D01*
G02X989270Y1550862I-3115J1600D01*
G02X986905Y1551781I0J3503D01*
G03X986635I-135J-148D01*
G02X984270Y1550862I-2365J2584D01*
G02Y1557866I0J3502D01*
G02X986635Y1556947I0J-3503D01*
G37*
G36*
G01X1033367D02*
G03X1033637I135J148D01*
G02X1036002Y1557866I2365J-2584D01*
G02X1039214Y1555760I0J-3502D01*
G02X1039298Y1555762I78J-1498D01*
G02Y1552762I0J-1500D01*
G02X1039121Y1552772I-4J1500D01*
G02X1036002Y1550862I-3119J1592D01*
G02X1033637Y1551781I0J3503D01*
G03X1033367I-135J-148D01*
G02X1031002Y1550862I-2365J2584D01*
G02Y1557866I0J3502D01*
G02X1033367Y1556947I0J-3503D01*
G37*
G36*
G01X229206Y1656840D02*
X232906D01*
G02X233208Y1656537I-1J-303D01*
G01Y1646531D01*
G02X232906Y1646228I-302J-1D01*
G01X229206D01*
G02X228904Y1646531I1J303D01*
G01Y1648936D01*
G02X228890Y1649173I2002J237D01*
G02X228904Y1649410I2016J0D01*
G01Y1653660D01*
G02X228890Y1653897I2002J237D01*
G02X228904Y1654134I2016J0D01*
G01Y1656537D01*
G02X229206Y1656840I302J1D01*
G37*
G36*
G01X276450D02*
X280150D01*
G02X280452Y1656537I-1J-303D01*
G01Y1646531D01*
G02X280150Y1646228I-302J-1D01*
G01X276450D01*
G02X276148Y1646531I1J303D01*
G01Y1648936D01*
G02X276134Y1649173I2002J237D01*
G02X276148Y1649410I2016J0D01*
G01Y1653660D01*
G02X276134Y1653897I2002J237D01*
G02X276148Y1654134I2016J0D01*
G01Y1656537D01*
G02X276450Y1656840I302J1D01*
G37*
G36*
G01X237080Y1660776D02*
X240780D01*
G02X241082Y1660474I0J-302D01*
G01Y1650468D01*
G02X240780Y1650166I-302J0D01*
G01X237080D01*
G02X236778Y1650468I0J302D01*
G01Y1652873D01*
G02X236764Y1653110I2002J237D01*
G02X236778Y1653347I2016J0D01*
G01Y1657597D01*
G02X236764Y1657834I2002J237D01*
G02X236778Y1658071I2016J0D01*
G01Y1660474D01*
G02X237080Y1660776I302J0D01*
G37*
G36*
G01X268576D02*
X272276D01*
G02X272578Y1660474I0J-302D01*
G01Y1650468D01*
G02X272276Y1650166I-302J0D01*
G01X268576D01*
G02X268274Y1650468I0J302D01*
G01Y1652873D01*
G02X268260Y1653110I2002J237D01*
G02X268274Y1653347I2016J0D01*
G01Y1657597D01*
G02X268260Y1657834I2002J237D01*
G02X268274Y1658071I2016J0D01*
G01Y1660474D01*
G02X268576Y1660776I302J0D01*
G37*
G36*
G01X284324D02*
X288024D01*
G02X288326Y1660474I0J-302D01*
G01Y1650468D01*
G02X288024Y1650166I-302J0D01*
G01X284324D01*
G02X284022Y1650468I0J302D01*
G01Y1652873D01*
G02X284008Y1653110I2002J237D01*
G02X284022Y1653347I2016J0D01*
G01Y1657597D01*
G02X284008Y1657834I2002J237D01*
G02X284022Y1658071I2016J0D01*
G01Y1660474D01*
G02X284324Y1660776I302J0D01*
G37*
G36*
G01X229206Y1671014D02*
X232906D01*
G02X233208Y1670711I-1J-303D01*
G01Y1660705D01*
G02X232906Y1660402I-302J-1D01*
G01X229206D01*
G02X228904Y1660705I1J303D01*
G01Y1663109D01*
G02X228890Y1663346I2002J237D01*
G02X228904Y1663583I2016J0D01*
G01Y1667833D01*
G02X228890Y1668070I2002J237D01*
G02X228904Y1668307I2016J0D01*
G01Y1670711D01*
G02X229206Y1671014I302J1D01*
G37*
G36*
G01X244954D02*
X248654D01*
G02X248956Y1670711I-1J-303D01*
G01Y1660705D01*
G02X248654Y1660402I-302J-1D01*
G01X244954D01*
G02X244652Y1660705I1J303D01*
G01Y1663109D01*
G02X244638Y1663346I2002J237D01*
G02X244652Y1663583I2016J0D01*
G01Y1667833D01*
G02X244638Y1668070I2002J237D01*
G02X244652Y1668307I2016J0D01*
G01Y1670711D01*
G02X244954Y1671014I302J1D01*
G37*
G36*
G01X276450D02*
X280150D01*
G02X280452Y1670711I-1J-303D01*
G01Y1660705D01*
G02X280150Y1660402I-302J-1D01*
G01X276450D01*
G02X276148Y1660705I1J303D01*
G01Y1663109D01*
G02X276134Y1663346I2002J237D01*
G02X276148Y1663583I2016J0D01*
G01Y1667833D01*
G02X276134Y1668070I2002J237D01*
G02X276148Y1668307I2016J0D01*
G01Y1670711D01*
G02X276450Y1671014I302J1D01*
G37*
G36*
G01X252828Y1674950D02*
X256528D01*
G02X256830Y1674648I0J-302D01*
G01Y1664642D01*
G02X256528Y1664340I-302J0D01*
G01X252828D01*
G02X252526Y1664642I0J302D01*
G01Y1667046D01*
G02X252512Y1667283I2002J237D01*
G02X252526Y1667520I2016J0D01*
G01Y1671770D01*
G02X252512Y1672007I2002J237D01*
G02X252526Y1672244I2016J0D01*
G01Y1674648D01*
G02X252828Y1674950I302J0D01*
G37*
G36*
G01X268576D02*
X272276D01*
G02X272578Y1674648I0J-302D01*
G01Y1664642D01*
G02X272276Y1664340I-302J0D01*
G01X268576D01*
G02X268274Y1664642I0J302D01*
G01Y1667046D01*
G02X268260Y1667283I2002J237D01*
G02X268274Y1667520I2016J0D01*
G01Y1671770D01*
G02X268260Y1672007I2002J237D01*
G02X268274Y1672244I2016J0D01*
G01Y1674648D01*
G02X268576Y1674950I302J0D01*
G37*
G36*
G01X284324D02*
X288024D01*
G02X288326Y1674648I0J-302D01*
G01Y1664642D01*
G02X288024Y1664340I-302J0D01*
G01X284324D01*
G02X284022Y1664642I0J302D01*
G01Y1667046D01*
G02X284008Y1667283I2002J237D01*
G02X284022Y1667520I2016J0D01*
G01Y1671770D01*
G02X284008Y1672007I2002J237D01*
G02X284022Y1672244I2016J0D01*
G01Y1674648D01*
G02X284324Y1674950I302J0D01*
G37*
G36*
G01X229206Y1685186D02*
X232906D01*
G02X233208Y1684884I0J-302D01*
G01Y1674878D01*
G02X232906Y1674576I-302J0D01*
G01X229206D01*
G02X228904Y1674878I0J302D01*
G01Y1676909D01*
G02X228813Y1677519I2002J610D01*
G02X229535Y1679101I2094J0D01*
G01X229854Y1679751D01*
G03Y1680013I-267J131D01*
G01X229536Y1680662D01*
G02X228813Y1682244I1369J1582D01*
G02X228904Y1682854I2093J0D01*
G01Y1684884D01*
G02X229206Y1685186I302J0D01*
G37*
G36*
G01X244954D02*
X248654D01*
G02X248956Y1684884I0J-302D01*
G01Y1674878D01*
G02X248654Y1674576I-302J0D01*
G01X244954D01*
G02X244652Y1674878I0J302D01*
G01Y1676909D01*
G02X244561Y1677519I2002J610D01*
G02X245283Y1679101I2094J0D01*
G01X245602Y1679751D01*
G03Y1680013I-267J131D01*
G01X245284Y1680662D01*
G02X244561Y1682244I1369J1582D01*
G02X244652Y1682854I2093J0D01*
G01Y1684884D01*
G02X244954Y1685186I302J0D01*
G37*
G36*
G01X260702D02*
X264402D01*
G02X264704Y1684884I0J-302D01*
G01Y1674878D01*
G02X264402Y1674576I-302J0D01*
G01X260702D01*
G02X260400Y1674878I0J302D01*
G01Y1676909D01*
G02X260309Y1677519I2002J610D01*
G02X261031Y1679101I2094J0D01*
G01X261350Y1679751D01*
G03Y1680013I-267J131D01*
G01X261032Y1680662D01*
G02X260309Y1682244I1369J1582D01*
G02X260400Y1682854I2093J0D01*
G01Y1684884D01*
G02X260702Y1685186I302J0D01*
G37*
G36*
G01X276450D02*
X280150D01*
G02X280452Y1684884I0J-302D01*
G01Y1674878D01*
G02X280150Y1674576I-302J0D01*
G01X276450D01*
G02X276148Y1674878I0J302D01*
G01Y1676909D01*
G02X276057Y1677519I2002J610D01*
G02X276779Y1679101I2094J0D01*
G01X277098Y1679751D01*
G03Y1680013I-267J131D01*
G01X276780Y1680662D01*
G02X276057Y1682244I1369J1582D01*
G02X276148Y1682854I2093J0D01*
G01Y1684884D01*
G02X276450Y1685186I302J0D01*
G37*
G36*
G01X560308D02*
X564008D01*
G02X564310Y1684884I0J-302D01*
G01Y1674878D01*
G02X564008Y1674576I-302J0D01*
G01X560308D01*
G02X560006Y1674878I0J302D01*
G01Y1677282D01*
G02X559992Y1677519I2002J237D01*
G02X560006Y1677756I2016J0D01*
G01Y1682007D01*
G02X559992Y1682244I2002J237D01*
G02X560006Y1682481I2016J0D01*
G01Y1684884D01*
G02X560308Y1685186I302J0D01*
G37*
G36*
G01X576056D02*
X579756D01*
G02X580058Y1684884I0J-302D01*
G01Y1674878D01*
G02X579756Y1674576I-302J0D01*
G01X576056D01*
G02X575754Y1674878I0J302D01*
G01Y1677282D01*
G02X575740Y1677519I2002J237D01*
G02X575754Y1677756I2016J0D01*
G01Y1682007D01*
G02X575740Y1682244I2002J237D01*
G02X575754Y1682481I2016J0D01*
G01Y1684884D01*
G02X576056Y1685186I302J0D01*
G37*
G36*
G01X591804D02*
X595504D01*
G02X595806Y1684884I0J-302D01*
G01Y1674878D01*
G02X595504Y1674576I-302J0D01*
G01X591804D01*
G02X591502Y1674878I0J302D01*
G01Y1677282D01*
G02X591488Y1677519I2002J237D01*
G02X591502Y1677756I2016J0D01*
G01Y1682007D01*
G02X591488Y1682244I2002J237D01*
G02X591502Y1682481I2016J0D01*
G01Y1684884D01*
G02X591804Y1685186I302J0D01*
G37*
G36*
G01X607552D02*
X611252D01*
G02X611554Y1684884I0J-302D01*
G01Y1674878D01*
G02X611252Y1674576I-302J0D01*
G01X607552D01*
G02X607250Y1674878I0J302D01*
G01Y1677282D01*
G02X607236Y1677519I2002J237D01*
G02X607250Y1677756I2016J0D01*
G01Y1682007D01*
G02X607236Y1682244I2002J237D01*
G02X607250Y1682481I2016J0D01*
G01Y1684884D01*
G02X607552Y1685186I302J0D01*
G37*
G36*
G01X1237080D02*
X1240780D01*
G02X1241082Y1684884I0J-302D01*
G01Y1674878D01*
G02X1240780Y1674576I-302J0D01*
G01X1237080D01*
G02X1236778Y1674878I0J302D01*
G01Y1676909D01*
G02X1236687Y1677519I2002J610D01*
G02X1237409Y1679101I2094J0D01*
G01X1237728Y1679751D01*
G03Y1680013I-267J131D01*
G01X1237410Y1680662D01*
G02X1236687Y1682244I1369J1582D01*
G02X1236778Y1682854I2093J0D01*
G01Y1684884D01*
G02X1237080Y1685186I302J0D01*
G37*
G36*
G01X1252828D02*
X1256528D01*
G02X1256830Y1684884I0J-302D01*
G01Y1674878D01*
G02X1256528Y1674576I-302J0D01*
G01X1252828D01*
G02X1252526Y1674878I0J302D01*
G01Y1676909D01*
G02X1252435Y1677519I2002J610D01*
G02X1253157Y1679101I2094J0D01*
G01X1253476Y1679751D01*
G03Y1680013I-267J131D01*
G01X1253158Y1680662D01*
G02X1252435Y1682244I1369J1582D01*
G02X1252526Y1682854I2093J0D01*
G01Y1684884D01*
G02X1252828Y1685186I302J0D01*
G37*
G36*
G01X1268576D02*
X1272276D01*
G02X1272578Y1684884I0J-302D01*
G01Y1674878D01*
G02X1272276Y1674576I-302J0D01*
G01X1268576D01*
G02X1268274Y1674878I0J302D01*
G01Y1676909D01*
G02X1268183Y1677519I2002J610D01*
G02X1268905Y1679101I2094J0D01*
G01X1269224Y1679751D01*
G03Y1680013I-267J131D01*
G01X1268906Y1680662D01*
G02X1268183Y1682244I1369J1582D01*
G02X1268274Y1682854I2093J0D01*
G01Y1684884D01*
G02X1268576Y1685186I302J0D01*
G37*
G36*
G01X1284324D02*
X1288024D01*
G02X1288326Y1684884I0J-302D01*
G01Y1674878D01*
G02X1288024Y1674576I-302J0D01*
G01X1284324D01*
G02X1284022Y1674878I0J302D01*
G01Y1676909D01*
G02X1283931Y1677519I2002J610D01*
G02X1284653Y1679101I2094J0D01*
G01X1284972Y1679751D01*
G03Y1680013I-267J131D01*
G01X1284654Y1680662D01*
G02X1283931Y1682244I1369J1582D01*
G02X1284022Y1682854I2093J0D01*
G01Y1684884D01*
G02X1284324Y1685186I302J0D01*
G37*
G36*
G01X1568182D02*
X1571882D01*
G02X1572184Y1684884I0J-302D01*
G01Y1674878D01*
G02X1571882Y1674576I-302J0D01*
G01X1568182D01*
G02X1567880Y1674878I0J302D01*
G01Y1677282D01*
G02X1567866Y1677519I2002J237D01*
G02X1567880Y1677756I2016J0D01*
G01Y1682007D01*
G02X1567866Y1682244I2002J237D01*
G02X1567880Y1682481I2016J0D01*
G01Y1684884D01*
G02X1568182Y1685186I302J0D01*
G37*
G36*
G01X1583930D02*
X1587630D01*
G02X1587932Y1684884I0J-302D01*
G01Y1674878D01*
G02X1587630Y1674576I-302J0D01*
G01X1583930D01*
G02X1583628Y1674878I0J302D01*
G01Y1677282D01*
G02X1583614Y1677519I2002J237D01*
G02X1583628Y1677756I2016J0D01*
G01Y1682007D01*
G02X1583614Y1682244I2002J237D01*
G02X1583628Y1682481I2016J0D01*
G01Y1684884D01*
G02X1583930Y1685186I302J0D01*
G37*
G36*
G01X1599678D02*
X1603378D01*
G02X1603680Y1684884I0J-302D01*
G01Y1674878D01*
G02X1603378Y1674576I-302J0D01*
G01X1599678D01*
G02X1599376Y1674878I0J302D01*
G01Y1677282D01*
G02X1599362Y1677519I2002J237D01*
G02X1599376Y1677756I2016J0D01*
G01Y1682007D01*
G02X1599362Y1682244I2002J237D01*
G02X1599376Y1682481I2016J0D01*
G01Y1684884D01*
G02X1599678Y1685186I302J0D01*
G37*
G36*
G01X1615426D02*
X1619126D01*
G02X1619428Y1684884I0J-302D01*
G01Y1674878D01*
G02X1619126Y1674576I-302J0D01*
G01X1615426D01*
G02X1615124Y1674878I0J302D01*
G01Y1677282D01*
G02X1615110Y1677519I2002J237D01*
G02X1615124Y1677756I2016J0D01*
G01Y1682007D01*
G02X1615110Y1682244I2002J237D01*
G02X1615124Y1682481I2016J0D01*
G01Y1684884D01*
G02X1615426Y1685186I302J0D01*
G37*
G36*
G01X296135D02*
X299835D01*
G02X300138Y1684884I1J-302D01*
G01Y1674878D01*
G02X299835Y1674576I-303J1D01*
G01X296135D01*
G02X295832Y1674878I-1J302D01*
G01Y1676912D01*
G02X295742Y1677519I2002J607D01*
G02X296464Y1679101I2094J0D01*
G01X296783Y1679751D01*
G03Y1680013I-267J131D01*
G01X296465Y1680662D01*
G02X295742Y1682244I1369J1582D01*
G02X295832Y1682851I2092J0D01*
G01Y1684884D01*
G02X296135Y1685186I303J-1D01*
G37*
G36*
G01X311883D02*
X315583D01*
G02X315886Y1684884I1J-302D01*
G01Y1674878D01*
G02X315583Y1674576I-303J1D01*
G01X311883D01*
G02X311580Y1674878I-1J302D01*
G01Y1676912D01*
G02X311490Y1677519I2002J607D01*
G02X312212Y1679101I2094J0D01*
G01X312531Y1679751D01*
G03Y1680013I-267J131D01*
G01X312213Y1680662D01*
G02X311490Y1682244I1369J1582D01*
G02X311580Y1682851I2092J0D01*
G01Y1684884D01*
G02X311883Y1685186I303J-1D01*
G37*
G36*
G01X327631D02*
X331331D01*
G02X331634Y1684884I1J-302D01*
G01Y1674878D01*
G02X331331Y1674576I-303J1D01*
G01X327631D01*
G02X327328Y1674878I-1J302D01*
G01Y1676912D01*
G02X327238Y1677519I2002J607D01*
G02X327960Y1679101I2094J0D01*
G01X328279Y1679751D01*
G03Y1680013I-267J131D01*
G01X327961Y1680662D01*
G02X327238Y1682244I1369J1582D01*
G02X327328Y1682851I2092J0D01*
G01Y1684884D01*
G02X327631Y1685186I303J-1D01*
G37*
G36*
G01X343379D02*
X347079D01*
G02X347382Y1684884I1J-302D01*
G01Y1674878D01*
G02X347079Y1674576I-303J1D01*
G01X343379D01*
G02X343076Y1674878I-1J302D01*
G01Y1676912D01*
G02X342986Y1677519I2002J607D01*
G02X343708Y1679101I2094J0D01*
G01X344027Y1679751D01*
G03Y1680013I-267J131D01*
G01X343709Y1680662D01*
G02X342986Y1682244I1369J1582D01*
G02X343076Y1682851I2092J0D01*
G01Y1684884D01*
G02X343379Y1685186I303J-1D01*
G37*
G36*
G01X493379D02*
X497079D01*
G02X497382Y1684884I1J-302D01*
G01Y1674878D01*
G02X497079Y1674576I-303J1D01*
G01X493379D01*
G02X493076Y1674878I-1J302D01*
G01Y1677290D01*
G02X493063Y1677519I2003J229D01*
G02X493076Y1677748I2016J0D01*
G01Y1682015D01*
G02X493063Y1682244I2003J229D01*
G02X493076Y1682473I2016J0D01*
G01Y1684884D01*
G02X493379Y1685186I303J-1D01*
G37*
G36*
G01X509127D02*
X512827D01*
G02X513130Y1684884I1J-302D01*
G01Y1674878D01*
G02X512827Y1674576I-303J1D01*
G01X509127D01*
G02X508824Y1674878I-1J302D01*
G01Y1677290D01*
G02X508811Y1677519I2003J229D01*
G02X508824Y1677748I2016J0D01*
G01Y1682015D01*
G02X508811Y1682244I2003J229D01*
G02X508824Y1682473I2016J0D01*
G01Y1684884D01*
G02X509127Y1685186I303J-1D01*
G37*
G36*
G01X524875D02*
X528575D01*
G02X528878Y1684884I1J-302D01*
G01Y1674878D01*
G02X528575Y1674576I-303J1D01*
G01X524875D01*
G02X524572Y1674878I-1J302D01*
G01Y1677290D01*
G02X524559Y1677519I2003J229D01*
G02X524572Y1677748I2016J0D01*
G01Y1682015D01*
G02X524559Y1682244I2003J229D01*
G02X524572Y1682473I2016J0D01*
G01Y1684884D01*
G02X524875Y1685186I303J-1D01*
G37*
G36*
G01X540623D02*
X544323D01*
G02X544626Y1684884I1J-302D01*
G01Y1674878D01*
G02X544323Y1674576I-303J1D01*
G01X540623D01*
G02X540320Y1674878I-1J302D01*
G01Y1677290D01*
G02X540307Y1677519I2003J229D01*
G02X540320Y1677748I2016J0D01*
G01Y1682015D01*
G02X540307Y1682244I2003J229D01*
G02X540320Y1682473I2016J0D01*
G01Y1684884D01*
G02X540623Y1685186I303J-1D01*
G37*
G36*
G01X1304009D02*
X1307709D01*
G02X1308012Y1684884I1J-302D01*
G01Y1674878D01*
G02X1307709Y1674576I-303J1D01*
G01X1304009D01*
G02X1303706Y1674878I-1J302D01*
G01Y1676912D01*
G02X1303616Y1677519I2002J607D01*
G02X1304338Y1679101I2094J0D01*
G01X1304657Y1679751D01*
G03Y1680013I-267J131D01*
G01X1304339Y1680662D01*
G02X1303616Y1682244I1369J1582D01*
G02X1303706Y1682851I2092J0D01*
G01Y1684884D01*
G02X1304009Y1685186I303J-1D01*
G37*
G36*
G01X1319757D02*
X1323457D01*
G02X1323760Y1684884I1J-302D01*
G01Y1674878D01*
G02X1323457Y1674576I-303J1D01*
G01X1319757D01*
G02X1319454Y1674878I-1J302D01*
G01Y1676912D01*
G02X1319364Y1677519I2002J607D01*
G02X1320086Y1679101I2094J0D01*
G01X1320405Y1679751D01*
G03Y1680013I-267J131D01*
G01X1320087Y1680662D01*
G02X1319364Y1682244I1369J1582D01*
G02X1319454Y1682851I2092J0D01*
G01Y1684884D01*
G02X1319757Y1685186I303J-1D01*
G37*
G36*
G01X1335505D02*
X1339205D01*
G02X1339508Y1684884I1J-302D01*
G01Y1674878D01*
G02X1339205Y1674576I-303J1D01*
G01X1335505D01*
G02X1335202Y1674878I-1J302D01*
G01Y1676912D01*
G02X1335112Y1677519I2002J607D01*
G02X1335834Y1679101I2094J0D01*
G01X1336153Y1679751D01*
G03Y1680013I-267J131D01*
G01X1335835Y1680662D01*
G02X1335112Y1682244I1369J1582D01*
G02X1335202Y1682851I2092J0D01*
G01Y1684884D01*
G02X1335505Y1685186I303J-1D01*
G37*
G36*
G01X1351253D02*
X1354953D01*
G02X1355256Y1684884I1J-302D01*
G01Y1674878D01*
G02X1354953Y1674576I-303J1D01*
G01X1351253D01*
G02X1350950Y1674878I-1J302D01*
G01Y1676912D01*
G02X1350860Y1677519I2002J607D01*
G02X1351582Y1679101I2094J0D01*
G01X1351901Y1679751D01*
G03Y1680013I-267J131D01*
G01X1351583Y1680662D01*
G02X1350860Y1682244I1369J1582D01*
G02X1350950Y1682851I2092J0D01*
G01Y1684884D01*
G02X1351253Y1685186I303J-1D01*
G37*
G36*
G01X1501253D02*
X1504953D01*
G02X1505256Y1684884I1J-302D01*
G01Y1674878D01*
G02X1504953Y1674576I-303J1D01*
G01X1501253D01*
G02X1500950Y1674878I-1J302D01*
G01Y1677290D01*
G02X1500937Y1677519I2003J229D01*
G02X1500950Y1677748I2016J0D01*
G01Y1682015D01*
G02X1500937Y1682244I2003J229D01*
G02X1500950Y1682473I2016J0D01*
G01Y1684884D01*
G02X1501253Y1685186I303J-1D01*
G37*
G36*
G01X1517001D02*
X1520701D01*
G02X1521004Y1684884I1J-302D01*
G01Y1674878D01*
G02X1520701Y1674576I-303J1D01*
G01X1517001D01*
G02X1516698Y1674878I-1J302D01*
G01Y1677290D01*
G02X1516685Y1677519I2003J229D01*
G02X1516698Y1677748I2016J0D01*
G01Y1682015D01*
G02X1516685Y1682244I2003J229D01*
G02X1516698Y1682473I2016J0D01*
G01Y1684884D01*
G02X1517001Y1685186I303J-1D01*
G37*
G36*
G01X1532749D02*
X1536449D01*
G02X1536752Y1684884I1J-302D01*
G01Y1674878D01*
G02X1536449Y1674576I-303J1D01*
G01X1532749D01*
G02X1532446Y1674878I-1J302D01*
G01Y1677290D01*
G02X1532433Y1677519I2003J229D01*
G02X1532446Y1677748I2016J0D01*
G01Y1682015D01*
G02X1532433Y1682244I2003J229D01*
G02X1532446Y1682473I2016J0D01*
G01Y1684884D01*
G02X1532749Y1685186I303J-1D01*
G37*
G36*
G01X1548497D02*
X1552197D01*
G02X1552500Y1684884I1J-302D01*
G01Y1674878D01*
G02X1552197Y1674576I-303J1D01*
G01X1548497D01*
G02X1548194Y1674878I-1J302D01*
G01Y1677290D01*
G02X1548181Y1677519I2003J229D01*
G02X1548194Y1677748I2016J0D01*
G01Y1682015D01*
G02X1548181Y1682244I2003J229D01*
G02X1548194Y1682473I2016J0D01*
G01Y1684884D01*
G02X1548497Y1685186I303J-1D01*
G37*
G36*
G01X1343379Y1689122D02*
X1347079D01*
G02X1347382Y1688820I1J-302D01*
G01Y1678814D01*
G02X1347079Y1678512I-303J1D01*
G01X1343379D01*
G02X1343076Y1678814I-1J302D01*
G01Y1680849D01*
G02X1342986Y1681456I2002J607D01*
G02X1343709Y1683038I2092J0D01*
G01X1344027Y1683687D01*
G03Y1683949I-267J131D01*
G01X1343709Y1684598D01*
G02X1342986Y1686180I1369J1582D01*
G02X1343076Y1686787I2092J0D01*
G01Y1688820D01*
G02X1343379Y1689122I303J-1D01*
G37*
G36*
G01X237080Y1689124D02*
X240780D01*
G02X241082Y1688821I-1J-303D01*
G01Y1678815D01*
G02X240780Y1678512I-302J-1D01*
G01X237080D01*
G02X236778Y1678815I1J303D01*
G01Y1680846D01*
G02X236687Y1681456I2002J610D01*
G02X237409Y1683038I2094J0D01*
G01X237728Y1683688D01*
G03Y1683950I-267J131D01*
G01X237411Y1684597D01*
G02X236687Y1686180I1369J1583D01*
G02X236778Y1686790I2093J0D01*
G01Y1688821D01*
G02X237080Y1689124I302J1D01*
G37*
G36*
G01X252828D02*
X256528D01*
G02X256830Y1688821I-1J-303D01*
G01Y1678815D01*
G02X256528Y1678512I-302J-1D01*
G01X252828D01*
G02X252526Y1678815I1J303D01*
G01Y1680846D01*
G02X252435Y1681456I2002J610D01*
G02X253157Y1683038I2094J0D01*
G01X253476Y1683688D01*
G03Y1683950I-267J131D01*
G01X253159Y1684597D01*
G02X252435Y1686180I1369J1583D01*
G02X252526Y1686790I2093J0D01*
G01Y1688821D01*
G02X252828Y1689124I302J1D01*
G37*
G36*
G01X268576D02*
X272276D01*
G02X272578Y1688821I-1J-303D01*
G01Y1678815D01*
G02X272276Y1678512I-302J-1D01*
G01X268576D01*
G02X268274Y1678815I1J303D01*
G01Y1680846D01*
G02X268183Y1681456I2002J610D01*
G02X268905Y1683038I2094J0D01*
G01X269224Y1683688D01*
G03Y1683950I-267J131D01*
G01X268907Y1684597D01*
G02X268183Y1686180I1369J1583D01*
G02X268274Y1686790I2093J0D01*
G01Y1688821D01*
G02X268576Y1689124I302J1D01*
G37*
G36*
G01X284324D02*
X288024D01*
G02X288326Y1688821I-1J-303D01*
G01Y1678815D01*
G02X288024Y1678512I-302J-1D01*
G01X284324D01*
G02X284022Y1678815I1J303D01*
G01Y1680846D01*
G02X283931Y1681456I2002J610D01*
G02X284653Y1683038I2094J0D01*
G01X284972Y1683688D01*
G03Y1683950I-267J131D01*
G01X284655Y1684597D01*
G02X283931Y1686180I1369J1583D01*
G02X284022Y1686790I2093J0D01*
G01Y1688821D01*
G02X284324Y1689124I302J1D01*
G37*
G36*
G01X304009D02*
X307709D01*
G02X308012Y1688821I0J-303D01*
G01Y1678815D01*
G02X307709Y1678512I-303J0D01*
G01X304009D01*
G02X303706Y1678815I0J303D01*
G01Y1680849D01*
G02X303616Y1681456I2002J607D01*
G02X304338Y1683038I2094J0D01*
G01X304657Y1683688D01*
G03Y1683950I-267J131D01*
G01X304340Y1684597D01*
G02X303616Y1686180I1369J1583D01*
G02X303706Y1686787I2092J0D01*
G01Y1688821D01*
G02X304009Y1689124I303J0D01*
G37*
G36*
G01X319757D02*
X323457D01*
G02X323760Y1688821I0J-303D01*
G01Y1678815D01*
G02X323457Y1678512I-303J0D01*
G01X319757D01*
G02X319454Y1678815I0J303D01*
G01Y1680849D01*
G02X319364Y1681456I2002J607D01*
G02X320086Y1683038I2094J0D01*
G01X320405Y1683688D01*
G03Y1683950I-267J131D01*
G01X320088Y1684597D01*
G02X319364Y1686180I1369J1583D01*
G02X319454Y1686787I2092J0D01*
G01Y1688821D01*
G02X319757Y1689124I303J0D01*
G37*
G36*
G01X335505D02*
X339205D01*
G02X339508Y1688821I0J-303D01*
G01Y1678815D01*
G02X339205Y1678512I-303J0D01*
G01X335505D01*
G02X335202Y1678815I0J303D01*
G01Y1680849D01*
G02X335112Y1681456I2002J607D01*
G02X335834Y1683038I2094J0D01*
G01X336153Y1683688D01*
G03Y1683950I-267J131D01*
G01X335836Y1684597D01*
G02X335112Y1686180I1369J1583D01*
G02X335202Y1686787I2092J0D01*
G01Y1688821D01*
G02X335505Y1689124I303J0D01*
G37*
G36*
G01X351253D02*
X354953D01*
G02X355256Y1688821I0J-303D01*
G01Y1678815D01*
G02X354953Y1678512I-303J0D01*
G01X351253D01*
G02X350950Y1678815I0J303D01*
G01Y1680849D01*
G02X350860Y1681456I2002J607D01*
G02X351582Y1683038I2094J0D01*
G01X351901Y1683688D01*
G03Y1683950I-267J131D01*
G01X351584Y1684597D01*
G02X350860Y1686180I1369J1583D01*
G02X350950Y1686787I2092J0D01*
G01Y1688821D01*
G02X351253Y1689124I303J0D01*
G37*
G36*
G01X501253D02*
X504953D01*
G02X505256Y1688821I0J-303D01*
G01Y1678815D01*
G02X504953Y1678512I-303J0D01*
G01X501253D01*
G02X500950Y1678815I0J303D01*
G01Y1681227D01*
G02X500937Y1681456I2003J229D01*
G02X500950Y1681685I2016J0D01*
G01Y1685951D01*
G02X500937Y1686180I2003J229D01*
G02X500950Y1686409I2016J0D01*
G01Y1688821D01*
G02X501253Y1689124I303J0D01*
G37*
G36*
G01X517001D02*
X520701D01*
G02X521004Y1688821I0J-303D01*
G01Y1678815D01*
G02X520701Y1678512I-303J0D01*
G01X517001D01*
G02X516698Y1678815I0J303D01*
G01Y1681227D01*
G02X516685Y1681456I2003J229D01*
G02X516698Y1681685I2016J0D01*
G01Y1685951D01*
G02X516685Y1686180I2003J229D01*
G02X516698Y1686409I2016J0D01*
G01Y1688821D01*
G02X517001Y1689124I303J0D01*
G37*
G36*
G01X532749D02*
X536449D01*
G02X536752Y1688821I0J-303D01*
G01Y1678815D01*
G02X536449Y1678512I-303J0D01*
G01X532749D01*
G02X532446Y1678815I0J303D01*
G01Y1681227D01*
G02X532433Y1681456I2003J229D01*
G02X532446Y1681685I2016J0D01*
G01Y1685951D01*
G02X532433Y1686180I2003J229D01*
G02X532446Y1686409I2016J0D01*
G01Y1688821D01*
G02X532749Y1689124I303J0D01*
G37*
G36*
G01X548497D02*
X552197D01*
G02X552500Y1688821I0J-303D01*
G01Y1678815D01*
G02X552197Y1678512I-303J0D01*
G01X548497D01*
G02X548194Y1678815I0J303D01*
G01Y1681227D01*
G02X548181Y1681456I2003J229D01*
G02X548194Y1681685I2016J0D01*
G01Y1685951D01*
G02X548181Y1686180I2003J229D01*
G02X548194Y1686409I2016J0D01*
G01Y1688821D01*
G02X548497Y1689124I303J0D01*
G37*
G36*
G01X568182D02*
X571882D01*
G02X572184Y1688821I-1J-303D01*
G01Y1678815D01*
G02X571882Y1678512I-302J-1D01*
G01X568182D01*
G02X567880Y1678815I1J303D01*
G01Y1681219D01*
G02X567866Y1681456I2002J237D01*
G02X567880Y1681693I2016J0D01*
G01Y1685943D01*
G02X567866Y1686180I2002J237D01*
G02X567880Y1686417I2016J0D01*
G01Y1688821D01*
G02X568182Y1689124I302J1D01*
G37*
G36*
G01X583930D02*
X587630D01*
G02X587932Y1688821I-1J-303D01*
G01Y1678815D01*
G02X587630Y1678512I-302J-1D01*
G01X583930D01*
G02X583628Y1678815I1J303D01*
G01Y1681219D01*
G02X583614Y1681456I2002J237D01*
G02X583628Y1681693I2016J0D01*
G01Y1685943D01*
G02X583614Y1686180I2002J237D01*
G02X583628Y1686417I2016J0D01*
G01Y1688821D01*
G02X583930Y1689124I302J1D01*
G37*
G36*
G01X599678D02*
X603378D01*
G02X603680Y1688821I-1J-303D01*
G01Y1678815D01*
G02X603378Y1678512I-302J-1D01*
G01X599678D01*
G02X599376Y1678815I1J303D01*
G01Y1681219D01*
G02X599362Y1681456I2002J237D01*
G02X599376Y1681693I2016J0D01*
G01Y1685943D01*
G02X599362Y1686180I2002J237D01*
G02X599376Y1686417I2016J0D01*
G01Y1688821D01*
G02X599678Y1689124I302J1D01*
G37*
G36*
G01X615426D02*
X619126D01*
G02X619428Y1688821I-1J-303D01*
G01Y1678815D01*
G02X619126Y1678512I-302J-1D01*
G01X615426D01*
G02X615124Y1678815I1J303D01*
G01Y1681219D01*
G02X615110Y1681456I2002J237D01*
G02X615124Y1681693I2016J0D01*
G01Y1685943D01*
G02X615110Y1686180I2002J237D01*
G02X615124Y1686417I2016J0D01*
G01Y1688821D01*
G02X615426Y1689124I302J1D01*
G37*
G36*
G01X1244954D02*
X1248654D01*
G02X1248956Y1688821I-1J-303D01*
G01Y1678815D01*
G02X1248654Y1678512I-302J-1D01*
G01X1244954D01*
G02X1244652Y1678815I1J303D01*
G01Y1680846D01*
G02X1244561Y1681456I2002J610D01*
G02X1245283Y1683038I2094J0D01*
G01X1245602Y1683688D01*
G03Y1683950I-267J131D01*
G01X1245285Y1684597D01*
G02X1244561Y1686180I1369J1583D01*
G02X1244652Y1686790I2093J0D01*
G01Y1688821D01*
G02X1244954Y1689124I302J1D01*
G37*
G36*
G01X1260702D02*
X1264402D01*
G02X1264704Y1688821I-1J-303D01*
G01Y1678815D01*
G02X1264402Y1678512I-302J-1D01*
G01X1260702D01*
G02X1260400Y1678815I1J303D01*
G01Y1680846D01*
G02X1260309Y1681456I2002J610D01*
G02X1261031Y1683038I2094J0D01*
G01X1261350Y1683688D01*
G03Y1683950I-267J131D01*
G01X1261033Y1684597D01*
G02X1260309Y1686180I1369J1583D01*
G02X1260400Y1686790I2093J0D01*
G01Y1688821D01*
G02X1260702Y1689124I302J1D01*
G37*
G36*
G01X1276450D02*
X1280150D01*
G02X1280452Y1688821I-1J-303D01*
G01Y1678815D01*
G02X1280150Y1678512I-302J-1D01*
G01X1276450D01*
G02X1276148Y1678815I1J303D01*
G01Y1680846D01*
G02X1276057Y1681456I2002J610D01*
G02X1276779Y1683038I2094J0D01*
G01X1277098Y1683688D01*
G03Y1683950I-267J131D01*
G01X1276781Y1684597D01*
G02X1276057Y1686180I1369J1583D01*
G02X1276148Y1686790I2093J0D01*
G01Y1688821D01*
G02X1276450Y1689124I302J1D01*
G37*
G36*
G01X1292198D02*
X1295898D01*
G02X1296200Y1688821I-1J-303D01*
G01Y1678815D01*
G02X1295898Y1678512I-302J-1D01*
G01X1292198D01*
G02X1291896Y1678815I1J303D01*
G01Y1680846D01*
G02X1291805Y1681456I2002J610D01*
G02X1292527Y1683038I2094J0D01*
G01X1292846Y1683688D01*
G03Y1683950I-267J131D01*
G01X1292529Y1684597D01*
G02X1291805Y1686180I1369J1583D01*
G02X1291896Y1686790I2093J0D01*
G01Y1688821D01*
G02X1292198Y1689124I302J1D01*
G37*
G36*
G01X1311883D02*
X1315583D01*
G02X1315886Y1688821I0J-303D01*
G01Y1678815D01*
G02X1315583Y1678512I-303J0D01*
G01X1311883D01*
G02X1311580Y1678815I0J303D01*
G01Y1680849D01*
G02X1311490Y1681456I2002J607D01*
G02X1312212Y1683038I2094J0D01*
G01X1312531Y1683688D01*
G03Y1683950I-267J131D01*
G01X1312214Y1684597D01*
G02X1311490Y1686180I1369J1583D01*
G02X1311580Y1686787I2092J0D01*
G01Y1688821D01*
G02X1311883Y1689124I303J0D01*
G37*
G36*
G01X1327631D02*
X1331331D01*
G02X1331634Y1688821I0J-303D01*
G01Y1678815D01*
G02X1331331Y1678512I-303J0D01*
G01X1327631D01*
G02X1327328Y1678815I0J303D01*
G01Y1680849D01*
G02X1327238Y1681456I2002J607D01*
G02X1327960Y1683038I2094J0D01*
G01X1328279Y1683688D01*
G03Y1683950I-267J131D01*
G01X1327962Y1684597D01*
G02X1327238Y1686180I1369J1583D01*
G02X1327328Y1686787I2092J0D01*
G01Y1688821D01*
G02X1327631Y1689124I303J0D01*
G37*
G36*
G01X1359127D02*
X1362827D01*
G02X1363130Y1688821I0J-303D01*
G01Y1678815D01*
G02X1362827Y1678512I-303J0D01*
G01X1359127D01*
G02X1358824Y1678815I0J303D01*
G01Y1680849D01*
G02X1358734Y1681456I2002J607D01*
G02X1359456Y1683038I2094J0D01*
G01X1359775Y1683688D01*
G03Y1683950I-267J131D01*
G01X1359458Y1684597D01*
G02X1358734Y1686180I1369J1583D01*
G02X1358824Y1686787I2092J0D01*
G01Y1688821D01*
G02X1359127Y1689124I303J0D01*
G37*
G36*
G01X1509127D02*
X1512827D01*
G02X1513130Y1688821I0J-303D01*
G01Y1678815D01*
G02X1512827Y1678512I-303J0D01*
G01X1509127D01*
G02X1508824Y1678815I0J303D01*
G01Y1681227D01*
G02X1508811Y1681456I2003J229D01*
G02X1508824Y1681685I2016J0D01*
G01Y1685951D01*
G02X1508811Y1686180I2003J229D01*
G02X1508824Y1686409I2016J0D01*
G01Y1688821D01*
G02X1509127Y1689124I303J0D01*
G37*
G36*
G01X1524875D02*
X1528575D01*
G02X1528878Y1688821I0J-303D01*
G01Y1678815D01*
G02X1528575Y1678512I-303J0D01*
G01X1524875D01*
G02X1524572Y1678815I0J303D01*
G01Y1681227D01*
G02X1524559Y1681456I2003J229D01*
G02X1524572Y1681685I2016J0D01*
G01Y1685951D01*
G02X1524559Y1686180I2003J229D01*
G02X1524572Y1686409I2016J0D01*
G01Y1688821D01*
G02X1524875Y1689124I303J0D01*
G37*
G36*
G01X1540623D02*
X1544323D01*
G02X1544626Y1688821I0J-303D01*
G01Y1678815D01*
G02X1544323Y1678512I-303J0D01*
G01X1540623D01*
G02X1540320Y1678815I0J303D01*
G01Y1681227D01*
G02X1540307Y1681456I2003J229D01*
G02X1540320Y1681685I2016J0D01*
G01Y1685951D01*
G02X1540307Y1686180I2003J229D01*
G02X1540320Y1686409I2016J0D01*
G01Y1688821D01*
G02X1540623Y1689124I303J0D01*
G37*
G36*
G01X1556371D02*
X1560071D01*
G02X1560374Y1688821I0J-303D01*
G01Y1678815D01*
G02X1560071Y1678512I-303J0D01*
G01X1556371D01*
G02X1556068Y1678815I0J303D01*
G01Y1681227D01*
G02X1556055Y1681456I2003J229D01*
G02X1556068Y1681685I2016J0D01*
G01Y1685951D01*
G02X1556055Y1686180I2003J229D01*
G02X1556068Y1686409I2016J0D01*
G01Y1688821D01*
G02X1556371Y1689124I303J0D01*
G37*
G36*
G01X1576056D02*
X1579756D01*
G02X1580058Y1688821I-1J-303D01*
G01Y1678815D01*
G02X1579756Y1678512I-302J-1D01*
G01X1576056D01*
G02X1575754Y1678815I1J303D01*
G01Y1681219D01*
G02X1575740Y1681456I2002J237D01*
G02X1575754Y1681693I2016J0D01*
G01Y1685943D01*
G02X1575740Y1686180I2002J237D01*
G02X1575754Y1686417I2016J0D01*
G01Y1688821D01*
G02X1576056Y1689124I302J1D01*
G37*
G36*
G01X1591804D02*
X1595504D01*
G02X1595806Y1688821I-1J-303D01*
G01Y1678815D01*
G02X1595504Y1678512I-302J-1D01*
G01X1591804D01*
G02X1591502Y1678815I1J303D01*
G01Y1681219D01*
G02X1591488Y1681456I2002J237D01*
G02X1591502Y1681693I2016J0D01*
G01Y1685943D01*
G02X1591488Y1686180I2002J237D01*
G02X1591502Y1686417I2016J0D01*
G01Y1688821D01*
G02X1591804Y1689124I302J1D01*
G37*
G36*
G01X1607552D02*
X1611252D01*
G02X1611554Y1688821I-1J-303D01*
G01Y1678815D01*
G02X1611252Y1678512I-302J-1D01*
G01X1607552D01*
G02X1607250Y1678815I1J303D01*
G01Y1681219D01*
G02X1607236Y1681456I2002J237D01*
G02X1607250Y1681693I2016J0D01*
G01Y1685943D01*
G02X1607236Y1686180I2002J237D01*
G02X1607250Y1686417I2016J0D01*
G01Y1688821D01*
G02X1607552Y1689124I302J1D01*
G37*
G36*
G01X1623300D02*
X1627000D01*
G02X1627302Y1688821I-1J-303D01*
G01Y1678815D01*
G02X1627000Y1678512I-302J-1D01*
G01X1623300D01*
G02X1622998Y1678815I1J303D01*
G01Y1681219D01*
G02X1622984Y1681456I2002J237D01*
G02X1622998Y1681693I2016J0D01*
G01Y1685943D01*
G02X1622984Y1686180I2002J237D01*
G02X1622998Y1686417I2016J0D01*
G01Y1688821D01*
G02X1623300Y1689124I302J1D01*
G37*
G36*
G01X229206Y1699360D02*
X232906D01*
G02X233208Y1699057I-1J-303D01*
G01Y1689051D01*
G02X232906Y1688748I-302J-1D01*
G01X229206D01*
G02X228904Y1689051I1J303D01*
G01Y1691455D01*
G02X228890Y1691692I2002J237D01*
G02X228904Y1691929I2016J0D01*
G01Y1696180D01*
G02X228890Y1696417I2002J237D01*
G02X228904Y1696654I2016J0D01*
G01Y1699057D01*
G02X229206Y1699360I302J1D01*
G37*
G36*
G01X244954D02*
X248654D01*
G02X248956Y1699057I-1J-303D01*
G01Y1689051D01*
G02X248654Y1688748I-302J-1D01*
G01X244954D01*
G02X244652Y1689051I1J303D01*
G01Y1691455D01*
G02X244638Y1691692I2002J237D01*
G02X244652Y1691929I2016J0D01*
G01Y1696180D01*
G02X244638Y1696417I2002J237D01*
G02X244652Y1696654I2016J0D01*
G01Y1699057D01*
G02X244954Y1699360I302J1D01*
G37*
G36*
G01X260702D02*
X264402D01*
G02X264704Y1699057I-1J-303D01*
G01Y1689051D01*
G02X264402Y1688748I-302J-1D01*
G01X260702D01*
G02X260400Y1689051I1J303D01*
G01Y1691455D01*
G02X260386Y1691692I2002J237D01*
G02X260400Y1691929I2016J0D01*
G01Y1696180D01*
G02X260386Y1696417I2002J237D01*
G02X260400Y1696654I2016J0D01*
G01Y1699057D01*
G02X260702Y1699360I302J1D01*
G37*
G36*
G01X276450D02*
X280150D01*
G02X280452Y1699057I-1J-303D01*
G01Y1689051D01*
G02X280150Y1688748I-302J-1D01*
G01X276450D01*
G02X276148Y1689051I1J303D01*
G01Y1691455D01*
G02X276134Y1691692I2002J237D01*
G02X276148Y1691929I2016J0D01*
G01Y1696180D01*
G02X276134Y1696417I2002J237D01*
G02X276148Y1696654I2016J0D01*
G01Y1699057D01*
G02X276450Y1699360I302J1D01*
G37*
G36*
G01X296135D02*
X299835D01*
G02X300138Y1699057I0J-303D01*
G01Y1689051D01*
G02X299835Y1688748I-303J0D01*
G01X296135D01*
G02X295832Y1689051I0J303D01*
G01Y1691463D01*
G02X295819Y1691692I2003J229D01*
G02X295832Y1691921I2016J0D01*
G01Y1696188D01*
G02X295819Y1696417I2003J229D01*
G02X295832Y1696646I2016J0D01*
G01Y1699057D01*
G02X296135Y1699360I303J0D01*
G37*
G36*
G01X311883D02*
X315583D01*
G02X315886Y1699057I0J-303D01*
G01Y1689051D01*
G02X315583Y1688748I-303J0D01*
G01X311883D01*
G02X311580Y1689051I0J303D01*
G01Y1691463D01*
G02X311567Y1691692I2003J229D01*
G02X311580Y1691921I2016J0D01*
G01Y1696188D01*
G02X311567Y1696417I2003J229D01*
G02X311580Y1696646I2016J0D01*
G01Y1699057D01*
G02X311883Y1699360I303J0D01*
G37*
G36*
G01X327631D02*
X331331D01*
G02X331634Y1699057I0J-303D01*
G01Y1689051D01*
G02X331331Y1688748I-303J0D01*
G01X327631D01*
G02X327328Y1689051I0J303D01*
G01Y1691463D01*
G02X327315Y1691692I2003J229D01*
G02X327328Y1691921I2016J0D01*
G01Y1696188D01*
G02X327315Y1696417I2003J229D01*
G02X327328Y1696646I2016J0D01*
G01Y1699057D01*
G02X327631Y1699360I303J0D01*
G37*
G36*
G01X343379D02*
X347079D01*
G02X347382Y1699057I0J-303D01*
G01Y1689051D01*
G02X347079Y1688748I-303J0D01*
G01X343379D01*
G02X343076Y1689051I0J303D01*
G01Y1691463D01*
G02X343063Y1691692I2003J229D01*
G02X343076Y1691921I2016J0D01*
G01Y1696188D01*
G02X343063Y1696417I2003J229D01*
G02X343076Y1696646I2016J0D01*
G01Y1699057D01*
G02X343379Y1699360I303J0D01*
G37*
G36*
G01X493379D02*
X497079D01*
G02X497382Y1699057I0J-303D01*
G01Y1689051D01*
G02X497079Y1688748I-303J0D01*
G01X493379D01*
G02X493076Y1689051I0J303D01*
G01Y1691085D01*
G02X492986Y1691692I2002J607D01*
G02X493708Y1693274I2094J0D01*
G01X494027Y1693924D01*
G03Y1694186I-267J131D01*
G01X493709Y1694835D01*
G02X492986Y1696417I1369J1582D01*
G02X493076Y1697024I2092J0D01*
G01Y1699057D01*
G02X493379Y1699360I303J0D01*
G37*
G36*
G01X509127D02*
X512827D01*
G02X513130Y1699057I0J-303D01*
G01Y1689051D01*
G02X512827Y1688748I-303J0D01*
G01X509127D01*
G02X508824Y1689051I0J303D01*
G01Y1691085D01*
G02X508734Y1691692I2002J607D01*
G02X509456Y1693274I2094J0D01*
G01X509775Y1693924D01*
G03Y1694186I-267J131D01*
G01X509457Y1694835D01*
G02X508734Y1696417I1369J1582D01*
G02X508824Y1697024I2092J0D01*
G01Y1699057D01*
G02X509127Y1699360I303J0D01*
G37*
G36*
G01X524875D02*
X528575D01*
G02X528878Y1699057I0J-303D01*
G01Y1689051D01*
G02X528575Y1688748I-303J0D01*
G01X524875D01*
G02X524572Y1689051I0J303D01*
G01Y1691085D01*
G02X524482Y1691692I2002J607D01*
G02X525204Y1693274I2094J0D01*
G01X525523Y1693924D01*
G03Y1694186I-267J131D01*
G01X525205Y1694835D01*
G02X524482Y1696417I1369J1582D01*
G02X524572Y1697024I2092J0D01*
G01Y1699057D01*
G02X524875Y1699360I303J0D01*
G37*
G36*
G01X540623D02*
X544323D01*
G02X544626Y1699057I0J-303D01*
G01Y1689051D01*
G02X544323Y1688748I-303J0D01*
G01X540623D01*
G02X540320Y1689051I0J303D01*
G01Y1691085D01*
G02X540230Y1691692I2002J607D01*
G02X540952Y1693274I2094J0D01*
G01X541271Y1693924D01*
G03Y1694186I-267J131D01*
G01X540953Y1694835D01*
G02X540230Y1696417I1369J1582D01*
G02X540320Y1697024I2092J0D01*
G01Y1699057D01*
G02X540623Y1699360I303J0D01*
G37*
G36*
G01X560308D02*
X564008D01*
G02X564310Y1699057I-1J-303D01*
G01Y1689051D01*
G02X564008Y1688748I-302J-1D01*
G01X560308D01*
G02X560006Y1689051I1J303D01*
G01Y1691082D01*
G02X559915Y1691692I2002J610D01*
G02X560637Y1693274I2094J0D01*
G01X560956Y1693924D01*
G03Y1694186I-267J131D01*
G01X560638Y1694835D01*
G02X559915Y1696417I1369J1582D01*
G02X560006Y1697027I2093J0D01*
G01Y1699057D01*
G02X560308Y1699360I302J1D01*
G37*
G36*
G01X576056D02*
X579756D01*
G02X580058Y1699057I-1J-303D01*
G01Y1689051D01*
G02X579756Y1688748I-302J-1D01*
G01X576056D01*
G02X575754Y1689051I1J303D01*
G01Y1691082D01*
G02X575663Y1691692I2002J610D01*
G02X576385Y1693274I2094J0D01*
G01X576704Y1693924D01*
G03Y1694186I-267J131D01*
G01X576386Y1694835D01*
G02X575663Y1696417I1369J1582D01*
G02X575754Y1697027I2093J0D01*
G01Y1699057D01*
G02X576056Y1699360I302J1D01*
G37*
G36*
G01X591804D02*
X595504D01*
G02X595806Y1699057I-1J-303D01*
G01Y1689051D01*
G02X595504Y1688748I-302J-1D01*
G01X591804D01*
G02X591502Y1689051I1J303D01*
G01Y1691082D01*
G02X591411Y1691692I2002J610D01*
G02X592133Y1693274I2094J0D01*
G01X592452Y1693924D01*
G03Y1694186I-267J131D01*
G01X592134Y1694835D01*
G02X591411Y1696417I1369J1582D01*
G02X591502Y1697027I2093J0D01*
G01Y1699057D01*
G02X591804Y1699360I302J1D01*
G37*
G36*
G01X607552D02*
X611252D01*
G02X611554Y1699057I-1J-303D01*
G01Y1689051D01*
G02X611252Y1688748I-302J-1D01*
G01X607552D01*
G02X607250Y1689051I1J303D01*
G01Y1691082D01*
G02X607159Y1691692I2002J610D01*
G02X607881Y1693274I2094J0D01*
G01X608200Y1693924D01*
G03Y1694186I-267J131D01*
G01X607882Y1694835D01*
G02X607159Y1696417I1369J1582D01*
G02X607250Y1697027I2093J0D01*
G01Y1699057D01*
G02X607552Y1699360I302J1D01*
G37*
G36*
G01X1237080D02*
X1240780D01*
G02X1241082Y1699057I-1J-303D01*
G01Y1689051D01*
G02X1240780Y1688748I-302J-1D01*
G01X1237080D01*
G02X1236778Y1689051I1J303D01*
G01Y1691455D01*
G02X1236764Y1691692I2002J237D01*
G02X1236778Y1691929I2016J0D01*
G01Y1696180D01*
G02X1236764Y1696417I2002J237D01*
G02X1236778Y1696654I2016J0D01*
G01Y1699057D01*
G02X1237080Y1699360I302J1D01*
G37*
G36*
G01X1252828D02*
X1256528D01*
G02X1256830Y1699057I-1J-303D01*
G01Y1689051D01*
G02X1256528Y1688748I-302J-1D01*
G01X1252828D01*
G02X1252526Y1689051I1J303D01*
G01Y1691455D01*
G02X1252512Y1691692I2002J237D01*
G02X1252526Y1691929I2016J0D01*
G01Y1696180D01*
G02X1252512Y1696417I2002J237D01*
G02X1252526Y1696654I2016J0D01*
G01Y1699057D01*
G02X1252828Y1699360I302J1D01*
G37*
G36*
G01X1268576D02*
X1272276D01*
G02X1272578Y1699057I-1J-303D01*
G01Y1689051D01*
G02X1272276Y1688748I-302J-1D01*
G01X1268576D01*
G02X1268274Y1689051I1J303D01*
G01Y1691455D01*
G02X1268260Y1691692I2002J237D01*
G02X1268274Y1691929I2016J0D01*
G01Y1696180D01*
G02X1268260Y1696417I2002J237D01*
G02X1268274Y1696654I2016J0D01*
G01Y1699057D01*
G02X1268576Y1699360I302J1D01*
G37*
G36*
G01X1284324D02*
X1288024D01*
G02X1288326Y1699057I-1J-303D01*
G01Y1689051D01*
G02X1288024Y1688748I-302J-1D01*
G01X1284324D01*
G02X1284022Y1689051I1J303D01*
G01Y1691455D01*
G02X1284008Y1691692I2002J237D01*
G02X1284022Y1691929I2016J0D01*
G01Y1696180D01*
G02X1284008Y1696417I2002J237D01*
G02X1284022Y1696654I2016J0D01*
G01Y1699057D01*
G02X1284324Y1699360I302J1D01*
G37*
G36*
G01X1304009D02*
X1307709D01*
G02X1308012Y1699057I0J-303D01*
G01Y1689051D01*
G02X1307709Y1688748I-303J0D01*
G01X1304009D01*
G02X1303706Y1689051I0J303D01*
G01Y1691463D01*
G02X1303693Y1691692I2003J229D01*
G02X1303706Y1691921I2016J0D01*
G01Y1696188D01*
G02X1303693Y1696417I2003J229D01*
G02X1303706Y1696646I2016J0D01*
G01Y1699057D01*
G02X1304009Y1699360I303J0D01*
G37*
G36*
G01X1319757D02*
X1323457D01*
G02X1323760Y1699057I0J-303D01*
G01Y1689051D01*
G02X1323457Y1688748I-303J0D01*
G01X1319757D01*
G02X1319454Y1689051I0J303D01*
G01Y1691463D01*
G02X1319441Y1691692I2003J229D01*
G02X1319454Y1691921I2016J0D01*
G01Y1696188D01*
G02X1319441Y1696417I2003J229D01*
G02X1319454Y1696646I2016J0D01*
G01Y1699057D01*
G02X1319757Y1699360I303J0D01*
G37*
G36*
G01X1335505D02*
X1339205D01*
G02X1339508Y1699057I0J-303D01*
G01Y1689051D01*
G02X1339205Y1688748I-303J0D01*
G01X1335505D01*
G02X1335202Y1689051I0J303D01*
G01Y1691463D01*
G02X1335189Y1691692I2003J229D01*
G02X1335202Y1691921I2016J0D01*
G01Y1696188D01*
G02X1335189Y1696417I2003J229D01*
G02X1335202Y1696646I2016J0D01*
G01Y1699057D01*
G02X1335505Y1699360I303J0D01*
G37*
G36*
G01X1351253D02*
X1354953D01*
G02X1355256Y1699057I0J-303D01*
G01Y1689051D01*
G02X1354953Y1688748I-303J0D01*
G01X1351253D01*
G02X1350950Y1689051I0J303D01*
G01Y1691463D01*
G02X1350937Y1691692I2003J229D01*
G02X1350950Y1691921I2016J0D01*
G01Y1696188D01*
G02X1350937Y1696417I2003J229D01*
G02X1350950Y1696646I2016J0D01*
G01Y1699057D01*
G02X1351253Y1699360I303J0D01*
G37*
G36*
G01X1501253D02*
X1504953D01*
G02X1505256Y1699057I0J-303D01*
G01Y1689051D01*
G02X1504953Y1688748I-303J0D01*
G01X1501253D01*
G02X1500950Y1689051I0J303D01*
G01Y1691085D01*
G02X1500860Y1691692I2002J607D01*
G02X1501582Y1693274I2094J0D01*
G01X1501901Y1693924D01*
G03Y1694186I-267J131D01*
G01X1501583Y1694835D01*
G02X1500860Y1696417I1369J1582D01*
G02X1500950Y1697024I2092J0D01*
G01Y1699057D01*
G02X1501253Y1699360I303J0D01*
G37*
G36*
G01X1517001D02*
X1520701D01*
G02X1521004Y1699057I0J-303D01*
G01Y1689051D01*
G02X1520701Y1688748I-303J0D01*
G01X1517001D01*
G02X1516698Y1689051I0J303D01*
G01Y1691085D01*
G02X1516608Y1691692I2002J607D01*
G02X1517330Y1693274I2094J0D01*
G01X1517649Y1693924D01*
G03Y1694186I-267J131D01*
G01X1517331Y1694835D01*
G02X1516608Y1696417I1369J1582D01*
G02X1516698Y1697024I2092J0D01*
G01Y1699057D01*
G02X1517001Y1699360I303J0D01*
G37*
G36*
G01X1532749D02*
X1536449D01*
G02X1536752Y1699057I0J-303D01*
G01Y1689051D01*
G02X1536449Y1688748I-303J0D01*
G01X1532749D01*
G02X1532446Y1689051I0J303D01*
G01Y1691085D01*
G02X1532356Y1691692I2002J607D01*
G02X1533078Y1693274I2094J0D01*
G01X1533397Y1693924D01*
G03Y1694186I-267J131D01*
G01X1533079Y1694835D01*
G02X1532356Y1696417I1369J1582D01*
G02X1532446Y1697024I2092J0D01*
G01Y1699057D01*
G02X1532749Y1699360I303J0D01*
G37*
G36*
G01X1548497D02*
X1552197D01*
G02X1552500Y1699057I0J-303D01*
G01Y1689051D01*
G02X1552197Y1688748I-303J0D01*
G01X1548497D01*
G02X1548194Y1689051I0J303D01*
G01Y1691085D01*
G02X1548104Y1691692I2002J607D01*
G02X1548826Y1693274I2094J0D01*
G01X1549145Y1693924D01*
G03Y1694186I-267J131D01*
G01X1548827Y1694835D01*
G02X1548104Y1696417I1369J1582D01*
G02X1548194Y1697024I2092J0D01*
G01Y1699057D01*
G02X1548497Y1699360I303J0D01*
G37*
G36*
G01X1568182D02*
X1571882D01*
G02X1572184Y1699057I-1J-303D01*
G01Y1689051D01*
G02X1571882Y1688748I-302J-1D01*
G01X1568182D01*
G02X1567880Y1689051I1J303D01*
G01Y1691082D01*
G02X1567789Y1691692I2002J610D01*
G02X1568511Y1693274I2094J0D01*
G01X1568830Y1693924D01*
G03Y1694186I-267J131D01*
G01X1568512Y1694835D01*
G02X1567789Y1696417I1369J1582D01*
G02X1567880Y1697027I2093J0D01*
G01Y1699057D01*
G02X1568182Y1699360I302J1D01*
G37*
G36*
G01X1583930D02*
X1587630D01*
G02X1587932Y1699057I-1J-303D01*
G01Y1689051D01*
G02X1587630Y1688748I-302J-1D01*
G01X1583930D01*
G02X1583628Y1689051I1J303D01*
G01Y1691082D01*
G02X1583537Y1691692I2002J610D01*
G02X1584259Y1693274I2094J0D01*
G01X1584578Y1693924D01*
G03Y1694186I-267J131D01*
G01X1584260Y1694835D01*
G02X1583537Y1696417I1369J1582D01*
G02X1583628Y1697027I2093J0D01*
G01Y1699057D01*
G02X1583930Y1699360I302J1D01*
G37*
G36*
G01X1599678D02*
X1603378D01*
G02X1603680Y1699057I-1J-303D01*
G01Y1689051D01*
G02X1603378Y1688748I-302J-1D01*
G01X1599678D01*
G02X1599376Y1689051I1J303D01*
G01Y1691082D01*
G02X1599285Y1691692I2002J610D01*
G02X1600007Y1693274I2094J0D01*
G01X1600326Y1693924D01*
G03Y1694186I-267J131D01*
G01X1600008Y1694835D01*
G02X1599285Y1696417I1369J1582D01*
G02X1599376Y1697027I2093J0D01*
G01Y1699057D01*
G02X1599678Y1699360I302J1D01*
G37*
G36*
G01X1615426D02*
X1619126D01*
G02X1619428Y1699057I-1J-303D01*
G01Y1689051D01*
G02X1619126Y1688748I-302J-1D01*
G01X1615426D01*
G02X1615124Y1689051I1J303D01*
G01Y1691082D01*
G02X1615033Y1691692I2002J610D01*
G02X1615755Y1693274I2094J0D01*
G01X1616074Y1693924D01*
G03Y1694186I-267J131D01*
G01X1615756Y1694835D01*
G02X1615033Y1696417I1369J1582D01*
G02X1615124Y1697027I2093J0D01*
G01Y1699057D01*
G02X1615426Y1699360I302J1D01*
G37*
G36*
G01X237080Y1703296D02*
X240780D01*
G02X241082Y1702994I0J-302D01*
G01Y1692988D01*
G02X240780Y1692686I-302J0D01*
G01X237080D01*
G02X236778Y1692988I0J302D01*
G01Y1695392D01*
G02X236764Y1695629I2002J237D01*
G02X236778Y1695866I2016J0D01*
G01Y1700117D01*
G02X236764Y1700354I2002J237D01*
G02X236778Y1700591I2016J0D01*
G01Y1702994D01*
G02X237080Y1703296I302J0D01*
G37*
G36*
G01X252828D02*
X256528D01*
G02X256830Y1702994I0J-302D01*
G01Y1692988D01*
G02X256528Y1692686I-302J0D01*
G01X252828D01*
G02X252526Y1692988I0J302D01*
G01Y1695392D01*
G02X252512Y1695629I2002J237D01*
G02X252526Y1695866I2016J0D01*
G01Y1700117D01*
G02X252512Y1700354I2002J237D01*
G02X252526Y1700591I2016J0D01*
G01Y1702994D01*
G02X252828Y1703296I302J0D01*
G37*
G36*
G01X268576D02*
X272276D01*
G02X272578Y1702994I0J-302D01*
G01Y1692988D01*
G02X272276Y1692686I-302J0D01*
G01X268576D01*
G02X268274Y1692988I0J302D01*
G01Y1695392D01*
G02X268260Y1695629I2002J237D01*
G02X268274Y1695866I2016J0D01*
G01Y1700117D01*
G02X268260Y1700354I2002J237D01*
G02X268274Y1700591I2016J0D01*
G01Y1702994D01*
G02X268576Y1703296I302J0D01*
G37*
G36*
G01X284324D02*
X288024D01*
G02X288326Y1702994I0J-302D01*
G01Y1692988D01*
G02X288024Y1692686I-302J0D01*
G01X284324D01*
G02X284022Y1692988I0J302D01*
G01Y1695392D01*
G02X284008Y1695629I2002J237D01*
G02X284022Y1695866I2016J0D01*
G01Y1700117D01*
G02X284008Y1700354I2002J237D01*
G02X284022Y1700591I2016J0D01*
G01Y1702994D01*
G02X284324Y1703296I302J0D01*
G37*
G36*
G01X568182D02*
X571882D01*
G02X572184Y1702994I0J-302D01*
G01Y1692988D01*
G02X571882Y1692686I-302J0D01*
G01X568182D01*
G02X567880Y1692988I0J302D01*
G01Y1695019D01*
G02X567789Y1695629I2002J610D01*
G02X568511Y1697211I2094J0D01*
G01X568830Y1697861D01*
G03Y1698123I-267J131D01*
G01X568512Y1698772D01*
G02X567789Y1700354I1369J1582D01*
G02X567880Y1700964I2093J0D01*
G01Y1702994D01*
G02X568182Y1703296I302J0D01*
G37*
G36*
G01X583930D02*
X587630D01*
G02X587932Y1702994I0J-302D01*
G01Y1692988D01*
G02X587630Y1692686I-302J0D01*
G01X583930D01*
G02X583628Y1692988I0J302D01*
G01Y1695019D01*
G02X583537Y1695629I2002J610D01*
G02X584259Y1697211I2094J0D01*
G01X584578Y1697861D01*
G03Y1698123I-267J131D01*
G01X584260Y1698772D01*
G02X583537Y1700354I1369J1582D01*
G02X583628Y1700964I2093J0D01*
G01Y1702994D01*
G02X583930Y1703296I302J0D01*
G37*
G36*
G01X599678D02*
X603378D01*
G02X603680Y1702994I0J-302D01*
G01Y1692988D01*
G02X603378Y1692686I-302J0D01*
G01X599678D01*
G02X599376Y1692988I0J302D01*
G01Y1695019D01*
G02X599285Y1695629I2002J610D01*
G02X600007Y1697211I2094J0D01*
G01X600326Y1697861D01*
G03Y1698123I-267J131D01*
G01X600008Y1698772D01*
G02X599285Y1700354I1369J1582D01*
G02X599376Y1700964I2093J0D01*
G01Y1702994D01*
G02X599678Y1703296I302J0D01*
G37*
G36*
G01X615426D02*
X619126D01*
G02X619428Y1702994I0J-302D01*
G01Y1692988D01*
G02X619126Y1692686I-302J0D01*
G01X615426D01*
G02X615124Y1692988I0J302D01*
G01Y1695019D01*
G02X615033Y1695629I2002J610D01*
G02X615755Y1697211I2094J0D01*
G01X616074Y1697861D01*
G03Y1698123I-267J131D01*
G01X615756Y1698772D01*
G02X615033Y1700354I1369J1582D01*
G02X615124Y1700964I2093J0D01*
G01Y1702994D01*
G02X615426Y1703296I302J0D01*
G37*
G36*
G01X1244954D02*
X1248654D01*
G02X1248956Y1702994I0J-302D01*
G01Y1692988D01*
G02X1248654Y1692686I-302J0D01*
G01X1244954D01*
G02X1244652Y1692988I0J302D01*
G01Y1695392D01*
G02X1244638Y1695629I2002J237D01*
G02X1244652Y1695866I2016J0D01*
G01Y1700117D01*
G02X1244638Y1700354I2002J237D01*
G02X1244652Y1700591I2016J0D01*
G01Y1702994D01*
G02X1244954Y1703296I302J0D01*
G37*
G36*
G01X1260702D02*
X1264402D01*
G02X1264704Y1702994I0J-302D01*
G01Y1692988D01*
G02X1264402Y1692686I-302J0D01*
G01X1260702D01*
G02X1260400Y1692988I0J302D01*
G01Y1695392D01*
G02X1260386Y1695629I2002J237D01*
G02X1260400Y1695866I2016J0D01*
G01Y1700117D01*
G02X1260386Y1700354I2002J237D01*
G02X1260400Y1700591I2016J0D01*
G01Y1702994D01*
G02X1260702Y1703296I302J0D01*
G37*
G36*
G01X1276450D02*
X1280150D01*
G02X1280452Y1702994I0J-302D01*
G01Y1692988D01*
G02X1280150Y1692686I-302J0D01*
G01X1276450D01*
G02X1276148Y1692988I0J302D01*
G01Y1695392D01*
G02X1276134Y1695629I2002J237D01*
G02X1276148Y1695866I2016J0D01*
G01Y1700117D01*
G02X1276134Y1700354I2002J237D01*
G02X1276148Y1700591I2016J0D01*
G01Y1702994D01*
G02X1276450Y1703296I302J0D01*
G37*
G36*
G01X1292198D02*
X1295898D01*
G02X1296200Y1702994I0J-302D01*
G01Y1692988D01*
G02X1295898Y1692686I-302J0D01*
G01X1292198D01*
G02X1291896Y1692988I0J302D01*
G01Y1695392D01*
G02X1291882Y1695629I2002J237D01*
G02X1291896Y1695866I2016J0D01*
G01Y1700117D01*
G02X1291882Y1700354I2002J237D01*
G02X1291896Y1700591I2016J0D01*
G01Y1702994D01*
G02X1292198Y1703296I302J0D01*
G37*
G36*
G01X1576056D02*
X1579756D01*
G02X1580058Y1702994I0J-302D01*
G01Y1692988D01*
G02X1579756Y1692686I-302J0D01*
G01X1576056D01*
G02X1575754Y1692988I0J302D01*
G01Y1695019D01*
G02X1575663Y1695629I2002J610D01*
G02X1576385Y1697211I2094J0D01*
G01X1576704Y1697861D01*
G03Y1698123I-267J131D01*
G01X1576386Y1698772D01*
G02X1575663Y1700354I1369J1582D01*
G02X1575754Y1700964I2093J0D01*
G01Y1702994D01*
G02X1576056Y1703296I302J0D01*
G37*
G36*
G01X1591804D02*
X1595504D01*
G02X1595806Y1702994I0J-302D01*
G01Y1692988D01*
G02X1595504Y1692686I-302J0D01*
G01X1591804D01*
G02X1591502Y1692988I0J302D01*
G01Y1695019D01*
G02X1591411Y1695629I2002J610D01*
G02X1592133Y1697211I2094J0D01*
G01X1592452Y1697861D01*
G03Y1698123I-267J131D01*
G01X1592134Y1698772D01*
G02X1591411Y1700354I1369J1582D01*
G02X1591502Y1700964I2093J0D01*
G01Y1702994D01*
G02X1591804Y1703296I302J0D01*
G37*
G36*
G01X1607552D02*
X1611252D01*
G02X1611554Y1702994I0J-302D01*
G01Y1692988D01*
G02X1611252Y1692686I-302J0D01*
G01X1607552D01*
G02X1607250Y1692988I0J302D01*
G01Y1695019D01*
G02X1607159Y1695629I2002J610D01*
G02X1607881Y1697211I2094J0D01*
G01X1608200Y1697861D01*
G03Y1698123I-267J131D01*
G01X1607882Y1698772D01*
G02X1607159Y1700354I1369J1582D01*
G02X1607250Y1700964I2093J0D01*
G01Y1702994D01*
G02X1607552Y1703296I302J0D01*
G37*
G36*
G01X1623300D02*
X1627000D01*
G02X1627302Y1702994I0J-302D01*
G01Y1692988D01*
G02X1627000Y1692686I-302J0D01*
G01X1623300D01*
G02X1622998Y1692988I0J302D01*
G01Y1695019D01*
G02X1622907Y1695629I2002J610D01*
G02X1623629Y1697211I2094J0D01*
G01X1623948Y1697861D01*
G03Y1698123I-267J131D01*
G01X1623630Y1698772D01*
G02X1622907Y1700354I1369J1582D01*
G02X1622998Y1700964I2093J0D01*
G01Y1702994D01*
G02X1623300Y1703296I302J0D01*
G37*
G36*
G01X304009D02*
X307709D01*
G02X308012Y1702994I1J-302D01*
G01Y1692988D01*
G02X307709Y1692686I-303J1D01*
G01X304009D01*
G02X303706Y1692988I-1J302D01*
G01Y1695400D01*
G02X303693Y1695629I2003J229D01*
G02X303706Y1695858I2016J0D01*
G01Y1700125D01*
G02X303693Y1700354I2003J229D01*
G02X303706Y1700583I2016J0D01*
G01Y1702994D01*
G02X304009Y1703296I303J-1D01*
G37*
G36*
G01X319757D02*
X323457D01*
G02X323760Y1702994I1J-302D01*
G01Y1692988D01*
G02X323457Y1692686I-303J1D01*
G01X319757D01*
G02X319454Y1692988I-1J302D01*
G01Y1695400D01*
G02X319441Y1695629I2003J229D01*
G02X319454Y1695858I2016J0D01*
G01Y1700125D01*
G02X319441Y1700354I2003J229D01*
G02X319454Y1700583I2016J0D01*
G01Y1702994D01*
G02X319757Y1703296I303J-1D01*
G37*
G36*
G01X335505D02*
X339205D01*
G02X339508Y1702994I1J-302D01*
G01Y1692988D01*
G02X339205Y1692686I-303J1D01*
G01X335505D01*
G02X335202Y1692988I-1J302D01*
G01Y1695400D01*
G02X335189Y1695629I2003J229D01*
G02X335202Y1695858I2016J0D01*
G01Y1700125D01*
G02X335189Y1700354I2003J229D01*
G02X335202Y1700583I2016J0D01*
G01Y1702994D01*
G02X335505Y1703296I303J-1D01*
G37*
G36*
G01X351253D02*
X354953D01*
G02X355256Y1702994I1J-302D01*
G01Y1692988D01*
G02X354953Y1692686I-303J1D01*
G01X351253D01*
G02X350950Y1692988I-1J302D01*
G01Y1695400D01*
G02X350937Y1695629I2003J229D01*
G02X350950Y1695858I2016J0D01*
G01Y1700125D01*
G02X350937Y1700354I2003J229D01*
G02X350950Y1700583I2016J0D01*
G01Y1702994D01*
G02X351253Y1703296I303J-1D01*
G37*
G36*
G01X501253D02*
X504953D01*
G02X505256Y1702994I1J-302D01*
G01Y1692988D01*
G02X504953Y1692686I-303J1D01*
G01X501253D01*
G02X500950Y1692988I-1J302D01*
G01Y1695022D01*
G02X500860Y1695629I2002J607D01*
G02X501582Y1697211I2094J0D01*
G01X501901Y1697861D01*
G03Y1698123I-267J131D01*
G01X501583Y1698772D01*
G02X500860Y1700354I1369J1582D01*
G02X500950Y1700961I2092J0D01*
G01Y1702994D01*
G02X501253Y1703296I303J-1D01*
G37*
G36*
G01X517001D02*
X520701D01*
G02X521004Y1702994I1J-302D01*
G01Y1692988D01*
G02X520701Y1692686I-303J1D01*
G01X517001D01*
G02X516698Y1692988I-1J302D01*
G01Y1695022D01*
G02X516608Y1695629I2002J607D01*
G02X517330Y1697211I2094J0D01*
G01X517649Y1697861D01*
G03Y1698123I-267J131D01*
G01X517331Y1698772D01*
G02X516608Y1700354I1369J1582D01*
G02X516698Y1700961I2092J0D01*
G01Y1702994D01*
G02X517001Y1703296I303J-1D01*
G37*
G36*
G01X532749D02*
X536449D01*
G02X536752Y1702994I1J-302D01*
G01Y1692988D01*
G02X536449Y1692686I-303J1D01*
G01X532749D01*
G02X532446Y1692988I-1J302D01*
G01Y1695022D01*
G02X532356Y1695629I2002J607D01*
G02X533078Y1697211I2094J0D01*
G01X533397Y1697861D01*
G03Y1698123I-267J131D01*
G01X533079Y1698772D01*
G02X532356Y1700354I1369J1582D01*
G02X532446Y1700961I2092J0D01*
G01Y1702994D01*
G02X532749Y1703296I303J-1D01*
G37*
G36*
G01X548497D02*
X552197D01*
G02X552500Y1702994I1J-302D01*
G01Y1692988D01*
G02X552197Y1692686I-303J1D01*
G01X548497D01*
G02X548194Y1692988I-1J302D01*
G01Y1695022D01*
G02X548104Y1695629I2002J607D01*
G02X548826Y1697211I2094J0D01*
G01X549145Y1697861D01*
G03Y1698123I-267J131D01*
G01X548827Y1698772D01*
G02X548104Y1700354I1369J1582D01*
G02X548194Y1700961I2092J0D01*
G01Y1702994D01*
G02X548497Y1703296I303J-1D01*
G37*
G36*
G01X1311883D02*
X1315583D01*
G02X1315886Y1702994I1J-302D01*
G01Y1692988D01*
G02X1315583Y1692686I-303J1D01*
G01X1311883D01*
G02X1311580Y1692988I-1J302D01*
G01Y1695400D01*
G02X1311567Y1695629I2003J229D01*
G02X1311580Y1695858I2016J0D01*
G01Y1700125D01*
G02X1311567Y1700354I2003J229D01*
G02X1311580Y1700583I2016J0D01*
G01Y1702994D01*
G02X1311883Y1703296I303J-1D01*
G37*
G36*
G01X1327631D02*
X1331331D01*
G02X1331634Y1702994I1J-302D01*
G01Y1692988D01*
G02X1331331Y1692686I-303J1D01*
G01X1327631D01*
G02X1327328Y1692988I-1J302D01*
G01Y1695400D01*
G02X1327315Y1695629I2003J229D01*
G02X1327328Y1695858I2016J0D01*
G01Y1700125D01*
G02X1327315Y1700354I2003J229D01*
G02X1327328Y1700583I2016J0D01*
G01Y1702994D01*
G02X1327631Y1703296I303J-1D01*
G37*
G36*
G01X1343379D02*
X1347079D01*
G02X1347382Y1702994I1J-302D01*
G01Y1692988D01*
G02X1347079Y1692686I-303J1D01*
G01X1343379D01*
G02X1343076Y1692988I-1J302D01*
G01Y1695400D01*
G02X1343063Y1695629I2003J229D01*
G02X1343076Y1695858I2016J0D01*
G01Y1700125D01*
G02X1343063Y1700354I2003J229D01*
G02X1343076Y1700583I2016J0D01*
G01Y1702994D01*
G02X1343379Y1703296I303J-1D01*
G37*
G36*
G01X1359127D02*
X1362827D01*
G02X1363130Y1702994I1J-302D01*
G01Y1692988D01*
G02X1362827Y1692686I-303J1D01*
G01X1359127D01*
G02X1358824Y1692988I-1J302D01*
G01Y1695400D01*
G02X1358811Y1695629I2003J229D01*
G02X1358824Y1695858I2016J0D01*
G01Y1700125D01*
G02X1358811Y1700354I2003J229D01*
G02X1358824Y1700583I2016J0D01*
G01Y1702994D01*
G02X1359127Y1703296I303J-1D01*
G37*
G36*
G01X1509127D02*
X1512827D01*
G02X1513130Y1702994I1J-302D01*
G01Y1692988D01*
G02X1512827Y1692686I-303J1D01*
G01X1509127D01*
G02X1508824Y1692988I-1J302D01*
G01Y1695022D01*
G02X1508734Y1695629I2002J607D01*
G02X1509456Y1697211I2094J0D01*
G01X1509775Y1697861D01*
G03Y1698123I-267J131D01*
G01X1509457Y1698772D01*
G02X1508734Y1700354I1369J1582D01*
G02X1508824Y1700961I2092J0D01*
G01Y1702994D01*
G02X1509127Y1703296I303J-1D01*
G37*
G36*
G01X1524875D02*
X1528575D01*
G02X1528878Y1702994I1J-302D01*
G01Y1692988D01*
G02X1528575Y1692686I-303J1D01*
G01X1524875D01*
G02X1524572Y1692988I-1J302D01*
G01Y1695022D01*
G02X1524482Y1695629I2002J607D01*
G02X1525204Y1697211I2094J0D01*
G01X1525523Y1697861D01*
G03Y1698123I-267J131D01*
G01X1525205Y1698772D01*
G02X1524482Y1700354I1369J1582D01*
G02X1524572Y1700961I2092J0D01*
G01Y1702994D01*
G02X1524875Y1703296I303J-1D01*
G37*
G36*
G01X1540623D02*
X1544323D01*
G02X1544626Y1702994I1J-302D01*
G01Y1692988D01*
G02X1544323Y1692686I-303J1D01*
G01X1540623D01*
G02X1540320Y1692988I-1J302D01*
G01Y1695022D01*
G02X1540230Y1695629I2002J607D01*
G02X1540952Y1697211I2094J0D01*
G01X1541271Y1697861D01*
G03Y1698123I-267J131D01*
G01X1540953Y1698772D01*
G02X1540230Y1700354I1369J1582D01*
G02X1540320Y1700961I2092J0D01*
G01Y1702994D01*
G02X1540623Y1703296I303J-1D01*
G37*
G36*
G01X1556371D02*
X1560071D01*
G02X1560374Y1702994I1J-302D01*
G01Y1692988D01*
G02X1560071Y1692686I-303J1D01*
G01X1556371D01*
G02X1556068Y1692988I-1J302D01*
G01Y1695022D01*
G02X1555978Y1695629I2002J607D01*
G02X1556700Y1697211I2094J0D01*
G01X1557019Y1697861D01*
G03Y1698123I-267J131D01*
G01X1556701Y1698772D01*
G02X1555978Y1700354I1369J1582D01*
G02X1556068Y1700961I2092J0D01*
G01Y1702994D01*
G02X1556371Y1703296I303J-1D01*
G37*
G36*
G01X229206Y1713532D02*
X232906D01*
G02X233208Y1713230I0J-302D01*
G01Y1703224D01*
G02X232906Y1702922I-302J0D01*
G01X229206D01*
G02X228904Y1703224I0J302D01*
G01Y1705629D01*
G02X228890Y1705866I2002J237D01*
G02X228904Y1706103I2016J0D01*
G01Y1710353D01*
G02X228890Y1710590I2002J237D01*
G02X228904Y1710827I2016J0D01*
G01Y1713230D01*
G02X229206Y1713532I302J0D01*
G37*
G36*
G01X244954D02*
X248654D01*
G02X248956Y1713230I0J-302D01*
G01Y1703224D01*
G02X248654Y1702922I-302J0D01*
G01X244954D01*
G02X244652Y1703224I0J302D01*
G01Y1705629D01*
G02X244638Y1705866I2002J237D01*
G02X244652Y1706103I2016J0D01*
G01Y1710353D01*
G02X244638Y1710590I2002J237D01*
G02X244652Y1710827I2016J0D01*
G01Y1713230D01*
G02X244954Y1713532I302J0D01*
G37*
G36*
G01X260702D02*
X264402D01*
G02X264704Y1713230I0J-302D01*
G01Y1703224D01*
G02X264402Y1702922I-302J0D01*
G01X260702D01*
G02X260400Y1703224I0J302D01*
G01Y1705629D01*
G02X260386Y1705866I2002J237D01*
G02X260400Y1706103I2016J0D01*
G01Y1710353D01*
G02X260386Y1710590I2002J237D01*
G02X260400Y1710827I2016J0D01*
G01Y1713230D01*
G02X260702Y1713532I302J0D01*
G37*
G36*
G01X276450D02*
X280150D01*
G02X280452Y1713230I0J-302D01*
G01Y1703224D01*
G02X280150Y1702922I-302J0D01*
G01X276450D01*
G02X276148Y1703224I0J302D01*
G01Y1705629D01*
G02X276134Y1705866I2002J237D01*
G02X276148Y1706103I2016J0D01*
G01Y1710353D01*
G02X276134Y1710590I2002J237D01*
G02X276148Y1710827I2016J0D01*
G01Y1713230D01*
G02X276450Y1713532I302J0D01*
G37*
G36*
G01X560308D02*
X564008D01*
G02X564310Y1713230I0J-302D01*
G01Y1703224D01*
G02X564008Y1702922I-302J0D01*
G01X560308D01*
G02X560006Y1703224I0J302D01*
G01Y1705629D01*
G02X559992Y1705866I2002J237D01*
G02X560006Y1706103I2016J0D01*
G01Y1710353D01*
G02X559992Y1710590I2002J237D01*
G02X560006Y1710827I2016J0D01*
G01Y1713230D01*
G02X560308Y1713532I302J0D01*
G37*
G36*
G01X576056D02*
X579756D01*
G02X580058Y1713230I0J-302D01*
G01Y1703224D01*
G02X579756Y1702922I-302J0D01*
G01X576056D01*
G02X575754Y1703224I0J302D01*
G01Y1705629D01*
G02X575740Y1705866I2002J237D01*
G02X575754Y1706103I2016J0D01*
G01Y1710353D01*
G02X575740Y1710590I2002J237D01*
G02X575754Y1710827I2016J0D01*
G01Y1713230D01*
G02X576056Y1713532I302J0D01*
G37*
G36*
G01X591804D02*
X595504D01*
G02X595806Y1713230I0J-302D01*
G01Y1703224D01*
G02X595504Y1702922I-302J0D01*
G01X591804D01*
G02X591502Y1703224I0J302D01*
G01Y1705629D01*
G02X591488Y1705866I2002J237D01*
G02X591502Y1706103I2016J0D01*
G01Y1710353D01*
G02X591488Y1710590I2002J237D01*
G02X591502Y1710827I2016J0D01*
G01Y1713230D01*
G02X591804Y1713532I302J0D01*
G37*
G36*
G01X607552D02*
X611252D01*
G02X611554Y1713230I0J-302D01*
G01Y1703224D01*
G02X611252Y1702922I-302J0D01*
G01X607552D01*
G02X607250Y1703224I0J302D01*
G01Y1705629D01*
G02X607236Y1705866I2002J237D01*
G02X607250Y1706103I2016J0D01*
G01Y1710353D01*
G02X607236Y1710590I2002J237D01*
G02X607250Y1710827I2016J0D01*
G01Y1713230D01*
G02X607552Y1713532I302J0D01*
G37*
G36*
G01X1237080D02*
X1240780D01*
G02X1241082Y1713230I0J-302D01*
G01Y1703224D01*
G02X1240780Y1702922I-302J0D01*
G01X1237080D01*
G02X1236778Y1703224I0J302D01*
G01Y1705629D01*
G02X1236764Y1705866I2002J237D01*
G02X1236778Y1706103I2016J0D01*
G01Y1710353D01*
G02X1236764Y1710590I2002J237D01*
G02X1236778Y1710827I2016J0D01*
G01Y1713230D01*
G02X1237080Y1713532I302J0D01*
G37*
G36*
G01X1252828D02*
X1256528D01*
G02X1256830Y1713230I0J-302D01*
G01Y1703224D01*
G02X1256528Y1702922I-302J0D01*
G01X1252828D01*
G02X1252526Y1703224I0J302D01*
G01Y1705629D01*
G02X1252512Y1705866I2002J237D01*
G02X1252526Y1706103I2016J0D01*
G01Y1710353D01*
G02X1252512Y1710590I2002J237D01*
G02X1252526Y1710827I2016J0D01*
G01Y1713230D01*
G02X1252828Y1713532I302J0D01*
G37*
G36*
G01X1268576D02*
X1272276D01*
G02X1272578Y1713230I0J-302D01*
G01Y1703224D01*
G02X1272276Y1702922I-302J0D01*
G01X1268576D01*
G02X1268274Y1703224I0J302D01*
G01Y1705629D01*
G02X1268260Y1705866I2002J237D01*
G02X1268274Y1706103I2016J0D01*
G01Y1710353D01*
G02X1268260Y1710590I2002J237D01*
G02X1268274Y1710827I2016J0D01*
G01Y1713230D01*
G02X1268576Y1713532I302J0D01*
G37*
G36*
G01X1284324D02*
X1288024D01*
G02X1288326Y1713230I0J-302D01*
G01Y1703224D01*
G02X1288024Y1702922I-302J0D01*
G01X1284324D01*
G02X1284022Y1703224I0J302D01*
G01Y1705629D01*
G02X1284008Y1705866I2002J237D01*
G02X1284022Y1706103I2016J0D01*
G01Y1710353D01*
G02X1284008Y1710590I2002J237D01*
G02X1284022Y1710827I2016J0D01*
G01Y1713230D01*
G02X1284324Y1713532I302J0D01*
G37*
G36*
G01X1568182D02*
X1571882D01*
G02X1572184Y1713230I0J-302D01*
G01Y1703224D01*
G02X1571882Y1702922I-302J0D01*
G01X1568182D01*
G02X1567880Y1703224I0J302D01*
G01Y1705629D01*
G02X1567866Y1705866I2002J237D01*
G02X1567880Y1706103I2016J0D01*
G01Y1710353D01*
G02X1567866Y1710590I2002J237D01*
G02X1567880Y1710827I2016J0D01*
G01Y1713230D01*
G02X1568182Y1713532I302J0D01*
G37*
G36*
G01X1583930D02*
X1587630D01*
G02X1587932Y1713230I0J-302D01*
G01Y1703224D01*
G02X1587630Y1702922I-302J0D01*
G01X1583930D01*
G02X1583628Y1703224I0J302D01*
G01Y1705629D01*
G02X1583614Y1705866I2002J237D01*
G02X1583628Y1706103I2016J0D01*
G01Y1710353D01*
G02X1583614Y1710590I2002J237D01*
G02X1583628Y1710827I2016J0D01*
G01Y1713230D01*
G02X1583930Y1713532I302J0D01*
G37*
G36*
G01X1599678D02*
X1603378D01*
G02X1603680Y1713230I0J-302D01*
G01Y1703224D01*
G02X1603378Y1702922I-302J0D01*
G01X1599678D01*
G02X1599376Y1703224I0J302D01*
G01Y1705629D01*
G02X1599362Y1705866I2002J237D01*
G02X1599376Y1706103I2016J0D01*
G01Y1710353D01*
G02X1599362Y1710590I2002J237D01*
G02X1599376Y1710827I2016J0D01*
G01Y1713230D01*
G02X1599678Y1713532I302J0D01*
G37*
G36*
G01X1615426D02*
X1619126D01*
G02X1619428Y1713230I0J-302D01*
G01Y1703224D01*
G02X1619126Y1702922I-302J0D01*
G01X1615426D01*
G02X1615124Y1703224I0J302D01*
G01Y1705629D01*
G02X1615110Y1705866I2002J237D01*
G02X1615124Y1706103I2016J0D01*
G01Y1710353D01*
G02X1615110Y1710590I2002J237D01*
G02X1615124Y1710827I2016J0D01*
G01Y1713230D01*
G02X1615426Y1713532I302J0D01*
G37*
G36*
G01X296135D02*
X299835D01*
G02X300138Y1713230I1J-302D01*
G01Y1703224D01*
G02X299835Y1702922I-303J1D01*
G01X296135D01*
G02X295832Y1703224I-1J302D01*
G01Y1705637D01*
G02X295819Y1705866I2003J229D01*
G02X295832Y1706095I2016J0D01*
G01Y1710361D01*
G02X295819Y1710590I2003J229D01*
G02X295832Y1710819I2016J0D01*
G01Y1713230D01*
G02X296135Y1713532I303J-1D01*
G37*
G36*
G01X311883D02*
X315583D01*
G02X315886Y1713230I1J-302D01*
G01Y1703224D01*
G02X315583Y1702922I-303J1D01*
G01X311883D01*
G02X311580Y1703224I-1J302D01*
G01Y1705637D01*
G02X311567Y1705866I2003J229D01*
G02X311580Y1706095I2016J0D01*
G01Y1710361D01*
G02X311567Y1710590I2003J229D01*
G02X311580Y1710819I2016J0D01*
G01Y1713230D01*
G02X311883Y1713532I303J-1D01*
G37*
G36*
G01X327631D02*
X331331D01*
G02X331634Y1713230I1J-302D01*
G01Y1703224D01*
G02X331331Y1702922I-303J1D01*
G01X327631D01*
G02X327328Y1703224I-1J302D01*
G01Y1705637D01*
G02X327315Y1705866I2003J229D01*
G02X327328Y1706095I2016J0D01*
G01Y1710361D01*
G02X327315Y1710590I2003J229D01*
G02X327328Y1710819I2016J0D01*
G01Y1713230D01*
G02X327631Y1713532I303J-1D01*
G37*
G36*
G01X343379D02*
X347079D01*
G02X347382Y1713230I1J-302D01*
G01Y1703224D01*
G02X347079Y1702922I-303J1D01*
G01X343379D01*
G02X343076Y1703224I-1J302D01*
G01Y1705637D01*
G02X343063Y1705866I2003J229D01*
G02X343076Y1706095I2016J0D01*
G01Y1710361D01*
G02X343063Y1710590I2003J229D01*
G02X343076Y1710819I2016J0D01*
G01Y1713230D01*
G02X343379Y1713532I303J-1D01*
G37*
G36*
G01X493379D02*
X497079D01*
G02X497382Y1713230I1J-302D01*
G01Y1703224D01*
G02X497079Y1702922I-303J1D01*
G01X493379D01*
G02X493076Y1703224I-1J302D01*
G01Y1705637D01*
G02X493063Y1705866I2003J229D01*
G02X493076Y1706095I2016J0D01*
G01Y1710361D01*
G02X493063Y1710590I2003J229D01*
G02X493076Y1710819I2016J0D01*
G01Y1713230D01*
G02X493379Y1713532I303J-1D01*
G37*
G36*
G01X509127D02*
X512827D01*
G02X513130Y1713230I1J-302D01*
G01Y1703224D01*
G02X512827Y1702922I-303J1D01*
G01X509127D01*
G02X508824Y1703224I-1J302D01*
G01Y1705637D01*
G02X508811Y1705866I2003J229D01*
G02X508824Y1706095I2016J0D01*
G01Y1710361D01*
G02X508811Y1710590I2003J229D01*
G02X508824Y1710819I2016J0D01*
G01Y1713230D01*
G02X509127Y1713532I303J-1D01*
G37*
G36*
G01X524875D02*
X528575D01*
G02X528878Y1713230I1J-302D01*
G01Y1703224D01*
G02X528575Y1702922I-303J1D01*
G01X524875D01*
G02X524572Y1703224I-1J302D01*
G01Y1705637D01*
G02X524559Y1705866I2003J229D01*
G02X524572Y1706095I2016J0D01*
G01Y1710361D01*
G02X524559Y1710590I2003J229D01*
G02X524572Y1710819I2016J0D01*
G01Y1713230D01*
G02X524875Y1713532I303J-1D01*
G37*
G36*
G01X540623D02*
X544323D01*
G02X544626Y1713230I1J-302D01*
G01Y1703224D01*
G02X544323Y1702922I-303J1D01*
G01X540623D01*
G02X540320Y1703224I-1J302D01*
G01Y1705637D01*
G02X540307Y1705866I2003J229D01*
G02X540320Y1706095I2016J0D01*
G01Y1710361D01*
G02X540307Y1710590I2003J229D01*
G02X540320Y1710819I2016J0D01*
G01Y1713230D01*
G02X540623Y1713532I303J-1D01*
G37*
G36*
G01X1304009D02*
X1307709D01*
G02X1308012Y1713230I1J-302D01*
G01Y1703224D01*
G02X1307709Y1702922I-303J1D01*
G01X1304009D01*
G02X1303706Y1703224I-1J302D01*
G01Y1705637D01*
G02X1303693Y1705866I2003J229D01*
G02X1303706Y1706095I2016J0D01*
G01Y1710361D01*
G02X1303693Y1710590I2003J229D01*
G02X1303706Y1710819I2016J0D01*
G01Y1713230D01*
G02X1304009Y1713532I303J-1D01*
G37*
G36*
G01X1319757D02*
X1323457D01*
G02X1323760Y1713230I1J-302D01*
G01Y1703224D01*
G02X1323457Y1702922I-303J1D01*
G01X1319757D01*
G02X1319454Y1703224I-1J302D01*
G01Y1705637D01*
G02X1319441Y1705866I2003J229D01*
G02X1319454Y1706095I2016J0D01*
G01Y1710361D01*
G02X1319441Y1710590I2003J229D01*
G02X1319454Y1710819I2016J0D01*
G01Y1713230D01*
G02X1319757Y1713532I303J-1D01*
G37*
G36*
G01X1335505D02*
X1339205D01*
G02X1339508Y1713230I1J-302D01*
G01Y1703224D01*
G02X1339205Y1702922I-303J1D01*
G01X1335505D01*
G02X1335202Y1703224I-1J302D01*
G01Y1705637D01*
G02X1335189Y1705866I2003J229D01*
G02X1335202Y1706095I2016J0D01*
G01Y1710361D01*
G02X1335189Y1710590I2003J229D01*
G02X1335202Y1710819I2016J0D01*
G01Y1713230D01*
G02X1335505Y1713532I303J-1D01*
G37*
G36*
G01X1351253D02*
X1354953D01*
G02X1355256Y1713230I1J-302D01*
G01Y1703224D01*
G02X1354953Y1702922I-303J1D01*
G01X1351253D01*
G02X1350950Y1703224I-1J302D01*
G01Y1705637D01*
G02X1350937Y1705866I2003J229D01*
G02X1350950Y1706095I2016J0D01*
G01Y1710361D01*
G02X1350937Y1710590I2003J229D01*
G02X1350950Y1710819I2016J0D01*
G01Y1713230D01*
G02X1351253Y1713532I303J-1D01*
G37*
G36*
G01X1501253D02*
X1504953D01*
G02X1505256Y1713230I1J-302D01*
G01Y1703224D01*
G02X1504953Y1702922I-303J1D01*
G01X1501253D01*
G02X1500950Y1703224I-1J302D01*
G01Y1705637D01*
G02X1500937Y1705866I2003J229D01*
G02X1500950Y1706095I2016J0D01*
G01Y1710361D01*
G02X1500937Y1710590I2003J229D01*
G02X1500950Y1710819I2016J0D01*
G01Y1713230D01*
G02X1501253Y1713532I303J-1D01*
G37*
G36*
G01X1517001D02*
X1520701D01*
G02X1521004Y1713230I1J-302D01*
G01Y1703224D01*
G02X1520701Y1702922I-303J1D01*
G01X1517001D01*
G02X1516698Y1703224I-1J302D01*
G01Y1705637D01*
G02X1516685Y1705866I2003J229D01*
G02X1516698Y1706095I2016J0D01*
G01Y1710361D01*
G02X1516685Y1710590I2003J229D01*
G02X1516698Y1710819I2016J0D01*
G01Y1713230D01*
G02X1517001Y1713532I303J-1D01*
G37*
G36*
G01X1532749D02*
X1536449D01*
G02X1536752Y1713230I1J-302D01*
G01Y1703224D01*
G02X1536449Y1702922I-303J1D01*
G01X1532749D01*
G02X1532446Y1703224I-1J302D01*
G01Y1705637D01*
G02X1532433Y1705866I2003J229D01*
G02X1532446Y1706095I2016J0D01*
G01Y1710361D01*
G02X1532433Y1710590I2003J229D01*
G02X1532446Y1710819I2016J0D01*
G01Y1713230D01*
G02X1532749Y1713532I303J-1D01*
G37*
G36*
G01X1548497D02*
X1552197D01*
G02X1552500Y1713230I1J-302D01*
G01Y1703224D01*
G02X1552197Y1702922I-303J1D01*
G01X1548497D01*
G02X1548194Y1703224I-1J302D01*
G01Y1705637D01*
G02X1548181Y1705866I2003J229D01*
G02X1548194Y1706095I2016J0D01*
G01Y1710361D01*
G02X1548181Y1710590I2003J229D01*
G02X1548194Y1710819I2016J0D01*
G01Y1713230D01*
G02X1548497Y1713532I303J-1D01*
G37*
G36*
G01X237080Y1717470D02*
X240780D01*
G02X241082Y1717167I-1J-303D01*
G01Y1707161D01*
G02X240780Y1706858I-302J-1D01*
G01X237080D01*
G02X236778Y1707161I1J303D01*
G01Y1709566D01*
G02X236764Y1709803I2002J237D01*
G02X236778Y1710040I2016J0D01*
G01Y1714290D01*
G02X236764Y1714527I2002J237D01*
G02X236778Y1714764I2016J0D01*
G01Y1717167D01*
G02X237080Y1717470I302J1D01*
G37*
G36*
G01X252828D02*
X256528D01*
G02X256830Y1717167I-1J-303D01*
G01Y1707161D01*
G02X256528Y1706858I-302J-1D01*
G01X252828D01*
G02X252526Y1707161I1J303D01*
G01Y1709566D01*
G02X252512Y1709803I2002J237D01*
G02X252526Y1710040I2016J0D01*
G01Y1714290D01*
G02X252512Y1714527I2002J237D01*
G02X252526Y1714764I2016J0D01*
G01Y1717167D01*
G02X252828Y1717470I302J1D01*
G37*
G36*
G01X268576D02*
X272276D01*
G02X272578Y1717167I-1J-303D01*
G01Y1707161D01*
G02X272276Y1706858I-302J-1D01*
G01X268576D01*
G02X268274Y1707161I1J303D01*
G01Y1709566D01*
G02X268260Y1709803I2002J237D01*
G02X268274Y1710040I2016J0D01*
G01Y1714290D01*
G02X268260Y1714527I2002J237D01*
G02X268274Y1714764I2016J0D01*
G01Y1717167D01*
G02X268576Y1717470I302J1D01*
G37*
G36*
G01X284324D02*
X288024D01*
G02X288326Y1717167I-1J-303D01*
G01Y1707161D01*
G02X288024Y1706858I-302J-1D01*
G01X284324D01*
G02X284022Y1707161I1J303D01*
G01Y1709566D01*
G02X284008Y1709803I2002J237D01*
G02X284022Y1710040I2016J0D01*
G01Y1714290D01*
G02X284008Y1714527I2002J237D01*
G02X284022Y1714764I2016J0D01*
G01Y1717167D01*
G02X284324Y1717470I302J1D01*
G37*
G36*
G01X304009D02*
X307709D01*
G02X308012Y1717167I0J-303D01*
G01Y1707161D01*
G02X307709Y1706858I-303J0D01*
G01X304009D01*
G02X303706Y1707161I0J303D01*
G01Y1709574D01*
G02X303693Y1709803I2003J229D01*
G02X303706Y1710032I2016J0D01*
G01Y1714298D01*
G02X303693Y1714527I2003J229D01*
G02X303706Y1714756I2016J0D01*
G01Y1717167D01*
G02X304009Y1717470I303J0D01*
G37*
G36*
G01X319757D02*
X323457D01*
G02X323760Y1717167I0J-303D01*
G01Y1707161D01*
G02X323457Y1706858I-303J0D01*
G01X319757D01*
G02X319454Y1707161I0J303D01*
G01Y1709574D01*
G02X319441Y1709803I2003J229D01*
G02X319454Y1710032I2016J0D01*
G01Y1714298D01*
G02X319441Y1714527I2003J229D01*
G02X319454Y1714756I2016J0D01*
G01Y1717167D01*
G02X319757Y1717470I303J0D01*
G37*
G36*
G01X335505D02*
X339205D01*
G02X339508Y1717167I0J-303D01*
G01Y1707161D01*
G02X339205Y1706858I-303J0D01*
G01X335505D01*
G02X335202Y1707161I0J303D01*
G01Y1709574D01*
G02X335189Y1709803I2003J229D01*
G02X335202Y1710032I2016J0D01*
G01Y1714298D01*
G02X335189Y1714527I2003J229D01*
G02X335202Y1714756I2016J0D01*
G01Y1717167D01*
G02X335505Y1717470I303J0D01*
G37*
G36*
G01X351253D02*
X354953D01*
G02X355256Y1717167I0J-303D01*
G01Y1707161D01*
G02X354953Y1706858I-303J0D01*
G01X351253D01*
G02X350950Y1707161I0J303D01*
G01Y1709574D01*
G02X350937Y1709803I2003J229D01*
G02X350950Y1710032I2016J0D01*
G01Y1714298D01*
G02X350937Y1714527I2003J229D01*
G02X350950Y1714756I2016J0D01*
G01Y1717167D01*
G02X351253Y1717470I303J0D01*
G37*
G36*
G01X501253D02*
X504953D01*
G02X505256Y1717167I0J-303D01*
G01Y1707161D01*
G02X504953Y1706858I-303J0D01*
G01X501253D01*
G02X500950Y1707161I0J303D01*
G01Y1709574D01*
G02X500937Y1709803I2003J229D01*
G02X500950Y1710032I2016J0D01*
G01Y1714298D01*
G02X500937Y1714527I2003J229D01*
G02X500950Y1714756I2016J0D01*
G01Y1717167D01*
G02X501253Y1717470I303J0D01*
G37*
G36*
G01X517001D02*
X520701D01*
G02X521004Y1717167I0J-303D01*
G01Y1707161D01*
G02X520701Y1706858I-303J0D01*
G01X517001D01*
G02X516698Y1707161I0J303D01*
G01Y1709574D01*
G02X516685Y1709803I2003J229D01*
G02X516698Y1710032I2016J0D01*
G01Y1714298D01*
G02X516685Y1714527I2003J229D01*
G02X516698Y1714756I2016J0D01*
G01Y1717167D01*
G02X517001Y1717470I303J0D01*
G37*
G36*
G01X532749D02*
X536449D01*
G02X536752Y1717167I0J-303D01*
G01Y1707161D01*
G02X536449Y1706858I-303J0D01*
G01X532749D01*
G02X532446Y1707161I0J303D01*
G01Y1709574D01*
G02X532433Y1709803I2003J229D01*
G02X532446Y1710032I2016J0D01*
G01Y1714298D01*
G02X532433Y1714527I2003J229D01*
G02X532446Y1714756I2016J0D01*
G01Y1717167D01*
G02X532749Y1717470I303J0D01*
G37*
G36*
G01X548497D02*
X552197D01*
G02X552500Y1717167I0J-303D01*
G01Y1707161D01*
G02X552197Y1706858I-303J0D01*
G01X548497D01*
G02X548194Y1707161I0J303D01*
G01Y1709574D01*
G02X548181Y1709803I2003J229D01*
G02X548194Y1710032I2016J0D01*
G01Y1714298D01*
G02X548181Y1714527I2003J229D01*
G02X548194Y1714756I2016J0D01*
G01Y1717167D01*
G02X548497Y1717470I303J0D01*
G37*
G36*
G01X568182D02*
X571882D01*
G02X572184Y1717167I-1J-303D01*
G01Y1707161D01*
G02X571882Y1706858I-302J-1D01*
G01X568182D01*
G02X567880Y1707161I1J303D01*
G01Y1709566D01*
G02X567866Y1709803I2002J237D01*
G02X567880Y1710040I2016J0D01*
G01Y1714290D01*
G02X567866Y1714527I2002J237D01*
G02X567880Y1714764I2016J0D01*
G01Y1717167D01*
G02X568182Y1717470I302J1D01*
G37*
G36*
G01X583930D02*
X587630D01*
G02X587932Y1717167I-1J-303D01*
G01Y1707161D01*
G02X587630Y1706858I-302J-1D01*
G01X583930D01*
G02X583628Y1707161I1J303D01*
G01Y1709566D01*
G02X583614Y1709803I2002J237D01*
G02X583628Y1710040I2016J0D01*
G01Y1714290D01*
G02X583614Y1714527I2002J237D01*
G02X583628Y1714764I2016J0D01*
G01Y1717167D01*
G02X583930Y1717470I302J1D01*
G37*
G36*
G01X599678D02*
X603378D01*
G02X603680Y1717167I-1J-303D01*
G01Y1707161D01*
G02X603378Y1706858I-302J-1D01*
G01X599678D01*
G02X599376Y1707161I1J303D01*
G01Y1709566D01*
G02X599362Y1709803I2002J237D01*
G02X599376Y1710040I2016J0D01*
G01Y1714290D01*
G02X599362Y1714527I2002J237D01*
G02X599376Y1714764I2016J0D01*
G01Y1717167D01*
G02X599678Y1717470I302J1D01*
G37*
G36*
G01X615426D02*
X619126D01*
G02X619428Y1717167I-1J-303D01*
G01Y1707161D01*
G02X619126Y1706858I-302J-1D01*
G01X615426D01*
G02X615124Y1707161I1J303D01*
G01Y1709566D01*
G02X615110Y1709803I2002J237D01*
G02X615124Y1710040I2016J0D01*
G01Y1714290D01*
G02X615110Y1714527I2002J237D01*
G02X615124Y1714764I2016J0D01*
G01Y1717167D01*
G02X615426Y1717470I302J1D01*
G37*
G36*
G01X1244954D02*
X1248654D01*
G02X1248956Y1717167I-1J-303D01*
G01Y1707161D01*
G02X1248654Y1706858I-302J-1D01*
G01X1244954D01*
G02X1244652Y1707161I1J303D01*
G01Y1709566D01*
G02X1244638Y1709803I2002J237D01*
G02X1244652Y1710040I2016J0D01*
G01Y1714290D01*
G02X1244638Y1714527I2002J237D01*
G02X1244652Y1714764I2016J0D01*
G01Y1717167D01*
G02X1244954Y1717470I302J1D01*
G37*
G36*
G01X1260702D02*
X1264402D01*
G02X1264704Y1717167I-1J-303D01*
G01Y1707161D01*
G02X1264402Y1706858I-302J-1D01*
G01X1260702D01*
G02X1260400Y1707161I1J303D01*
G01Y1709566D01*
G02X1260386Y1709803I2002J237D01*
G02X1260400Y1710040I2016J0D01*
G01Y1714290D01*
G02X1260386Y1714527I2002J237D01*
G02X1260400Y1714764I2016J0D01*
G01Y1717167D01*
G02X1260702Y1717470I302J1D01*
G37*
G36*
G01X1276450D02*
X1280150D01*
G02X1280452Y1717167I-1J-303D01*
G01Y1707161D01*
G02X1280150Y1706858I-302J-1D01*
G01X1276450D01*
G02X1276148Y1707161I1J303D01*
G01Y1709566D01*
G02X1276134Y1709803I2002J237D01*
G02X1276148Y1710040I2016J0D01*
G01Y1714290D01*
G02X1276134Y1714527I2002J237D01*
G02X1276148Y1714764I2016J0D01*
G01Y1717167D01*
G02X1276450Y1717470I302J1D01*
G37*
G36*
G01X1292198D02*
X1295898D01*
G02X1296200Y1717167I-1J-303D01*
G01Y1707161D01*
G02X1295898Y1706858I-302J-1D01*
G01X1292198D01*
G02X1291896Y1707161I1J303D01*
G01Y1709566D01*
G02X1291882Y1709803I2002J237D01*
G02X1291896Y1710040I2016J0D01*
G01Y1714290D01*
G02X1291882Y1714527I2002J237D01*
G02X1291896Y1714764I2016J0D01*
G01Y1717167D01*
G02X1292198Y1717470I302J1D01*
G37*
G36*
G01X1311883D02*
X1315583D01*
G02X1315886Y1717167I0J-303D01*
G01Y1707161D01*
G02X1315583Y1706858I-303J0D01*
G01X1311883D01*
G02X1311580Y1707161I0J303D01*
G01Y1709574D01*
G02X1311567Y1709803I2003J229D01*
G02X1311580Y1710032I2016J0D01*
G01Y1714298D01*
G02X1311567Y1714527I2003J229D01*
G02X1311580Y1714756I2016J0D01*
G01Y1717167D01*
G02X1311883Y1717470I303J0D01*
G37*
G36*
G01X1327631D02*
X1331331D01*
G02X1331634Y1717167I0J-303D01*
G01Y1707161D01*
G02X1331331Y1706858I-303J0D01*
G01X1327631D01*
G02X1327328Y1707161I0J303D01*
G01Y1709574D01*
G02X1327315Y1709803I2003J229D01*
G02X1327328Y1710032I2016J0D01*
G01Y1714298D01*
G02X1327315Y1714527I2003J229D01*
G02X1327328Y1714756I2016J0D01*
G01Y1717167D01*
G02X1327631Y1717470I303J0D01*
G37*
G36*
G01X1343379D02*
X1347079D01*
G02X1347382Y1717167I0J-303D01*
G01Y1707161D01*
G02X1347079Y1706858I-303J0D01*
G01X1343379D01*
G02X1343076Y1707161I0J303D01*
G01Y1709574D01*
G02X1343063Y1709803I2003J229D01*
G02X1343076Y1710032I2016J0D01*
G01Y1714298D01*
G02X1343063Y1714527I2003J229D01*
G02X1343076Y1714756I2016J0D01*
G01Y1717167D01*
G02X1343379Y1717470I303J0D01*
G37*
G36*
G01X1359127D02*
X1362827D01*
G02X1363130Y1717167I0J-303D01*
G01Y1707161D01*
G02X1362827Y1706858I-303J0D01*
G01X1359127D01*
G02X1358824Y1707161I0J303D01*
G01Y1709574D01*
G02X1358811Y1709803I2003J229D01*
G02X1358824Y1710032I2016J0D01*
G01Y1714298D01*
G02X1358811Y1714527I2003J229D01*
G02X1358824Y1714756I2016J0D01*
G01Y1717167D01*
G02X1359127Y1717470I303J0D01*
G37*
G36*
G01X1509127D02*
X1512827D01*
G02X1513130Y1717167I0J-303D01*
G01Y1707161D01*
G02X1512827Y1706858I-303J0D01*
G01X1509127D01*
G02X1508824Y1707161I0J303D01*
G01Y1709574D01*
G02X1508811Y1709803I2003J229D01*
G02X1508824Y1710032I2016J0D01*
G01Y1714298D01*
G02X1508811Y1714527I2003J229D01*
G02X1508824Y1714756I2016J0D01*
G01Y1717167D01*
G02X1509127Y1717470I303J0D01*
G37*
G36*
G01X1524875D02*
X1528575D01*
G02X1528878Y1717167I0J-303D01*
G01Y1707161D01*
G02X1528575Y1706858I-303J0D01*
G01X1524875D01*
G02X1524572Y1707161I0J303D01*
G01Y1709574D01*
G02X1524559Y1709803I2003J229D01*
G02X1524572Y1710032I2016J0D01*
G01Y1714298D01*
G02X1524559Y1714527I2003J229D01*
G02X1524572Y1714756I2016J0D01*
G01Y1717167D01*
G02X1524875Y1717470I303J0D01*
G37*
G36*
G01X1540623D02*
X1544323D01*
G02X1544626Y1717167I0J-303D01*
G01Y1707161D01*
G02X1544323Y1706858I-303J0D01*
G01X1540623D01*
G02X1540320Y1707161I0J303D01*
G01Y1709574D01*
G02X1540307Y1709803I2003J229D01*
G02X1540320Y1710032I2016J0D01*
G01Y1714298D01*
G02X1540307Y1714527I2003J229D01*
G02X1540320Y1714756I2016J0D01*
G01Y1717167D01*
G02X1540623Y1717470I303J0D01*
G37*
G36*
G01X1556371D02*
X1560071D01*
G02X1560374Y1717167I0J-303D01*
G01Y1707161D01*
G02X1560071Y1706858I-303J0D01*
G01X1556371D01*
G02X1556068Y1707161I0J303D01*
G01Y1709574D01*
G02X1556055Y1709803I2003J229D01*
G02X1556068Y1710032I2016J0D01*
G01Y1714298D01*
G02X1556055Y1714527I2003J229D01*
G02X1556068Y1714756I2016J0D01*
G01Y1717167D01*
G02X1556371Y1717470I303J0D01*
G37*
G36*
G01X1576056D02*
X1579756D01*
G02X1580058Y1717167I-1J-303D01*
G01Y1707161D01*
G02X1579756Y1706858I-302J-1D01*
G01X1576056D01*
G02X1575754Y1707161I1J303D01*
G01Y1709566D01*
G02X1575740Y1709803I2002J237D01*
G02X1575754Y1710040I2016J0D01*
G01Y1714290D01*
G02X1575740Y1714527I2002J237D01*
G02X1575754Y1714764I2016J0D01*
G01Y1717167D01*
G02X1576056Y1717470I302J1D01*
G37*
G36*
G01X1591804D02*
X1595504D01*
G02X1595806Y1717167I-1J-303D01*
G01Y1707161D01*
G02X1595504Y1706858I-302J-1D01*
G01X1591804D01*
G02X1591502Y1707161I1J303D01*
G01Y1709566D01*
G02X1591488Y1709803I2002J237D01*
G02X1591502Y1710040I2016J0D01*
G01Y1714290D01*
G02X1591488Y1714527I2002J237D01*
G02X1591502Y1714764I2016J0D01*
G01Y1717167D01*
G02X1591804Y1717470I302J1D01*
G37*
G36*
G01X1607552D02*
X1611252D01*
G02X1611554Y1717167I-1J-303D01*
G01Y1707161D01*
G02X1611252Y1706858I-302J-1D01*
G01X1607552D01*
G02X1607250Y1707161I1J303D01*
G01Y1709566D01*
G02X1607236Y1709803I2002J237D01*
G02X1607250Y1710040I2016J0D01*
G01Y1714290D01*
G02X1607236Y1714527I2002J237D01*
G02X1607250Y1714764I2016J0D01*
G01Y1717167D01*
G02X1607552Y1717470I302J1D01*
G37*
G36*
G01X1623300D02*
X1627000D01*
G02X1627302Y1717167I-1J-303D01*
G01Y1707161D01*
G02X1627000Y1706858I-302J-1D01*
G01X1623300D01*
G02X1622998Y1707161I1J303D01*
G01Y1709566D01*
G02X1622984Y1709803I2002J237D01*
G02X1622998Y1710040I2016J0D01*
G01Y1714290D01*
G02X1622984Y1714527I2002J237D01*
G02X1622998Y1714764I2016J0D01*
G01Y1717167D01*
G02X1623300Y1717470I302J1D01*
G37*
G36*
G01X229206Y1727706D02*
X232906D01*
G02X233208Y1727404I0J-302D01*
G01Y1717398D01*
G02X232906Y1717096I-302J0D01*
G01X229206D01*
G02X228904Y1717398I0J302D01*
G01Y1719802D01*
G02X228890Y1720039I2002J237D01*
G02X228904Y1720276I2016J0D01*
G01Y1724526D01*
G02X228890Y1724763I2002J237D01*
G02X228904Y1725000I2016J0D01*
G01Y1727404D01*
G02X229206Y1727706I302J0D01*
G37*
G36*
G01X244954D02*
X248654D01*
G02X248956Y1727404I0J-302D01*
G01Y1717398D01*
G02X248654Y1717096I-302J0D01*
G01X244954D01*
G02X244652Y1717398I0J302D01*
G01Y1719802D01*
G02X244638Y1720039I2002J237D01*
G02X244652Y1720276I2016J0D01*
G01Y1724526D01*
G02X244638Y1724763I2002J237D01*
G02X244652Y1725000I2016J0D01*
G01Y1727404D01*
G02X244954Y1727706I302J0D01*
G37*
G36*
G01X260702D02*
X264402D01*
G02X264704Y1727404I0J-302D01*
G01Y1717398D01*
G02X264402Y1717096I-302J0D01*
G01X260702D01*
G02X260400Y1717398I0J302D01*
G01Y1719802D01*
G02X260386Y1720039I2002J237D01*
G02X260400Y1720276I2016J0D01*
G01Y1724526D01*
G02X260386Y1724763I2002J237D01*
G02X260400Y1725000I2016J0D01*
G01Y1727404D01*
G02X260702Y1727706I302J0D01*
G37*
G36*
G01X276450D02*
X280150D01*
G02X280452Y1727404I0J-302D01*
G01Y1717398D01*
G02X280150Y1717096I-302J0D01*
G01X276450D01*
G02X276148Y1717398I0J302D01*
G01Y1719802D01*
G02X276134Y1720039I2002J237D01*
G02X276148Y1720276I2016J0D01*
G01Y1724526D01*
G02X276134Y1724763I2002J237D01*
G02X276148Y1725000I2016J0D01*
G01Y1727404D01*
G02X276450Y1727706I302J0D01*
G37*
G36*
G01X493379D02*
X497079D01*
G02X497382Y1727403I0J-303D01*
G01Y1717397D01*
G02X497079Y1717094I-303J0D01*
G01X493379D01*
G02X493076Y1717397I0J303D01*
G01Y1719810D01*
G02X493063Y1720039I2003J229D01*
G02X493076Y1720268I2016J0D01*
G01Y1724534D01*
G02X493063Y1724763I2003J229D01*
G02X493076Y1724992I2016J0D01*
G01Y1727403D01*
G02X493379Y1727706I303J0D01*
G37*
G36*
G01X509127D02*
X512827D01*
G02X513130Y1727403I0J-303D01*
G01Y1717397D01*
G02X512827Y1717094I-303J0D01*
G01X509127D01*
G02X508824Y1717397I0J303D01*
G01Y1719810D01*
G02X508811Y1720039I2003J229D01*
G02X508824Y1720268I2016J0D01*
G01Y1724534D01*
G02X508811Y1724763I2003J229D01*
G02X508824Y1724992I2016J0D01*
G01Y1727403D01*
G02X509127Y1727706I303J0D01*
G37*
G36*
G01X524875D02*
X528575D01*
G02X528878Y1727403I0J-303D01*
G01Y1717397D01*
G02X528575Y1717094I-303J0D01*
G01X524875D01*
G02X524572Y1717397I0J303D01*
G01Y1719810D01*
G02X524559Y1720039I2003J229D01*
G02X524572Y1720268I2016J0D01*
G01Y1724534D01*
G02X524559Y1724763I2003J229D01*
G02X524572Y1724992I2016J0D01*
G01Y1727403D01*
G02X524875Y1727706I303J0D01*
G37*
G36*
G01X540623D02*
X544323D01*
G02X544626Y1727403I0J-303D01*
G01Y1717397D01*
G02X544323Y1717094I-303J0D01*
G01X540623D01*
G02X540320Y1717397I0J303D01*
G01Y1719810D01*
G02X540307Y1720039I2003J229D01*
G02X540320Y1720268I2016J0D01*
G01Y1724534D01*
G02X540307Y1724763I2003J229D01*
G02X540320Y1724992I2016J0D01*
G01Y1727403D01*
G02X540623Y1727706I303J0D01*
G37*
G36*
G01X560308D02*
X564008D01*
G02X564310Y1727403I-1J-303D01*
G01Y1717397D01*
G02X564008Y1717094I-302J-1D01*
G01X560308D01*
G02X560006Y1717397I1J303D01*
G01Y1719802D01*
G02X559992Y1720039I2002J237D01*
G02X560006Y1720276I2016J0D01*
G01Y1724526D01*
G02X559992Y1724763I2002J237D01*
G02X560006Y1725000I2016J0D01*
G01Y1727403D01*
G02X560308Y1727706I302J1D01*
G37*
G36*
G01X576056D02*
X579756D01*
G02X580058Y1727403I-1J-303D01*
G01Y1717397D01*
G02X579756Y1717094I-302J-1D01*
G01X576056D01*
G02X575754Y1717397I1J303D01*
G01Y1719802D01*
G02X575740Y1720039I2002J237D01*
G02X575754Y1720276I2016J0D01*
G01Y1724526D01*
G02X575740Y1724763I2002J237D01*
G02X575754Y1725000I2016J0D01*
G01Y1727403D01*
G02X576056Y1727706I302J1D01*
G37*
G36*
G01X591804D02*
X595504D01*
G02X595806Y1727403I-1J-303D01*
G01Y1717397D01*
G02X595504Y1717094I-302J-1D01*
G01X591804D01*
G02X591502Y1717397I1J303D01*
G01Y1719802D01*
G02X591488Y1720039I2002J237D01*
G02X591502Y1720276I2016J0D01*
G01Y1724526D01*
G02X591488Y1724763I2002J237D01*
G02X591502Y1725000I2016J0D01*
G01Y1727403D01*
G02X591804Y1727706I302J1D01*
G37*
G36*
G01X607552D02*
X611252D01*
G02X611554Y1727403I-1J-303D01*
G01Y1717397D01*
G02X611252Y1717094I-302J-1D01*
G01X607552D01*
G02X607250Y1717397I1J303D01*
G01Y1719802D01*
G02X607236Y1720039I2002J237D01*
G02X607250Y1720276I2016J0D01*
G01Y1724526D01*
G02X607236Y1724763I2002J237D01*
G02X607250Y1725000I2016J0D01*
G01Y1727403D01*
G02X607552Y1727706I302J1D01*
G37*
G36*
G01X1237080D02*
X1240780D01*
G02X1241082Y1727404I0J-302D01*
G01Y1717398D01*
G02X1240780Y1717096I-302J0D01*
G01X1237080D01*
G02X1236778Y1717398I0J302D01*
G01Y1719802D01*
G02X1236764Y1720039I2002J237D01*
G02X1236778Y1720276I2016J0D01*
G01Y1724526D01*
G02X1236764Y1724763I2002J237D01*
G02X1236778Y1725000I2016J0D01*
G01Y1727404D01*
G02X1237080Y1727706I302J0D01*
G37*
G36*
G01X1252828D02*
X1256528D01*
G02X1256830Y1727404I0J-302D01*
G01Y1717398D01*
G02X1256528Y1717096I-302J0D01*
G01X1252828D01*
G02X1252526Y1717398I0J302D01*
G01Y1719802D01*
G02X1252512Y1720039I2002J237D01*
G02X1252526Y1720276I2016J0D01*
G01Y1724526D01*
G02X1252512Y1724763I2002J237D01*
G02X1252526Y1725000I2016J0D01*
G01Y1727404D01*
G02X1252828Y1727706I302J0D01*
G37*
G36*
G01X1268576D02*
X1272276D01*
G02X1272578Y1727404I0J-302D01*
G01Y1717398D01*
G02X1272276Y1717096I-302J0D01*
G01X1268576D01*
G02X1268274Y1717398I0J302D01*
G01Y1719802D01*
G02X1268260Y1720039I2002J237D01*
G02X1268274Y1720276I2016J0D01*
G01Y1724526D01*
G02X1268260Y1724763I2002J237D01*
G02X1268274Y1725000I2016J0D01*
G01Y1727404D01*
G02X1268576Y1727706I302J0D01*
G37*
G36*
G01X1284324D02*
X1288024D01*
G02X1288326Y1727404I0J-302D01*
G01Y1717398D01*
G02X1288024Y1717096I-302J0D01*
G01X1284324D01*
G02X1284022Y1717398I0J302D01*
G01Y1719802D01*
G02X1284008Y1720039I2002J237D01*
G02X1284022Y1720276I2016J0D01*
G01Y1724526D01*
G02X1284008Y1724763I2002J237D01*
G02X1284022Y1725000I2016J0D01*
G01Y1727404D01*
G02X1284324Y1727706I302J0D01*
G37*
G36*
G01X1501253D02*
X1504953D01*
G02X1505256Y1727403I0J-303D01*
G01Y1717397D01*
G02X1504953Y1717094I-303J0D01*
G01X1501253D01*
G02X1500950Y1717397I0J303D01*
G01Y1719810D01*
G02X1500937Y1720039I2003J229D01*
G02X1500950Y1720268I2016J0D01*
G01Y1724534D01*
G02X1500937Y1724763I2003J229D01*
G02X1500950Y1724992I2016J0D01*
G01Y1727403D01*
G02X1501253Y1727706I303J0D01*
G37*
G36*
G01X1517001D02*
X1520701D01*
G02X1521004Y1727403I0J-303D01*
G01Y1717397D01*
G02X1520701Y1717094I-303J0D01*
G01X1517001D01*
G02X1516698Y1717397I0J303D01*
G01Y1719810D01*
G02X1516685Y1720039I2003J229D01*
G02X1516698Y1720268I2016J0D01*
G01Y1724534D01*
G02X1516685Y1724763I2003J229D01*
G02X1516698Y1724992I2016J0D01*
G01Y1727403D01*
G02X1517001Y1727706I303J0D01*
G37*
G36*
G01X1532749D02*
X1536449D01*
G02X1536752Y1727403I0J-303D01*
G01Y1717397D01*
G02X1536449Y1717094I-303J0D01*
G01X1532749D01*
G02X1532446Y1717397I0J303D01*
G01Y1719810D01*
G02X1532433Y1720039I2003J229D01*
G02X1532446Y1720268I2016J0D01*
G01Y1724534D01*
G02X1532433Y1724763I2003J229D01*
G02X1532446Y1724992I2016J0D01*
G01Y1727403D01*
G02X1532749Y1727706I303J0D01*
G37*
G36*
G01X1548497D02*
X1552197D01*
G02X1552500Y1727403I0J-303D01*
G01Y1717397D01*
G02X1552197Y1717094I-303J0D01*
G01X1548497D01*
G02X1548194Y1717397I0J303D01*
G01Y1719810D01*
G02X1548181Y1720039I2003J229D01*
G02X1548194Y1720268I2016J0D01*
G01Y1724534D01*
G02X1548181Y1724763I2003J229D01*
G02X1548194Y1724992I2016J0D01*
G01Y1727403D01*
G02X1548497Y1727706I303J0D01*
G37*
G36*
G01X1568182D02*
X1571882D01*
G02X1572184Y1727403I-1J-303D01*
G01Y1717397D01*
G02X1571882Y1717094I-302J-1D01*
G01X1568182D01*
G02X1567880Y1717397I1J303D01*
G01Y1719802D01*
G02X1567866Y1720039I2002J237D01*
G02X1567880Y1720276I2016J0D01*
G01Y1724526D01*
G02X1567866Y1724763I2002J237D01*
G02X1567880Y1725000I2016J0D01*
G01Y1727403D01*
G02X1568182Y1727706I302J1D01*
G37*
G36*
G01X1583930D02*
X1587630D01*
G02X1587932Y1727403I-1J-303D01*
G01Y1717397D01*
G02X1587630Y1717094I-302J-1D01*
G01X1583930D01*
G02X1583628Y1717397I1J303D01*
G01Y1719802D01*
G02X1583614Y1720039I2002J237D01*
G02X1583628Y1720276I2016J0D01*
G01Y1724526D01*
G02X1583614Y1724763I2002J237D01*
G02X1583628Y1725000I2016J0D01*
G01Y1727403D01*
G02X1583930Y1727706I302J1D01*
G37*
G36*
G01X1599678D02*
X1603378D01*
G02X1603680Y1727403I-1J-303D01*
G01Y1717397D01*
G02X1603378Y1717094I-302J-1D01*
G01X1599678D01*
G02X1599376Y1717397I1J303D01*
G01Y1719802D01*
G02X1599362Y1720039I2002J237D01*
G02X1599376Y1720276I2016J0D01*
G01Y1724526D01*
G02X1599362Y1724763I2002J237D01*
G02X1599376Y1725000I2016J0D01*
G01Y1727403D01*
G02X1599678Y1727706I302J1D01*
G37*
G36*
G01X1615426D02*
X1619126D01*
G02X1619428Y1727403I-1J-303D01*
G01Y1717397D01*
G02X1619126Y1717094I-302J-1D01*
G01X1615426D01*
G02X1615124Y1717397I1J303D01*
G01Y1719802D01*
G02X1615110Y1720039I2002J237D01*
G02X1615124Y1720276I2016J0D01*
G01Y1724526D01*
G02X1615110Y1724763I2002J237D01*
G02X1615124Y1725000I2016J0D01*
G01Y1727403D01*
G02X1615426Y1727706I302J1D01*
G37*
G36*
G01X296135D02*
X299835D01*
G02X300138Y1727404I1J-302D01*
G01Y1717398D01*
G02X299835Y1717096I-303J1D01*
G01X296135D01*
G02X295832Y1717398I-1J302D01*
G01Y1719810D01*
G02X295819Y1720039I2003J229D01*
G02X295832Y1720268I2016J0D01*
G01Y1724534D01*
G02X295819Y1724763I2003J229D01*
G02X295832Y1724992I2016J0D01*
G01Y1727404D01*
G02X296135Y1727706I303J-1D01*
G37*
G36*
G01X311883D02*
X315583D01*
G02X315886Y1727404I1J-302D01*
G01Y1717398D01*
G02X315583Y1717096I-303J1D01*
G01X311883D01*
G02X311580Y1717398I-1J302D01*
G01Y1719810D01*
G02X311567Y1720039I2003J229D01*
G02X311580Y1720268I2016J0D01*
G01Y1724534D01*
G02X311567Y1724763I2003J229D01*
G02X311580Y1724992I2016J0D01*
G01Y1727404D01*
G02X311883Y1727706I303J-1D01*
G37*
G36*
G01X327631D02*
X331331D01*
G02X331634Y1727404I1J-302D01*
G01Y1717398D01*
G02X331331Y1717096I-303J1D01*
G01X327631D01*
G02X327328Y1717398I-1J302D01*
G01Y1719810D01*
G02X327315Y1720039I2003J229D01*
G02X327328Y1720268I2016J0D01*
G01Y1724534D01*
G02X327315Y1724763I2003J229D01*
G02X327328Y1724992I2016J0D01*
G01Y1727404D01*
G02X327631Y1727706I303J-1D01*
G37*
G36*
G01X343379D02*
X347079D01*
G02X347382Y1727404I1J-302D01*
G01Y1717398D01*
G02X347079Y1717096I-303J1D01*
G01X343379D01*
G02X343076Y1717398I-1J302D01*
G01Y1719810D01*
G02X343063Y1720039I2003J229D01*
G02X343076Y1720268I2016J0D01*
G01Y1724534D01*
G02X343063Y1724763I2003J229D01*
G02X343076Y1724992I2016J0D01*
G01Y1727404D01*
G02X343379Y1727706I303J-1D01*
G37*
G36*
G01X1304009D02*
X1307709D01*
G02X1308012Y1727404I1J-302D01*
G01Y1717398D01*
G02X1307709Y1717096I-303J1D01*
G01X1304009D01*
G02X1303706Y1717398I-1J302D01*
G01Y1719810D01*
G02X1303693Y1720039I2003J229D01*
G02X1303706Y1720268I2016J0D01*
G01Y1724534D01*
G02X1303693Y1724763I2003J229D01*
G02X1303706Y1724992I2016J0D01*
G01Y1727404D01*
G02X1304009Y1727706I303J-1D01*
G37*
G36*
G01X1319757D02*
X1323457D01*
G02X1323760Y1727404I1J-302D01*
G01Y1717398D01*
G02X1323457Y1717096I-303J1D01*
G01X1319757D01*
G02X1319454Y1717398I-1J302D01*
G01Y1719810D01*
G02X1319441Y1720039I2003J229D01*
G02X1319454Y1720268I2016J0D01*
G01Y1724534D01*
G02X1319441Y1724763I2003J229D01*
G02X1319454Y1724992I2016J0D01*
G01Y1727404D01*
G02X1319757Y1727706I303J-1D01*
G37*
G36*
G01X1335505D02*
X1339205D01*
G02X1339508Y1727404I1J-302D01*
G01Y1717398D01*
G02X1339205Y1717096I-303J1D01*
G01X1335505D01*
G02X1335202Y1717398I-1J302D01*
G01Y1719810D01*
G02X1335189Y1720039I2003J229D01*
G02X1335202Y1720268I2016J0D01*
G01Y1724534D01*
G02X1335189Y1724763I2003J229D01*
G02X1335202Y1724992I2016J0D01*
G01Y1727404D01*
G02X1335505Y1727706I303J-1D01*
G37*
G36*
G01X1351253D02*
X1354953D01*
G02X1355256Y1727404I1J-302D01*
G01Y1717398D01*
G02X1354953Y1717096I-303J1D01*
G01X1351253D01*
G02X1350950Y1717398I-1J302D01*
G01Y1719810D01*
G02X1350937Y1720039I2003J229D01*
G02X1350950Y1720268I2016J0D01*
G01Y1724534D01*
G02X1350937Y1724763I2003J229D01*
G02X1350950Y1724992I2016J0D01*
G01Y1727404D01*
G02X1351253Y1727706I303J-1D01*
G37*
G36*
G01X568182Y1731642D02*
X571882D01*
G02X572184Y1731340I0J-302D01*
G01Y1721334D01*
G02X571882Y1721032I-302J0D01*
G01X568182D01*
G02X567880Y1721334I0J302D01*
G01Y1723739D01*
G02X567866Y1723976I2002J237D01*
G02X567880Y1724213I2016J0D01*
G01Y1728463D01*
G02X567866Y1728700I2002J237D01*
G02X567880Y1728937I2016J0D01*
G01Y1731340D01*
G02X568182Y1731642I302J0D01*
G37*
G36*
G01X583930D02*
X587630D01*
G02X587932Y1731340I0J-302D01*
G01Y1721334D01*
G02X587630Y1721032I-302J0D01*
G01X583930D01*
G02X583628Y1721334I0J302D01*
G01Y1723739D01*
G02X583614Y1723976I2002J237D01*
G02X583628Y1724213I2016J0D01*
G01Y1728463D01*
G02X583614Y1728700I2002J237D01*
G02X583628Y1728937I2016J0D01*
G01Y1731340D01*
G02X583930Y1731642I302J0D01*
G37*
G36*
G01X599678D02*
X603378D01*
G02X603680Y1731340I0J-302D01*
G01Y1721334D01*
G02X603378Y1721032I-302J0D01*
G01X599678D01*
G02X599376Y1721334I0J302D01*
G01Y1723739D01*
G02X599362Y1723976I2002J237D01*
G02X599376Y1724213I2016J0D01*
G01Y1728463D01*
G02X599362Y1728700I2002J237D01*
G02X599376Y1728937I2016J0D01*
G01Y1731340D01*
G02X599678Y1731642I302J0D01*
G37*
G36*
G01X615426D02*
X619126D01*
G02X619428Y1731340I0J-302D01*
G01Y1721334D01*
G02X619126Y1721032I-302J0D01*
G01X615426D01*
G02X615124Y1721334I0J302D01*
G01Y1723739D01*
G02X615110Y1723976I2002J237D01*
G02X615124Y1724213I2016J0D01*
G01Y1728463D01*
G02X615110Y1728700I2002J237D01*
G02X615124Y1728937I2016J0D01*
G01Y1731340D01*
G02X615426Y1731642I302J0D01*
G37*
G36*
G01X1576056D02*
X1579756D01*
G02X1580058Y1731340I0J-302D01*
G01Y1721334D01*
G02X1579756Y1721032I-302J0D01*
G01X1576056D01*
G02X1575754Y1721334I0J302D01*
G01Y1723739D01*
G02X1575740Y1723976I2002J237D01*
G02X1575754Y1724213I2016J0D01*
G01Y1728463D01*
G02X1575740Y1728700I2002J237D01*
G02X1575754Y1728937I2016J0D01*
G01Y1731340D01*
G02X1576056Y1731642I302J0D01*
G37*
G36*
G01X1591804D02*
X1595504D01*
G02X1595806Y1731340I0J-302D01*
G01Y1721334D01*
G02X1595504Y1721032I-302J0D01*
G01X1591804D01*
G02X1591502Y1721334I0J302D01*
G01Y1723739D01*
G02X1591488Y1723976I2002J237D01*
G02X1591502Y1724213I2016J0D01*
G01Y1728463D01*
G02X1591488Y1728700I2002J237D01*
G02X1591502Y1728937I2016J0D01*
G01Y1731340D01*
G02X1591804Y1731642I302J0D01*
G37*
G36*
G01X1607552D02*
X1611252D01*
G02X1611554Y1731340I0J-302D01*
G01Y1721334D01*
G02X1611252Y1721032I-302J0D01*
G01X1607552D01*
G02X1607250Y1721334I0J302D01*
G01Y1723739D01*
G02X1607236Y1723976I2002J237D01*
G02X1607250Y1724213I2016J0D01*
G01Y1728463D01*
G02X1607236Y1728700I2002J237D01*
G02X1607250Y1728937I2016J0D01*
G01Y1731340D01*
G02X1607552Y1731642I302J0D01*
G37*
G36*
G01X1623300D02*
X1627000D01*
G02X1627302Y1731340I0J-302D01*
G01Y1721334D01*
G02X1627000Y1721032I-302J0D01*
G01X1623300D01*
G02X1622998Y1721334I0J302D01*
G01Y1723739D01*
G02X1622984Y1723976I2002J237D01*
G02X1622998Y1724213I2016J0D01*
G01Y1728463D01*
G02X1622984Y1728700I2002J237D01*
G02X1622998Y1728937I2016J0D01*
G01Y1731340D01*
G02X1623300Y1731642I302J0D01*
G37*
G36*
G01X501253D02*
X504953D01*
G02X505256Y1731340I1J-302D01*
G01Y1721334D01*
G02X504953Y1721032I-303J1D01*
G01X501253D01*
G02X500950Y1721334I-1J302D01*
G01Y1723747D01*
G02X500937Y1723976I2003J229D01*
G02X500950Y1724205I2016J0D01*
G01Y1728471D01*
G02X500937Y1728700I2003J229D01*
G02X500950Y1728929I2016J0D01*
G01Y1731340D01*
G02X501253Y1731642I303J-1D01*
G37*
G36*
G01X517001D02*
X520701D01*
G02X521004Y1731340I1J-302D01*
G01Y1721334D01*
G02X520701Y1721032I-303J1D01*
G01X517001D01*
G02X516698Y1721334I-1J302D01*
G01Y1723747D01*
G02X516685Y1723976I2003J229D01*
G02X516698Y1724205I2016J0D01*
G01Y1728471D01*
G02X516685Y1728700I2003J229D01*
G02X516698Y1728929I2016J0D01*
G01Y1731340D01*
G02X517001Y1731642I303J-1D01*
G37*
G36*
G01X532749D02*
X536449D01*
G02X536752Y1731340I1J-302D01*
G01Y1721334D01*
G02X536449Y1721032I-303J1D01*
G01X532749D01*
G02X532446Y1721334I-1J302D01*
G01Y1723747D01*
G02X532433Y1723976I2003J229D01*
G02X532446Y1724205I2016J0D01*
G01Y1728471D01*
G02X532433Y1728700I2003J229D01*
G02X532446Y1728929I2016J0D01*
G01Y1731340D01*
G02X532749Y1731642I303J-1D01*
G37*
G36*
G01X548497D02*
X552197D01*
G02X552500Y1731340I1J-302D01*
G01Y1721334D01*
G02X552197Y1721032I-303J1D01*
G01X548497D01*
G02X548194Y1721334I-1J302D01*
G01Y1723747D01*
G02X548181Y1723976I2003J229D01*
G02X548194Y1724205I2016J0D01*
G01Y1728471D01*
G02X548181Y1728700I2003J229D01*
G02X548194Y1728929I2016J0D01*
G01Y1731340D01*
G02X548497Y1731642I303J-1D01*
G37*
G36*
G01X1509127D02*
X1512827D01*
G02X1513130Y1731340I1J-302D01*
G01Y1721334D01*
G02X1512827Y1721032I-303J1D01*
G01X1509127D01*
G02X1508824Y1721334I-1J302D01*
G01Y1723747D01*
G02X1508811Y1723976I2003J229D01*
G02X1508824Y1724205I2016J0D01*
G01Y1728471D01*
G02X1508811Y1728700I2003J229D01*
G02X1508824Y1728929I2016J0D01*
G01Y1731340D01*
G02X1509127Y1731642I303J-1D01*
G37*
G36*
G01X1524875D02*
X1528575D01*
G02X1528878Y1731340I1J-302D01*
G01Y1721334D01*
G02X1528575Y1721032I-303J1D01*
G01X1524875D01*
G02X1524572Y1721334I-1J302D01*
G01Y1723747D01*
G02X1524559Y1723976I2003J229D01*
G02X1524572Y1724205I2016J0D01*
G01Y1728471D01*
G02X1524559Y1728700I2003J229D01*
G02X1524572Y1728929I2016J0D01*
G01Y1731340D01*
G02X1524875Y1731642I303J-1D01*
G37*
G36*
G01X1540623D02*
X1544323D01*
G02X1544626Y1731340I1J-302D01*
G01Y1721334D01*
G02X1544323Y1721032I-303J1D01*
G01X1540623D01*
G02X1540320Y1721334I-1J302D01*
G01Y1723747D01*
G02X1540307Y1723976I2003J229D01*
G02X1540320Y1724205I2016J0D01*
G01Y1728471D01*
G02X1540307Y1728700I2003J229D01*
G02X1540320Y1728929I2016J0D01*
G01Y1731340D01*
G02X1540623Y1731642I303J-1D01*
G37*
G36*
G01X1556371D02*
X1560071D01*
G02X1560374Y1731340I1J-302D01*
G01Y1721334D01*
G02X1560071Y1721032I-303J1D01*
G01X1556371D01*
G02X1556068Y1721334I-1J302D01*
G01Y1723747D01*
G02X1556055Y1723976I2003J229D01*
G02X1556068Y1724205I2016J0D01*
G01Y1728471D01*
G02X1556055Y1728700I2003J229D01*
G02X1556068Y1728929I2016J0D01*
G01Y1731340D01*
G02X1556371Y1731642I303J-1D01*
G37*
G36*
G01X237080Y1731644D02*
X240780D01*
G02X241082Y1731341I-1J-303D01*
G01Y1721335D01*
G02X240780Y1721032I-302J-1D01*
G01X237080D01*
G02X236778Y1721335I1J303D01*
G01Y1723739D01*
G02X236764Y1723976I2002J237D01*
G02X236778Y1724213I2016J0D01*
G01Y1728463D01*
G02X236764Y1728700I2002J237D01*
G02X236778Y1728937I2016J0D01*
G01Y1731341D01*
G02X237080Y1731644I302J1D01*
G37*
G36*
G01X252828D02*
X256528D01*
G02X256830Y1731341I-1J-303D01*
G01Y1721335D01*
G02X256528Y1721032I-302J-1D01*
G01X252828D01*
G02X252526Y1721335I1J303D01*
G01Y1723739D01*
G02X252512Y1723976I2002J237D01*
G02X252526Y1724213I2016J0D01*
G01Y1728463D01*
G02X252512Y1728700I2002J237D01*
G02X252526Y1728937I2016J0D01*
G01Y1731341D01*
G02X252828Y1731644I302J1D01*
G37*
G36*
G01X268576D02*
X272276D01*
G02X272578Y1731341I-1J-303D01*
G01Y1721335D01*
G02X272276Y1721032I-302J-1D01*
G01X268576D01*
G02X268274Y1721335I1J303D01*
G01Y1723739D01*
G02X268260Y1723976I2002J237D01*
G02X268274Y1724213I2016J0D01*
G01Y1728463D01*
G02X268260Y1728700I2002J237D01*
G02X268274Y1728937I2016J0D01*
G01Y1731341D01*
G02X268576Y1731644I302J1D01*
G37*
G36*
G01X284324D02*
X288024D01*
G02X288326Y1731341I-1J-303D01*
G01Y1721335D01*
G02X288024Y1721032I-302J-1D01*
G01X284324D01*
G02X284022Y1721335I1J303D01*
G01Y1723739D01*
G02X284008Y1723976I2002J237D01*
G02X284022Y1724213I2016J0D01*
G01Y1728463D01*
G02X284008Y1728700I2002J237D01*
G02X284022Y1728937I2016J0D01*
G01Y1731341D01*
G02X284324Y1731644I302J1D01*
G37*
G36*
G01X304009D02*
X307709D01*
G02X308012Y1731341I0J-303D01*
G01Y1721335D01*
G02X307709Y1721032I-303J0D01*
G01X304009D01*
G02X303706Y1721335I0J303D01*
G01Y1723747D01*
G02X303693Y1723976I2003J229D01*
G02X303706Y1724205I2016J0D01*
G01Y1728471D01*
G02X303693Y1728700I2003J229D01*
G02X303706Y1728929I2016J0D01*
G01Y1731341D01*
G02X304009Y1731644I303J0D01*
G37*
G36*
G01X319757D02*
X323457D01*
G02X323760Y1731341I0J-303D01*
G01Y1721335D01*
G02X323457Y1721032I-303J0D01*
G01X319757D01*
G02X319454Y1721335I0J303D01*
G01Y1723747D01*
G02X319441Y1723976I2003J229D01*
G02X319454Y1724205I2016J0D01*
G01Y1728471D01*
G02X319441Y1728700I2003J229D01*
G02X319454Y1728929I2016J0D01*
G01Y1731341D01*
G02X319757Y1731644I303J0D01*
G37*
G36*
G01X335505D02*
X339205D01*
G02X339508Y1731341I0J-303D01*
G01Y1721335D01*
G02X339205Y1721032I-303J0D01*
G01X335505D01*
G02X335202Y1721335I0J303D01*
G01Y1723747D01*
G02X335189Y1723976I2003J229D01*
G02X335202Y1724205I2016J0D01*
G01Y1728471D01*
G02X335189Y1728700I2003J229D01*
G02X335202Y1728929I2016J0D01*
G01Y1731341D01*
G02X335505Y1731644I303J0D01*
G37*
G36*
G01X351253D02*
X354953D01*
G02X355256Y1731341I0J-303D01*
G01Y1721335D01*
G02X354953Y1721032I-303J0D01*
G01X351253D01*
G02X350950Y1721335I0J303D01*
G01Y1723747D01*
G02X350937Y1723976I2003J229D01*
G02X350950Y1724205I2016J0D01*
G01Y1728471D01*
G02X350937Y1728700I2003J229D01*
G02X350950Y1728929I2016J0D01*
G01Y1731341D01*
G02X351253Y1731644I303J0D01*
G37*
G36*
G01X1244954D02*
X1248654D01*
G02X1248956Y1731341I-1J-303D01*
G01Y1721335D01*
G02X1248654Y1721032I-302J-1D01*
G01X1244954D01*
G02X1244652Y1721335I1J303D01*
G01Y1723739D01*
G02X1244638Y1723976I2002J237D01*
G02X1244652Y1724213I2016J0D01*
G01Y1728463D01*
G02X1244638Y1728700I2002J237D01*
G02X1244652Y1728937I2016J0D01*
G01Y1731341D01*
G02X1244954Y1731644I302J1D01*
G37*
G36*
G01X1260702D02*
X1264402D01*
G02X1264704Y1731341I-1J-303D01*
G01Y1721335D01*
G02X1264402Y1721032I-302J-1D01*
G01X1260702D01*
G02X1260400Y1721335I1J303D01*
G01Y1723739D01*
G02X1260386Y1723976I2002J237D01*
G02X1260400Y1724213I2016J0D01*
G01Y1728463D01*
G02X1260386Y1728700I2002J237D01*
G02X1260400Y1728937I2016J0D01*
G01Y1731341D01*
G02X1260702Y1731644I302J1D01*
G37*
G36*
G01X1276450D02*
X1280150D01*
G02X1280452Y1731341I-1J-303D01*
G01Y1721335D01*
G02X1280150Y1721032I-302J-1D01*
G01X1276450D01*
G02X1276148Y1721335I1J303D01*
G01Y1723739D01*
G02X1276134Y1723976I2002J237D01*
G02X1276148Y1724213I2016J0D01*
G01Y1728463D01*
G02X1276134Y1728700I2002J237D01*
G02X1276148Y1728937I2016J0D01*
G01Y1731341D01*
G02X1276450Y1731644I302J1D01*
G37*
G36*
G01X1292198D02*
X1295898D01*
G02X1296200Y1731341I-1J-303D01*
G01Y1721335D01*
G02X1295898Y1721032I-302J-1D01*
G01X1292198D01*
G02X1291896Y1721335I1J303D01*
G01Y1723739D01*
G02X1291882Y1723976I2002J237D01*
G02X1291896Y1724213I2016J0D01*
G01Y1728463D01*
G02X1291882Y1728700I2002J237D01*
G02X1291896Y1728937I2016J0D01*
G01Y1731341D01*
G02X1292198Y1731644I302J1D01*
G37*
G36*
G01X1311883D02*
X1315583D01*
G02X1315886Y1731341I0J-303D01*
G01Y1721335D01*
G02X1315583Y1721032I-303J0D01*
G01X1311883D01*
G02X1311580Y1721335I0J303D01*
G01Y1723747D01*
G02X1311567Y1723976I2003J229D01*
G02X1311580Y1724205I2016J0D01*
G01Y1728471D01*
G02X1311567Y1728700I2003J229D01*
G02X1311580Y1728929I2016J0D01*
G01Y1731341D01*
G02X1311883Y1731644I303J0D01*
G37*
G36*
G01X1327631D02*
X1331331D01*
G02X1331634Y1731341I0J-303D01*
G01Y1721335D01*
G02X1331331Y1721032I-303J0D01*
G01X1327631D01*
G02X1327328Y1721335I0J303D01*
G01Y1723747D01*
G02X1327315Y1723976I2003J229D01*
G02X1327328Y1724205I2016J0D01*
G01Y1728471D01*
G02X1327315Y1728700I2003J229D01*
G02X1327328Y1728929I2016J0D01*
G01Y1731341D01*
G02X1327631Y1731644I303J0D01*
G37*
G36*
G01X1343379D02*
X1347079D01*
G02X1347382Y1731341I0J-303D01*
G01Y1721335D01*
G02X1347079Y1721032I-303J0D01*
G01X1343379D01*
G02X1343076Y1721335I0J303D01*
G01Y1723747D01*
G02X1343063Y1723976I2003J229D01*
G02X1343076Y1724205I2016J0D01*
G01Y1728471D01*
G02X1343063Y1728700I2003J229D01*
G02X1343076Y1728929I2016J0D01*
G01Y1731341D01*
G02X1343379Y1731644I303J0D01*
G37*
G36*
G01X1359127D02*
X1362827D01*
G02X1363130Y1731341I0J-303D01*
G01Y1721335D01*
G02X1362827Y1721032I-303J0D01*
G01X1359127D01*
G02X1358824Y1721335I0J303D01*
G01Y1723747D01*
G02X1358811Y1723976I2003J229D01*
G02X1358824Y1724205I2016J0D01*
G01Y1728471D01*
G02X1358811Y1728700I2003J229D01*
G02X1358824Y1728929I2016J0D01*
G01Y1731341D01*
G02X1359127Y1731644I303J0D01*
G37*
G36*
G01X105651Y1575002D02*
X102251D01*
G02Y1578006I0J1502D01*
G01X105651D01*
G02Y1575002I0J-1502D01*
G37*
G36*
G01X74218Y1574006D02*
X77618D01*
G02Y1571002I0J-1502D01*
G01X74218D01*
G02Y1574006I0J1502D01*
G37*
G36*
G01X76369Y1508958D02*
X79769D01*
G02Y1505954I0J-1502D01*
G01X76369D01*
G02Y1508958I0J1502D01*
G37*
G36*
G01X391330Y1583652D02*
X387930D01*
G02Y1586658I0J1503D01*
G01X391330D01*
G02Y1583652I0J-1503D01*
G37*
G36*
G01X148938Y1515872D02*
X145538D01*
G02Y1518876I0J1502D01*
G01X148938D01*
G02Y1515872I0J-1502D01*
G37*
G36*
G01X164710Y1519516D02*
X168110D01*
G02Y1516512I0J-1502D01*
G01X164710D01*
G02Y1519516I0J1502D01*
G37*
G36*
G01X89264Y1509114D02*
X92664D01*
G02Y1506108I0J-1503D01*
G01X89264D01*
G02Y1509114I0J1503D01*
G37*
G36*
G01X167266Y1571470D02*
X170666D01*
G02Y1568466I0J-1502D01*
G01X167266D01*
G02Y1571470I0J1502D01*
G37*
G36*
G01X1346792Y1615794D02*
X1350192D01*
G02Y1612790I0J-1502D01*
G01X1346792D01*
G02Y1615794I0J1502D01*
G37*
G36*
G01X1358852D02*
X1362252D01*
G02Y1612790I0J-1502D01*
G01X1358852D01*
G02Y1615794I0J1502D01*
G37*
G36*
G01X1365612Y1591596D02*
X1369012D01*
G02Y1588592I0J-1502D01*
G01X1365612D01*
G02Y1591596I0J1502D01*
G37*
G36*
G01Y1579684D02*
X1369012D01*
G02Y1576680I0J-1502D01*
G01X1365612D01*
G02Y1579684I0J1502D01*
G37*
G36*
G01X1305312D02*
X1308712D01*
G02Y1576680I0J-1502D01*
G01X1305312D01*
G02Y1579684I0J1502D01*
G37*
G36*
G01X1293252Y1591596D02*
X1296652D01*
G02Y1588592I0J-1502D01*
G01X1293252D01*
G02Y1591596I0J1502D01*
G37*
G36*
G01X1310612Y1615794D02*
X1314012D01*
G02Y1612790I0J-1502D01*
G01X1310612D01*
G02Y1615794I0J1502D01*
G37*
G36*
G01X1262372Y1603882D02*
X1265772D01*
G02Y1600878I0J-1502D01*
G01X1262372D01*
G02Y1603882I0J1502D01*
G37*
G36*
G01X1286492Y1615794D02*
X1289892D01*
G02Y1612790I0J-1502D01*
G01X1286492D01*
G02Y1615794I0J1502D01*
G37*
G36*
G01X1262372D02*
X1265772D01*
G02Y1612790I0J-1502D01*
G01X1262372D01*
G02Y1615794I0J1502D01*
G37*
G36*
G01X1334732Y1603882D02*
X1338132D01*
G02Y1600878I0J-1502D01*
G01X1334732D01*
G02Y1603882I0J1502D01*
G37*
G36*
G01X1220892Y1579684D02*
X1224292D01*
G02Y1576680I0J-1502D01*
G01X1220892D01*
G02Y1579684I0J1502D01*
G37*
G36*
G01X1334732Y1615794D02*
X1338132D01*
G02Y1612790I0J-1502D01*
G01X1334732D01*
G02Y1615794I0J1502D01*
G37*
G36*
G01X1370912Y1603882D02*
X1374312D01*
G02Y1600878I0J-1502D01*
G01X1370912D01*
G02Y1603882I0J1502D01*
G37*
G36*
G01X1214132D02*
X1217532D01*
G02Y1600878I0J-1502D01*
G01X1214132D01*
G02Y1603882I0J1502D01*
G37*
G36*
G01X1286492D02*
X1289892D01*
G02Y1600878I0J-1502D01*
G01X1286492D01*
G02Y1603882I0J1502D01*
G37*
G36*
G01X1298552D02*
X1301952D01*
G02Y1600878I0J-1502D01*
G01X1298552D01*
G02Y1603882I0J1502D01*
G37*
G36*
G01X1353552Y1579684D02*
X1356952D01*
G02Y1576680I0J-1502D01*
G01X1353552D01*
G02Y1579684I0J1502D01*
G37*
G36*
G01X1341492Y1591596D02*
X1344892D01*
G02Y1588592I0J-1502D01*
G01X1341492D01*
G02Y1591596I0J1502D01*
G37*
G36*
G01X1370912Y1615794D02*
X1374312D01*
G02Y1612790I0J-1502D01*
G01X1370912D01*
G02Y1615794I0J1502D01*
G37*
G36*
G01X1269132Y1591596D02*
X1272532D01*
G02Y1588592I0J-1502D01*
G01X1269132D01*
G02Y1591596I0J1502D01*
G37*
G36*
G01X1238252Y1603882D02*
X1241652D01*
G02Y1600878I0J-1502D01*
G01X1238252D01*
G02Y1603882I0J1502D01*
G37*
G36*
G01X1353552Y1591596D02*
X1356952D01*
G02Y1588592I0J-1502D01*
G01X1353552D01*
G02Y1591596I0J1502D01*
G37*
G36*
G01X1214132Y1615794D02*
X1217532D01*
G02Y1612790I0J-1502D01*
G01X1214132D01*
G02Y1615794I0J1502D01*
G37*
G36*
G01X1226192Y1603882D02*
X1229592D01*
G02Y1600878I0J-1502D01*
G01X1226192D01*
G02Y1603882I0J1502D01*
G37*
G36*
G01X1208832Y1579684D02*
X1212232D01*
G02Y1576680I0J-1502D01*
G01X1208832D01*
G02Y1579684I0J1502D01*
G37*
G36*
G01Y1591596D02*
X1212232D01*
G02Y1588592I0J-1502D01*
G01X1208832D01*
G02Y1591596I0J1502D01*
G37*
G36*
G01X1341492Y1579684D02*
X1344892D01*
G02Y1576680I0J-1502D01*
G01X1341492D01*
G02Y1579684I0J1502D01*
G37*
G36*
G01X1250312Y1615794D02*
X1253712D01*
G02Y1612790I0J-1502D01*
G01X1250312D01*
G02Y1615794I0J1502D01*
G37*
G36*
G01X1232952Y1579684D02*
X1236352D01*
G02Y1576680I0J-1502D01*
G01X1232952D01*
G02Y1579684I0J1502D01*
G37*
G36*
G01Y1591596D02*
X1236352D01*
G02Y1588592I0J-1502D01*
G01X1232952D01*
G02Y1591596I0J1502D01*
G37*
G36*
G01X1196772Y1579684D02*
X1200172D01*
G02Y1576680I0J-1502D01*
G01X1196772D01*
G02Y1579684I0J1502D01*
G37*
G36*
G01X1257072D02*
X1260472D01*
G02Y1576680I0J-1502D01*
G01X1257072D01*
G02Y1579684I0J1502D01*
G37*
G36*
G01X1220892Y1591596D02*
X1224292D01*
G02Y1588592I0J-1502D01*
G01X1220892D01*
G02Y1591596I0J1502D01*
G37*
G36*
G01X1269132Y1579684D02*
X1272532D01*
G02Y1576680I0J-1502D01*
G01X1269132D01*
G02Y1579684I0J1502D01*
G37*
G36*
G01X1305312Y1591596D02*
X1308712D01*
G02Y1588592I0J-1502D01*
G01X1305312D01*
G02Y1591596I0J1502D01*
G37*
G36*
G01X1245012D02*
X1248412D01*
G02Y1588592I0J-1502D01*
G01X1245012D01*
G02Y1591596I0J1502D01*
G37*
G36*
G01X1250312Y1603882D02*
X1253712D01*
G02Y1600878I0J-1502D01*
G01X1250312D01*
G02Y1603882I0J1502D01*
G37*
G36*
G01X1317372Y1579684D02*
X1320772D01*
G02Y1576680I0J-1502D01*
G01X1317372D01*
G02Y1579684I0J1502D01*
G37*
G36*
G01X1358852Y1603882D02*
X1362252D01*
G02Y1600878I0J-1502D01*
G01X1358852D01*
G02Y1603882I0J1502D01*
G37*
G36*
G01X1202072D02*
X1205472D01*
G02Y1600878I0J-1502D01*
G01X1202072D01*
G02Y1603882I0J1502D01*
G37*
G36*
G01Y1615794D02*
X1205472D01*
G02Y1612790I0J-1502D01*
G01X1202072D01*
G02Y1615794I0J1502D01*
G37*
G36*
G01X1322672Y1603882D02*
X1326072D01*
G02Y1600878I0J-1502D01*
G01X1322672D01*
G02Y1603882I0J1502D01*
G37*
G36*
G01X1310612D02*
X1314012D01*
G02Y1600878I0J-1502D01*
G01X1310612D01*
G02Y1603882I0J1502D01*
G37*
G36*
G01X1274432Y1615794D02*
X1277832D01*
G02Y1612790I0J-1502D01*
G01X1274432D01*
G02Y1615794I0J1502D01*
G37*
G36*
G01X1329432Y1579684D02*
X1332832D01*
G02Y1576680I0J-1502D01*
G01X1329432D01*
G02Y1579684I0J1502D01*
G37*
G36*
G01X1346792Y1603882D02*
X1350192D01*
G02Y1600878I0J-1502D01*
G01X1346792D01*
G02Y1603882I0J1502D01*
G37*
G36*
G01X1317372Y1591596D02*
X1320772D01*
G02Y1588592I0J-1502D01*
G01X1317372D01*
G02Y1591596I0J1502D01*
G37*
G36*
G01X1329432D02*
X1332832D01*
G02Y1588592I0J-1502D01*
G01X1329432D01*
G02Y1591596I0J1502D01*
G37*
G36*
G01X1322672Y1615794D02*
X1326072D01*
G02Y1612790I0J-1502D01*
G01X1322672D01*
G02Y1615794I0J1502D01*
G37*
G36*
G01X1281192Y1591596D02*
X1284592D01*
G02Y1588592I0J-1502D01*
G01X1281192D01*
G02Y1591596I0J1502D01*
G37*
G36*
G01X1196772D02*
X1200172D01*
G02Y1588592I0J-1502D01*
G01X1196772D01*
G02Y1591596I0J1502D01*
G37*
G36*
G01X1226192Y1615794D02*
X1229592D01*
G02Y1612790I0J-1502D01*
G01X1226192D01*
G02Y1615794I0J1502D01*
G37*
G36*
G01X1293252Y1579684D02*
X1296652D01*
G02Y1576680I0J-1502D01*
G01X1293252D01*
G02Y1579684I0J1502D01*
G37*
G36*
G01X1298552Y1615794D02*
X1301952D01*
G02Y1612790I0J-1502D01*
G01X1298552D01*
G02Y1615794I0J1502D01*
G37*
G36*
G01X1281192Y1579684D02*
X1284592D01*
G02Y1576680I0J-1502D01*
G01X1281192D01*
G02Y1579684I0J1502D01*
G37*
G36*
G01X1245012D02*
X1248412D01*
G02Y1576680I0J-1502D01*
G01X1245012D01*
G02Y1579684I0J1502D01*
G37*
G36*
G01X1257072Y1591596D02*
X1260472D01*
G02Y1588592I0J-1502D01*
G01X1257072D01*
G02Y1591596I0J1502D01*
G37*
G36*
G01X1274432Y1603882D02*
X1277832D01*
G02Y1600878I0J-1502D01*
G01X1274432D01*
G02Y1603882I0J1502D01*
G37*
G36*
G01X1238252Y1615794D02*
X1241652D01*
G02Y1612790I0J-1502D01*
G01X1238252D01*
G02Y1615794I0J1502D01*
G37*
G36*
G01X1474516Y730492D02*
G02X1473515Y728758I-2002J0D01*
G01X1469877Y726657D01*
G02X1468878Y726390I-999J1736D01*
G01X1468876D01*
G02X1466874Y728392I0J2002D01*
G02X1467875Y730126I2002J0D01*
G01X1471513Y732227D01*
G02X1472512Y732494I999J-1736D01*
G01X1472514D01*
G02X1474516Y730492I0J-2002D01*
G37*
G36*
G01X1477716Y717492D02*
G02X1476715Y715758I-2002J0D01*
G01X1473077Y713657D01*
G02X1472078Y713390I-999J1736D01*
G01X1472076D01*
G02X1470074Y715392I0J2002D01*
G02X1471075Y717126I2002J0D01*
G01X1474713Y719227D01*
G02X1475712Y719494I999J-1736D01*
G01X1475714D01*
G02X1477716Y717492I0J-2002D01*
G37*
G36*
G01Y702992D02*
G02X1476715Y701258I-2002J0D01*
G01X1473077Y699157D01*
G02X1472078Y698890I-999J1736D01*
G01X1472076D01*
G02X1470074Y700892I0J2002D01*
G02X1471075Y702626I2002J0D01*
G01X1474713Y704727D01*
G02X1475712Y704994I999J-1736D01*
G01X1475714D01*
G02X1477716Y702992I0J-2002D01*
G37*
G36*
G01Y688492D02*
G02X1476715Y686758I-2002J0D01*
G01X1473077Y684657D01*
G02X1472078Y684390I-999J1736D01*
G01X1472076D01*
G02X1470074Y686392I0J2002D01*
G02X1471075Y688126I2002J0D01*
G01X1474713Y690227D01*
G02X1475712Y690494I999J-1736D01*
G01X1475714D01*
G02X1477716Y688492I0J-2002D01*
G37*
G36*
G01Y673992D02*
G02X1476715Y672258I-2002J0D01*
G01X1473077Y670157D01*
G02X1472078Y669890I-999J1736D01*
G01X1472076D01*
G02X1470074Y671892I0J2002D01*
G02X1471075Y673626I2002J0D01*
G01X1474713Y675727D01*
G02X1475712Y675994I999J-1736D01*
G01X1475714D01*
G02X1477716Y673992I0J-2002D01*
G37*
G36*
G01Y659492D02*
G02X1476715Y657758I-2002J0D01*
G01X1473077Y655657D01*
G02X1472078Y655390I-999J1736D01*
G01X1472076D01*
G02X1470074Y657392I0J2002D01*
G02X1471075Y659126I2002J0D01*
G01X1474713Y661227D01*
G02X1475712Y661494I999J-1736D01*
G01X1475714D01*
G02X1477716Y659492I0J-2002D01*
G37*
G36*
G01X1455174Y716992D02*
G02X1457176Y718994I2002J0D01*
G01X1457178D01*
G02X1458177Y718727I0J-2003D01*
G01X1461815Y716626D01*
G02X1462816Y714892I-1001J-1734D01*
G02X1460814Y712890I-2002J0D01*
G01X1460812D01*
G02X1459813Y713157I0J2003D01*
G01X1456175Y715258D01*
G02X1455174Y716992I1001J1734D01*
G37*
G36*
G01Y704992D02*
G02X1457176Y706994I2002J0D01*
G01X1457178D01*
G02X1458177Y706727I0J-2003D01*
G01X1461815Y704626D01*
G02X1462816Y702892I-1001J-1734D01*
G02X1460814Y700890I-2002J0D01*
G01X1460812D01*
G02X1459813Y701157I0J2003D01*
G01X1456175Y703258D01*
G02X1455174Y704992I1001J1734D01*
G37*
G36*
G01Y692992D02*
G02X1457176Y694994I2002J0D01*
G01X1457178D01*
G02X1458177Y694727I0J-2003D01*
G01X1461815Y692626D01*
G02X1462816Y690892I-1001J-1734D01*
G02X1460814Y688890I-2002J0D01*
G01X1460812D01*
G02X1459813Y689157I0J2003D01*
G01X1456175Y691258D01*
G02X1455174Y692992I1001J1734D01*
G37*
G36*
G01Y680992D02*
G02X1457176Y682994I2002J0D01*
G01X1457178D01*
G02X1458177Y682727I0J-2003D01*
G01X1461815Y680626D01*
G02X1462816Y678892I-1001J-1734D01*
G02X1460814Y676890I-2002J0D01*
G01X1460812D01*
G02X1459813Y677157I0J2003D01*
G01X1456175Y679258D01*
G02X1455174Y680992I1001J1734D01*
G37*
G36*
G01Y668992D02*
G02X1457176Y670994I2002J0D01*
G01X1457178D01*
G02X1458177Y670727I0J-2003D01*
G01X1461815Y668626D01*
G02X1462816Y666892I-1001J-1734D01*
G02X1460814Y664890I-2002J0D01*
G01X1460812D01*
G02X1459813Y665157I0J2003D01*
G01X1456175Y667258D01*
G02X1455174Y668992I1001J1734D01*
G37*
G36*
G01Y656992D02*
G02X1457176Y658994I2002J0D01*
G01X1457178D01*
G02X1458177Y658727I0J-2003D01*
G01X1461815Y656626D01*
G02X1462816Y654892I-1001J-1734D01*
G02X1460814Y652890I-2002J0D01*
G01X1460812D01*
G02X1459813Y653157I0J2003D01*
G01X1456175Y655258D01*
G02X1455174Y656992I1001J1734D01*
G37*
G36*
G01X1390978Y737198D02*
G02X1389977Y735464I-2002J0D01*
G01X1386339Y733363D01*
G02X1385340Y733096I-999J1736D01*
G01X1385338D01*
G02X1383336Y735098I0J2002D01*
G02X1384337Y736832I2002J0D01*
G01X1387975Y738933D01*
G02X1388974Y739200I999J-1736D01*
G01X1388976D01*
G02X1390978Y737198I0J-2002D01*
G37*
G36*
G01X1395208Y722735D02*
G02X1394207Y721001I-2002J0D01*
G01X1390569Y718900D01*
G02X1389570Y718632I-1001J1735D01*
G01X1389568D01*
G02X1387566Y720635I1J2003D01*
G02X1388567Y722369I2002J0D01*
G01X1392205Y724470D01*
G02X1393204Y724738I1001J-1735D01*
G01X1393206D01*
G02X1395208Y722735I-1J-2003D01*
G37*
G36*
G01Y693708D02*
G02X1394207Y691974I-2002J0D01*
G01X1390569Y689873D01*
G02X1389570Y689606I-999J1736D01*
G01X1389568D01*
G02X1387566Y691608I0J2002D01*
G02X1388567Y693342I2002J0D01*
G01X1392205Y695443D01*
G02X1393204Y695710I999J-1736D01*
G01X1393206D01*
G02X1395208Y693708I0J-2002D01*
G37*
G36*
G01Y708208D02*
G02X1394207Y706474I-2002J0D01*
G01X1390569Y704373D01*
G02X1389570Y704106I-999J1736D01*
G01X1389568D01*
G02X1387566Y706108I0J2002D01*
G02X1388567Y707842I2002J0D01*
G01X1392205Y709943D01*
G02X1393204Y710210I999J-1736D01*
G01X1393206D01*
G02X1395208Y708208I0J-2002D01*
G37*
G36*
G01Y679208D02*
G02X1394207Y677474I-2002J0D01*
G01X1390569Y675373D01*
G02X1389570Y675106I-999J1736D01*
G01X1389568D01*
G02X1387566Y677108I0J2002D01*
G02X1388567Y678842I2002J0D01*
G01X1392205Y680943D01*
G02X1393204Y681210I999J-1736D01*
G01X1393206D01*
G02X1395208Y679208I0J-2002D01*
G37*
G36*
G01Y664708D02*
G02X1394207Y662974I-2002J0D01*
G01X1390569Y660873D01*
G02X1389570Y660606I-999J1736D01*
G01X1389568D01*
G02X1387566Y662608I0J2002D01*
G02X1388567Y664342I2002J0D01*
G01X1392205Y666443D01*
G02X1393204Y666710I999J-1736D01*
G01X1393206D01*
G02X1395208Y664708I0J-2002D01*
G37*
G36*
G01X1372666Y719708D02*
G02X1374668Y721710I2002J0D01*
G01X1374670D01*
G02X1375669Y721443I0J-2003D01*
G01X1379307Y719342D01*
G02X1380308Y717608I-1001J-1734D01*
G02X1378306Y715606I-2002J0D01*
G01X1378304D01*
G02X1377305Y715873I0J2003D01*
G01X1373667Y717974D01*
G02X1372666Y719708I1001J1734D01*
G37*
G36*
G01Y695708D02*
G02X1374668Y697710I2002J0D01*
G01X1374670D01*
G02X1375669Y697443I0J-2003D01*
G01X1379307Y695342D01*
G02X1380308Y693608I-1001J-1734D01*
G02X1378306Y691606I-2002J0D01*
G01X1378304D01*
G02X1377305Y691873I0J2003D01*
G01X1373667Y693974D01*
G02X1372666Y695708I1001J1734D01*
G37*
G36*
G01Y707708D02*
G02X1374668Y709710I2002J0D01*
G01X1374670D01*
G02X1375669Y709443I0J-2003D01*
G01X1379307Y707342D01*
G02X1380308Y705608I-1001J-1734D01*
G02X1378306Y703606I-2002J0D01*
G01X1378304D01*
G02X1377305Y703873I0J2003D01*
G01X1373667Y705974D01*
G02X1372666Y707708I1001J1734D01*
G37*
G36*
G01Y683708D02*
G02X1374668Y685710I2002J0D01*
G01X1374670D01*
G02X1375669Y685443I0J-2003D01*
G01X1379307Y683342D01*
G02X1380308Y681608I-1001J-1734D01*
G02X1378306Y679606I-2002J0D01*
G01X1378304D01*
G02X1377305Y679873I0J2003D01*
G01X1373667Y681974D01*
G02X1372666Y683708I1001J1734D01*
G37*
G36*
G01Y671708D02*
G02X1374668Y673710I2002J0D01*
G01X1374670D01*
G02X1375669Y673443I0J-2003D01*
G01X1379307Y671342D01*
G02X1380308Y669608I-1001J-1734D01*
G02X1378306Y667606I-2002J0D01*
G01X1378304D01*
G02X1377305Y667873I0J2003D01*
G01X1373667Y669974D01*
G02X1372666Y671708I1001J1734D01*
G37*
G36*
G01Y659708D02*
G02X1374668Y661710I2002J0D01*
G01X1374670D01*
G02X1375669Y661443I0J-2003D01*
G01X1379307Y659342D01*
G02X1380308Y657608I-1001J-1734D01*
G02X1378306Y655606I-2002J0D01*
G01X1378304D01*
G02X1377305Y655873I0J2003D01*
G01X1373667Y657974D01*
G02X1372666Y659708I1001J1734D01*
G37*
G36*
G01X146312Y1571028D02*
X149712D01*
G02Y1568022I0J-1503D01*
G01X146312D01*
G02Y1571028I0J1503D01*
G37*
G36*
G01X1701934Y76800D02*
X1705334D01*
G02Y73794I0J-1503D01*
G01X1701934D01*
G02Y76800I0J1503D01*
G37*
G36*
G01X1690934Y70800D02*
X1694334D01*
G02Y67794I0J-1503D01*
G01X1690934D01*
G02Y70800I0J1503D01*
G37*
G36*
G01X1679934Y76800D02*
X1683334D01*
G02Y73794I0J-1503D01*
G01X1679934D01*
G02Y76800I0J1503D01*
G37*
G36*
G01X1657800D02*
X1661200D01*
G02Y73794I0J-1503D01*
G01X1657800D01*
G02Y76800I0J1503D01*
G37*
G36*
G01X1668800Y70800D02*
X1672200D01*
G02Y67794I0J-1503D01*
G01X1668800D01*
G02Y70800I0J1503D01*
G37*
G36*
G01X1646800D02*
X1650200D01*
G02Y67794I0J-1503D01*
G01X1646800D01*
G02Y70800I0J1503D01*
G37*
G36*
G01X1635800Y76800D02*
X1639200D01*
G02Y73794I0J-1503D01*
G01X1635800D01*
G02Y76800I0J1503D01*
G37*
G36*
G01X1612596D02*
X1615996D01*
G02Y73794I0J-1503D01*
G01X1612596D01*
G02Y76800I0J1503D01*
G37*
G36*
G01X1623596Y70800D02*
X1626996D01*
G02Y67794I0J-1503D01*
G01X1623596D01*
G02Y70800I0J1503D01*
G37*
G36*
G01X1601596D02*
X1604996D01*
G02Y67794I0J-1503D01*
G01X1601596D01*
G02Y70800I0J1503D01*
G37*
G36*
G01X1590596Y76800D02*
X1593996D01*
G02Y73794I0J-1503D01*
G01X1590596D01*
G02Y76800I0J1503D01*
G37*
G36*
G01X1579596Y70800D02*
X1582996D01*
G02Y67794I0J-1503D01*
G01X1579596D01*
G02Y70800I0J1503D01*
G37*
G36*
G01X1568596Y76800D02*
X1571996D01*
G02Y73794I0J-1503D01*
G01X1568596D01*
G02Y76800I0J1503D01*
G37*
G36*
G01X1546596D02*
X1549996D01*
G02Y73794I0J-1503D01*
G01X1546596D01*
G02Y76800I0J1503D01*
G37*
G36*
G01X1557596Y70800D02*
X1560996D01*
G02Y67794I0J-1503D01*
G01X1557596D01*
G02Y70800I0J1503D01*
G37*
G36*
G01X1535596D02*
X1538996D01*
G02Y67794I0J-1503D01*
G01X1535596D01*
G02Y70800I0J1503D01*
G37*
G36*
G01X230895Y73838D02*
X227495D01*
G02Y76842I0J1502D01*
G01X230895D01*
G02Y73838I0J-1502D01*
G37*
G36*
G01X219895Y67838D02*
X216495D01*
G02Y70842I0J1502D01*
G01X219895D01*
G02Y67838I0J-1502D01*
G37*
G36*
G01X208895Y73838D02*
X205495D01*
G02Y76842I0J1502D01*
G01X208895D01*
G02Y73838I0J-1502D01*
G37*
G36*
G01X194361Y70842D02*
X197761D01*
G02Y67838I0J-1502D01*
G01X194361D01*
G02Y70842I0J1502D01*
G37*
G36*
G01X183361Y76842D02*
X186761D01*
G02Y73838I0J-1502D01*
G01X183361D01*
G02Y76842I0J1502D01*
G37*
G36*
G01X161361D02*
X164761D01*
G02Y73838I0J-1502D01*
G01X161361D01*
G02Y76842I0J1502D01*
G37*
G36*
G01X172361Y70842D02*
X175761D01*
G02Y67838I0J-1502D01*
G01X172361D01*
G02Y70842I0J1502D01*
G37*
G36*
G01X149157D02*
X152557D01*
G02Y67838I0J-1502D01*
G01X149157D01*
G02Y70842I0J1502D01*
G37*
G36*
G01X138157Y76842D02*
X141557D01*
G02Y73838I0J-1502D01*
G01X138157D01*
G02Y76842I0J1502D01*
G37*
G36*
G01X116157D02*
X119557D01*
G02Y73838I0J-1502D01*
G01X116157D01*
G02Y76842I0J1502D01*
G37*
G36*
G01X127157Y70842D02*
X130557D01*
G02Y67838I0J-1502D01*
G01X127157D01*
G02Y70842I0J1502D01*
G37*
G36*
G01X105157D02*
X108557D01*
G02Y67838I0J-1502D01*
G01X105157D01*
G02Y70842I0J1502D01*
G37*
G36*
G01X94157Y76842D02*
X97557D01*
G02Y73838I0J-1502D01*
G01X94157D01*
G02Y76842I0J1502D01*
G37*
G36*
G01X83157Y70842D02*
X86557D01*
G02Y67838I0J-1502D01*
G01X83157D01*
G02Y70842I0J1502D01*
G37*
G36*
G01X72157Y76842D02*
X75557D01*
G02Y73838I0J-1502D01*
G01X72157D01*
G02Y76842I0J1502D01*
G37*
G36*
G01X61157Y70842D02*
X64557D01*
G02Y67838I0J-1502D01*
G01X61157D01*
G02Y70842I0J1502D01*
G37*
G36*
G01X1619075Y1579684D02*
X1622475D01*
G02Y1576680I0J-1502D01*
G01X1619075D01*
G02Y1579684I0J1502D01*
G37*
G36*
G01X326857Y1603882D02*
X330257D01*
G02Y1600878I0J-1502D01*
G01X326857D01*
G02Y1603882I0J1502D01*
G37*
G36*
G01X363037Y1615794D02*
X366437D01*
G02Y1612790I0J-1502D01*
G01X363037D01*
G02Y1615794I0J1502D01*
G37*
G36*
G01X545411Y1579684D02*
X548811D01*
G02Y1576680I0J-1502D01*
G01X545411D01*
G02Y1579684I0J1502D01*
G37*
G36*
G01Y1591596D02*
X548811D01*
G02Y1588592I0J-1502D01*
G01X545411D01*
G02Y1591596I0J1502D01*
G37*
G36*
G01X1377672D02*
X1381072D01*
G02Y1588592I0J-1502D01*
G01X1377672D01*
G02Y1591596I0J1502D01*
G37*
G36*
G01X533351D02*
X536751D01*
G02Y1588592I0J-1502D01*
G01X533351D01*
G02Y1591596I0J1502D01*
G37*
G36*
G01Y1579684D02*
X536751D01*
G02Y1576680I0J-1502D01*
G01X533351D01*
G02Y1579684I0J1502D01*
G37*
G36*
G01X1594955Y1591596D02*
X1598355D01*
G02Y1588592I0J-1502D01*
G01X1594955D01*
G02Y1591596I0J1502D01*
G37*
G36*
G01X581591D02*
X584991D01*
G02Y1588592I0J-1502D01*
G01X581591D01*
G02Y1591596I0J1502D01*
G37*
G36*
G01Y1579684D02*
X584991D01*
G02Y1576680I0J-1502D01*
G01X581591D01*
G02Y1579684I0J1502D01*
G37*
G36*
G01X1594955D02*
X1598355D01*
G02Y1576680I0J-1502D01*
G01X1594955D01*
G02Y1579684I0J1502D01*
G37*
G36*
G01X605711Y1591596D02*
X609111D01*
G02Y1588592I0J-1502D01*
G01X605711D01*
G02Y1591596I0J1502D01*
G37*
G36*
G01X333617Y1579684D02*
X337017D01*
G02Y1576680I0J-1502D01*
G01X333617D01*
G02Y1579684I0J1502D01*
G37*
G36*
G01X345677D02*
X349077D01*
G02Y1576680I0J-1502D01*
G01X345677D01*
G02Y1579684I0J1502D01*
G37*
G36*
G01X617771D02*
X621171D01*
G02Y1576680I0J-1502D01*
G01X617771D01*
G02Y1579684I0J1502D01*
G37*
G36*
G01Y1591596D02*
X621171D01*
G02Y1588592I0J-1502D01*
G01X617771D01*
G02Y1591596I0J1502D01*
G37*
G36*
G01X629831Y1579684D02*
X633231D01*
G02Y1576680I0J-1502D01*
G01X629831D01*
G02Y1579684I0J1502D01*
G37*
G36*
G01X1582895D02*
X1586295D01*
G02Y1576680I0J-1502D01*
G01X1582895D01*
G02Y1579684I0J1502D01*
G37*
G36*
G01X1570835D02*
X1574235D01*
G02Y1576680I0J-1502D01*
G01X1570835D01*
G02Y1579684I0J1502D01*
G37*
G36*
G01X1558775D02*
X1562175D01*
G02Y1576680I0J-1502D01*
G01X1558775D01*
G02Y1579684I0J1502D01*
G37*
G36*
G01X321557D02*
X324957D01*
G02Y1576680I0J-1502D01*
G01X321557D01*
G02Y1579684I0J1502D01*
G37*
G36*
G01X278617Y1603882D02*
X282017D01*
G02Y1600878I0J-1502D01*
G01X278617D01*
G02Y1603882I0J1502D01*
G37*
G36*
G01X1534655Y1591596D02*
X1538055D01*
G02Y1588592I0J-1502D01*
G01X1534655D01*
G02Y1591596I0J1502D01*
G37*
G36*
G01Y1579684D02*
X1538055D01*
G02Y1576680I0J-1502D01*
G01X1534655D01*
G02Y1579684I0J1502D01*
G37*
G36*
G01X1510535Y1591596D02*
X1513935D01*
G02Y1588592I0J-1502D01*
G01X1510535D01*
G02Y1591596I0J1502D01*
G37*
G36*
G01X1522595D02*
X1525995D01*
G02Y1588592I0J-1502D01*
G01X1522595D01*
G02Y1591596I0J1502D01*
G37*
G36*
G01X309497Y1579684D02*
X312897D01*
G02Y1576680I0J-1502D01*
G01X309497D01*
G02Y1579684I0J1502D01*
G37*
G36*
G01X302737Y1603882D02*
X306137D01*
G02Y1600878I0J-1502D01*
G01X302737D01*
G02Y1603882I0J1502D01*
G37*
G36*
G01X1498475Y1579684D02*
X1501875D01*
G02Y1576680I0J-1502D01*
G01X1498475D01*
G02Y1579684I0J1502D01*
G37*
G36*
G01X314797Y1615794D02*
X318197D01*
G02Y1612790I0J-1502D01*
G01X314797D01*
G02Y1615794I0J1502D01*
G37*
G36*
G01X278617D02*
X282017D01*
G02Y1612790I0J-1502D01*
G01X278617D01*
G02Y1615794I0J1502D01*
G37*
G36*
G01X497171Y1591596D02*
X500571D01*
G02Y1588592I0J-1502D01*
G01X497171D01*
G02Y1591596I0J1502D01*
G37*
G36*
G01X509231D02*
X512631D01*
G02Y1588592I0J-1502D01*
G01X509231D01*
G02Y1591596I0J1502D01*
G37*
G36*
G01Y1579684D02*
X512631D01*
G02Y1576680I0J-1502D01*
G01X509231D01*
G02Y1579684I0J1502D01*
G37*
G36*
G01X1486415Y1591596D02*
X1489815D01*
G02Y1588592I0J-1502D01*
G01X1486415D01*
G02Y1591596I0J1502D01*
G37*
G36*
G01Y1579684D02*
X1489815D01*
G02Y1576680I0J-1502D01*
G01X1486415D01*
G02Y1579684I0J1502D01*
G37*
G36*
G01X321557Y1591596D02*
X324957D01*
G02Y1588592I0J-1502D01*
G01X321557D01*
G02Y1591596I0J1502D01*
G37*
G36*
G01X1462295D02*
X1465695D01*
G02Y1588592I0J-1502D01*
G01X1462295D01*
G02Y1591596I0J1502D01*
G37*
G36*
G01X1474355D02*
X1477755D01*
G02Y1588592I0J-1502D01*
G01X1474355D01*
G02Y1591596I0J1502D01*
G37*
G36*
G01X641891Y1579684D02*
X645291D01*
G02Y1576680I0J-1502D01*
G01X641891D01*
G02Y1579684I0J1502D01*
G37*
G36*
G01Y1591596D02*
X645291D01*
G02Y1588592I0J-1502D01*
G01X641891D01*
G02Y1591596I0J1502D01*
G37*
G36*
G01X285377Y1579684D02*
X288777D01*
G02Y1576680I0J-1502D01*
G01X285377D01*
G02Y1579684I0J1502D01*
G37*
G36*
G01X1462295D02*
X1465695D01*
G02Y1576680I0J-1502D01*
G01X1462295D01*
G02Y1579684I0J1502D01*
G37*
G36*
G01X206257Y1615794D02*
X209657D01*
G02Y1612790I0J-1502D01*
G01X206257D01*
G02Y1615794I0J1502D01*
G37*
G36*
G01X338917D02*
X342317D01*
G02Y1612790I0J-1502D01*
G01X338917D01*
G02Y1615794I0J1502D01*
G37*
G36*
G01X1474355Y1579684D02*
X1477755D01*
G02Y1576680I0J-1502D01*
G01X1474355D01*
G02Y1579684I0J1502D01*
G37*
G36*
G01X261257D02*
X264657D01*
G02Y1576680I0J-1502D01*
G01X261257D01*
G02Y1579684I0J1502D01*
G37*
G36*
G01X485111D02*
X488511D01*
G02Y1576680I0J-1502D01*
G01X485111D01*
G02Y1579684I0J1502D01*
G37*
G36*
G01Y1591596D02*
X488511D01*
G02Y1588592I0J-1502D01*
G01X485111D01*
G02Y1591596I0J1502D01*
G37*
G36*
G01X338917Y1603882D02*
X342317D01*
G02Y1600878I0J-1502D01*
G01X338917D01*
G02Y1603882I0J1502D01*
G37*
G36*
G01X1648495Y1615794D02*
X1651895D01*
G02Y1612790I0J-1502D01*
G01X1648495D01*
G02Y1615794I0J1502D01*
G37*
G36*
G01Y1603882D02*
X1651895D01*
G02Y1600878I0J-1502D01*
G01X1648495D01*
G02Y1603882I0J1502D01*
G37*
G36*
G01X1624375Y1615794D02*
X1627775D01*
G02Y1612790I0J-1502D01*
G01X1624375D01*
G02Y1615794I0J1502D01*
G37*
G36*
G01X266557D02*
X269957D01*
G02Y1612790I0J-1502D01*
G01X266557D01*
G02Y1615794I0J1502D01*
G37*
G36*
G01X254497Y1603882D02*
X257897D01*
G02Y1600878I0J-1502D01*
G01X254497D01*
G02Y1603882I0J1502D01*
G37*
G36*
G01X653951Y1591596D02*
X657351D01*
G02Y1588592I0J-1502D01*
G01X653951D01*
G02Y1591596I0J1502D01*
G37*
G36*
G01Y1579684D02*
X657351D01*
G02Y1576680I0J-1502D01*
G01X653951D01*
G02Y1579684I0J1502D01*
G37*
G36*
G01X369797Y1591596D02*
X373197D01*
G02Y1588592I0J-1502D01*
G01X369797D01*
G02Y1591596I0J1502D01*
G37*
G36*
G01X1636435Y1603882D02*
X1639835D01*
G02Y1600878I0J-1502D01*
G01X1636435D01*
G02Y1603882I0J1502D01*
G37*
G36*
G01X266557D02*
X269957D01*
G02Y1600878I0J-1502D01*
G01X266557D01*
G02Y1603882I0J1502D01*
G37*
G36*
G01X1624375D02*
X1627775D01*
G02Y1600878I0J-1502D01*
G01X1624375D01*
G02Y1603882I0J1502D01*
G37*
G36*
G01X254497Y1615794D02*
X257897D01*
G02Y1612790I0J-1502D01*
G01X254497D01*
G02Y1615794I0J1502D01*
G37*
G36*
G01X194197Y1603882D02*
X197597D01*
G02Y1600878I0J-1502D01*
G01X194197D01*
G02Y1603882I0J1502D01*
G37*
G36*
G01X242437D02*
X245837D01*
G02Y1600878I0J-1502D01*
G01X242437D01*
G02Y1603882I0J1502D01*
G37*
G36*
G01X1612315D02*
X1615715D01*
G02Y1600878I0J-1502D01*
G01X1612315D01*
G02Y1603882I0J1502D01*
G37*
G36*
G01Y1615794D02*
X1615715D01*
G02Y1612790I0J-1502D01*
G01X1612315D01*
G02Y1615794I0J1502D01*
G37*
G36*
G01X230377D02*
X233777D01*
G02Y1612790I0J-1502D01*
G01X230377D01*
G02Y1615794I0J1502D01*
G37*
G36*
G01X521291Y1579684D02*
X524691D01*
G02Y1576680I0J-1502D01*
G01X521291D01*
G02Y1579684I0J1502D01*
G37*
G36*
G01Y1591596D02*
X524691D01*
G02Y1588592I0J-1502D01*
G01X521291D01*
G02Y1591596I0J1502D01*
G37*
G36*
G01X497171Y1579684D02*
X500571D01*
G02Y1576680I0J-1502D01*
G01X497171D01*
G02Y1579684I0J1502D01*
G37*
G36*
G01X593651D02*
X597051D01*
G02Y1576680I0J-1502D01*
G01X593651D01*
G02Y1579684I0J1502D01*
G37*
G36*
G01Y1591596D02*
X597051D01*
G02Y1588592I0J-1502D01*
G01X593651D01*
G02Y1591596I0J1502D01*
G37*
G36*
G01X1600255Y1603882D02*
X1603655D01*
G02Y1600878I0J-1502D01*
G01X1600255D01*
G02Y1603882I0J1502D01*
G37*
G36*
G01Y1615794D02*
X1603655D01*
G02Y1612790I0J-1502D01*
G01X1600255D01*
G02Y1615794I0J1502D01*
G37*
G36*
G01X557471Y1579684D02*
X560871D01*
G02Y1576680I0J-1502D01*
G01X557471D01*
G02Y1579684I0J1502D01*
G37*
G36*
G01X569531D02*
X572931D01*
G02Y1576680I0J-1502D01*
G01X569531D01*
G02Y1579684I0J1502D01*
G37*
G36*
G01Y1591596D02*
X572931D01*
G02Y1588592I0J-1502D01*
G01X569531D01*
G02Y1591596I0J1502D01*
G37*
G36*
G01X557471D02*
X560871D01*
G02Y1588592I0J-1502D01*
G01X557471D01*
G02Y1591596I0J1502D01*
G37*
G36*
G01X333617D02*
X337017D01*
G02Y1588592I0J-1502D01*
G01X333617D01*
G02Y1591596I0J1502D01*
G37*
G36*
G01X345677D02*
X349077D01*
G02Y1588592I0J-1502D01*
G01X345677D01*
G02Y1591596I0J1502D01*
G37*
G36*
G01X1607015Y1579684D02*
X1610415D01*
G02Y1576680I0J-1502D01*
G01X1607015D01*
G02Y1579684I0J1502D01*
G37*
G36*
G01X1576135Y1615794D02*
X1579535D01*
G02Y1612790I0J-1502D01*
G01X1576135D01*
G02Y1615794I0J1502D01*
G37*
G36*
G01X314797Y1603882D02*
X318197D01*
G02Y1600878I0J-1502D01*
G01X314797D01*
G02Y1603882I0J1502D01*
G37*
G36*
G01X1576135D02*
X1579535D01*
G02Y1600878I0J-1502D01*
G01X1576135D01*
G02Y1603882I0J1502D01*
G37*
G36*
G01X261257Y1591596D02*
X264657D01*
G02Y1588592I0J-1502D01*
G01X261257D01*
G02Y1591596I0J1502D01*
G37*
G36*
G01X357737Y1579684D02*
X361137D01*
G02Y1576680I0J-1502D01*
G01X357737D01*
G02Y1579684I0J1502D01*
G37*
G36*
G01X1546715Y1591596D02*
X1550115D01*
G02Y1588592I0J-1502D01*
G01X1546715D01*
G02Y1591596I0J1502D01*
G37*
G36*
G01Y1579684D02*
X1550115D01*
G02Y1576680I0J-1502D01*
G01X1546715D01*
G02Y1579684I0J1502D01*
G37*
G36*
G01X326857Y1615794D02*
X330257D01*
G02Y1612790I0J-1502D01*
G01X326857D01*
G02Y1615794I0J1502D01*
G37*
G36*
G01X249197Y1591596D02*
X252597D01*
G02Y1588592I0J-1502D01*
G01X249197D01*
G02Y1591596I0J1502D01*
G37*
G36*
G01X309497D02*
X312897D01*
G02Y1588592I0J-1502D01*
G01X309497D01*
G02Y1591596I0J1502D01*
G37*
G36*
G01X1564075Y1603882D02*
X1567475D01*
G02Y1600878I0J-1502D01*
G01X1564075D01*
G02Y1603882I0J1502D01*
G37*
G36*
G01Y1615794D02*
X1567475D01*
G02Y1612790I0J-1502D01*
G01X1564075D01*
G02Y1615794I0J1502D01*
G37*
G36*
G01X1552015D02*
X1555415D01*
G02Y1612790I0J-1502D01*
G01X1552015D01*
G02Y1615794I0J1502D01*
G37*
G36*
G01X1503775D02*
X1507175D01*
G02Y1612790I0J-1502D01*
G01X1503775D01*
G02Y1615794I0J1502D01*
G37*
G36*
G01X1552015Y1603882D02*
X1555415D01*
G02Y1600878I0J-1502D01*
G01X1552015D01*
G02Y1603882I0J1502D01*
G37*
G36*
G01X629831Y1591596D02*
X633231D01*
G02Y1588592I0J-1502D01*
G01X629831D01*
G02Y1591596I0J1502D01*
G37*
G36*
G01X1377672Y1579684D02*
X1381072D01*
G02Y1576680I0J-1502D01*
G01X1377672D01*
G02Y1579684I0J1502D01*
G37*
G36*
G01X218317Y1603882D02*
X221717D01*
G02Y1600878I0J-1502D01*
G01X218317D01*
G02Y1603882I0J1502D01*
G37*
G36*
G01X206257D02*
X209657D01*
G02Y1600878I0J-1502D01*
G01X206257D01*
G02Y1603882I0J1502D01*
G37*
G36*
G01X1527895Y1615794D02*
X1531295D01*
G02Y1612790I0J-1502D01*
G01X1527895D01*
G02Y1615794I0J1502D01*
G37*
G36*
G01X200957Y1591596D02*
X204357D01*
G02Y1588592I0J-1502D01*
G01X200957D01*
G02Y1591596I0J1502D01*
G37*
G36*
G01X1631135D02*
X1634535D01*
G02Y1588592I0J-1502D01*
G01X1631135D01*
G02Y1591596I0J1502D01*
G37*
G36*
G01X1539955Y1615794D02*
X1543355D01*
G02Y1612790I0J-1502D01*
G01X1539955D01*
G02Y1615794I0J1502D01*
G37*
G36*
G01Y1603882D02*
X1543355D01*
G02Y1600878I0J-1502D01*
G01X1539955D01*
G02Y1603882I0J1502D01*
G37*
G36*
G01X1527895D02*
X1531295D01*
G02Y1600878I0J-1502D01*
G01X1527895D01*
G02Y1603882I0J1502D01*
G37*
G36*
G01X302737Y1615794D02*
X306137D01*
G02Y1612790I0J-1502D01*
G01X302737D01*
G02Y1615794I0J1502D01*
G37*
G36*
G01X1522595Y1579684D02*
X1525995D01*
G02Y1576680I0J-1502D01*
G01X1522595D01*
G02Y1579684I0J1502D01*
G37*
G36*
G01X1515835Y1615794D02*
X1519235D01*
G02Y1612790I0J-1502D01*
G01X1515835D01*
G02Y1615794I0J1502D01*
G37*
G36*
G01X1636435D02*
X1639835D01*
G02Y1612790I0J-1502D01*
G01X1636435D01*
G02Y1615794I0J1502D01*
G37*
G36*
G01X1498475Y1591596D02*
X1501875D01*
G02Y1588592I0J-1502D01*
G01X1498475D01*
G02Y1591596I0J1502D01*
G37*
G36*
G01X1643195D02*
X1646595D01*
G02Y1588592I0J-1502D01*
G01X1643195D01*
G02Y1591596I0J1502D01*
G37*
G36*
G01X1515835Y1603882D02*
X1519235D01*
G02Y1600878I0J-1502D01*
G01X1515835D01*
G02Y1603882I0J1502D01*
G37*
G36*
G01X357737Y1591596D02*
X361137D01*
G02Y1588592I0J-1502D01*
G01X357737D01*
G02Y1591596I0J1502D01*
G37*
G36*
G01X194197Y1615794D02*
X197597D01*
G02Y1612790I0J-1502D01*
G01X194197D01*
G02Y1615794I0J1502D01*
G37*
G36*
G01X1510535Y1579684D02*
X1513935D01*
G02Y1576680I0J-1502D01*
G01X1510535D01*
G02Y1579684I0J1502D01*
G37*
G36*
G01X1570835Y1591596D02*
X1574235D01*
G02Y1588592I0J-1502D01*
G01X1570835D01*
G02Y1591596I0J1502D01*
G37*
G36*
G01X273317D02*
X276717D01*
G02Y1588592I0J-1502D01*
G01X273317D01*
G02Y1591596I0J1502D01*
G37*
G36*
G01Y1579684D02*
X276717D01*
G02Y1576680I0J-1502D01*
G01X273317D01*
G02Y1579684I0J1502D01*
G37*
G36*
G01X1491715Y1603882D02*
X1495115D01*
G02Y1600878I0J-1502D01*
G01X1491715D01*
G02Y1603882I0J1502D01*
G37*
G36*
G01Y1615794D02*
X1495115D01*
G02Y1612790I0J-1502D01*
G01X1491715D01*
G02Y1615794I0J1502D01*
G37*
G36*
G01X1631135Y1579684D02*
X1634535D01*
G02Y1576680I0J-1502D01*
G01X1631135D01*
G02Y1579684I0J1502D01*
G37*
G36*
G01X213017Y1591596D02*
X216417D01*
G02Y1588592I0J-1502D01*
G01X213017D01*
G02Y1591596I0J1502D01*
G37*
G36*
G01X188897Y1579684D02*
X192297D01*
G02Y1576680I0J-1502D01*
G01X188897D01*
G02Y1579684I0J1502D01*
G37*
G36*
G01X1503775Y1603882D02*
X1507175D01*
G02Y1600878I0J-1502D01*
G01X1503775D01*
G02Y1603882I0J1502D01*
G37*
G36*
G01X200957Y1579684D02*
X204357D01*
G02Y1576680I0J-1502D01*
G01X200957D01*
G02Y1579684I0J1502D01*
G37*
G36*
G01X605711D02*
X609111D01*
G02Y1576680I0J-1502D01*
G01X605711D01*
G02Y1579684I0J1502D01*
G37*
G36*
G01X1479655Y1603882D02*
X1483055D01*
G02Y1600878I0J-1502D01*
G01X1479655D01*
G02Y1603882I0J1502D01*
G37*
G36*
G01Y1615794D02*
X1483055D01*
G02Y1612790I0J-1502D01*
G01X1479655D01*
G02Y1615794I0J1502D01*
G37*
G36*
G01X249197Y1579684D02*
X252597D01*
G02Y1576680I0J-1502D01*
G01X249197D01*
G02Y1579684I0J1502D01*
G37*
G36*
G01X1467595Y1615794D02*
X1470995D01*
G02Y1612790I0J-1502D01*
G01X1467595D01*
G02Y1615794I0J1502D01*
G37*
G36*
G01Y1603882D02*
X1470995D01*
G02Y1600878I0J-1502D01*
G01X1467595D01*
G02Y1603882I0J1502D01*
G37*
G36*
G01X1558775Y1591596D02*
X1562175D01*
G02Y1588592I0J-1502D01*
G01X1558775D01*
G02Y1591596I0J1502D01*
G37*
G36*
G01X1643195Y1579684D02*
X1646595D01*
G02Y1576680I0J-1502D01*
G01X1643195D01*
G02Y1579684I0J1502D01*
G37*
G36*
G01X188897Y1591596D02*
X192297D01*
G02Y1588592I0J-1502D01*
G01X188897D01*
G02Y1591596I0J1502D01*
G37*
G36*
G01X1607015D02*
X1610415D01*
G02Y1588592I0J-1502D01*
G01X1607015D01*
G02Y1591596I0J1502D01*
G37*
G36*
G01X1582895D02*
X1586295D01*
G02Y1588592I0J-1502D01*
G01X1582895D01*
G02Y1591596I0J1502D01*
G37*
G36*
G01X225077Y1579684D02*
X228477D01*
G02Y1576680I0J-1502D01*
G01X225077D01*
G02Y1579684I0J1502D01*
G37*
G36*
G01Y1591596D02*
X228477D01*
G02Y1588592I0J-1502D01*
G01X225077D01*
G02Y1591596I0J1502D01*
G37*
G36*
G01X218317Y1615794D02*
X221717D01*
G02Y1612790I0J-1502D01*
G01X218317D01*
G02Y1615794I0J1502D01*
G37*
G36*
G01X290677Y1603882D02*
X294077D01*
G02Y1600878I0J-1502D01*
G01X290677D01*
G02Y1603882I0J1502D01*
G37*
G36*
G01Y1615794D02*
X294077D01*
G02Y1612790I0J-1502D01*
G01X290677D01*
G02Y1615794I0J1502D01*
G37*
G36*
G01X237137Y1579684D02*
X240537D01*
G02Y1576680I0J-1502D01*
G01X237137D01*
G02Y1579684I0J1502D01*
G37*
G36*
G01X213017D02*
X216417D01*
G02Y1576680I0J-1502D01*
G01X213017D01*
G02Y1579684I0J1502D01*
G37*
G36*
G01X230377Y1603882D02*
X233777D01*
G02Y1600878I0J-1502D01*
G01X230377D01*
G02Y1603882I0J1502D01*
G37*
G36*
G01X1619075Y1591596D02*
X1622475D01*
G02Y1588592I0J-1502D01*
G01X1619075D01*
G02Y1591596I0J1502D01*
G37*
G36*
G01X242437Y1615794D02*
X245837D01*
G02Y1612790I0J-1502D01*
G01X242437D01*
G02Y1615794I0J1502D01*
G37*
G36*
G01X369797Y1579684D02*
X373197D01*
G02Y1576680I0J-1502D01*
G01X369797D01*
G02Y1579684I0J1502D01*
G37*
G36*
G01X473051Y1591596D02*
X476451D01*
G02Y1588592I0J-1502D01*
G01X473051D01*
G02Y1591596I0J1502D01*
G37*
G36*
G01Y1579684D02*
X476451D01*
G02Y1576680I0J-1502D01*
G01X473051D01*
G02Y1579684I0J1502D01*
G37*
G36*
G01X1588195Y1603882D02*
X1591595D01*
G02Y1600878I0J-1502D01*
G01X1588195D01*
G02Y1603882I0J1502D01*
G37*
G36*
G01Y1615794D02*
X1591595D01*
G02Y1612790I0J-1502D01*
G01X1588195D01*
G02Y1615794I0J1502D01*
G37*
G36*
G01X61470Y86124D02*
X64870D01*
G02Y83120I0J-1502D01*
G01X61470D01*
G02Y86124I0J1502D01*
G37*
G36*
G01X297437Y1579684D02*
X300837D01*
G02Y1576680I0J-1502D01*
G01X297437D01*
G02Y1579684I0J1502D01*
G37*
G36*
G01X350977Y1615794D02*
X354377D01*
G02Y1612790I0J-1502D01*
G01X350977D01*
G02Y1615794I0J1502D01*
G37*
G36*
G01X375097Y1603882D02*
X378497D01*
G02Y1600878I0J-1502D01*
G01X375097D01*
G02Y1603882I0J1502D01*
G37*
G36*
G01Y1615794D02*
X378497D01*
G02Y1612790I0J-1502D01*
G01X375097D01*
G02Y1615794I0J1502D01*
G37*
G36*
G01X363037Y1603882D02*
X366437D01*
G02Y1600878I0J-1502D01*
G01X363037D01*
G02Y1603882I0J1502D01*
G37*
G36*
G01X521480Y873810D02*
G02X524076I1298J0D01*
G01Y873808D01*
G02X524003Y873381I-1298J2D01*
G01X523973Y873295D01*
X524779Y871898D01*
X524869Y871881D01*
G02X525926Y870606I-240J-1275D01*
G02X523332I-1297J0D01*
G01Y870607D01*
G02X523403Y871032I1297J2D01*
G01X523433Y871118D01*
X522626Y872518D01*
X522536Y872535D01*
G02X521480Y873810I242J1275D01*
G37*
G36*
G01X1499474Y883423D02*
G02X1502068I1297J0D01*
G01Y883421D01*
G02X1501996Y882994I-1298J-1D01*
G01X1501966Y882908D01*
X1502772Y881511D01*
X1502862Y881494D01*
G02X1503918Y880219I-242J-1275D01*
G02X1501324I-1297J0D01*
G01Y880221D01*
G02X1501396Y880646I1297J-1D01*
G01X1501426Y880732D01*
X1500619Y882131D01*
X1500529Y882148D01*
G02X1499474Y883423I243J1275D01*
G37*
G36*
G01X1505024Y886625D02*
Y886627D01*
G02X1507618I1297J0D01*
G02X1506563Y885352I-1298J0D01*
G01X1506473Y885335D01*
X1505666Y883937D01*
X1505696Y883851D01*
G02X1505768Y883423I-1226J-426D01*
G02X1503174I-1297J0D01*
G02X1504230Y884698I1298J0D01*
G01X1504320Y884715D01*
X1505126Y886112D01*
X1505096Y886198D01*
G02X1505024Y886625I1226J426D01*
G37*
G36*
G01X1497622Y873810D02*
G02X1500218I1298J0D01*
G01Y873808D01*
G02X1500145Y873381I-1298J2D01*
G01X1500115Y873295D01*
X1500921Y871898D01*
X1501011Y871881D01*
G02X1502068Y870606I-240J-1275D01*
G02X1499474I-1297J0D01*
G01Y870607D01*
G02X1499545Y871032I1297J2D01*
G01X1499575Y871118D01*
X1498768Y872518D01*
X1498678Y872535D01*
G02X1497622Y873810I242J1275D01*
G37*
G36*
G01X515932Y883423D02*
G02X518526I1297J0D01*
G01Y883421D01*
G02X518454Y882994I-1298J-1D01*
G01X518424Y882908D01*
X519230Y881511D01*
X519320Y881494D01*
G02X520376Y880219I-242J-1275D01*
G02X517780I-1298J0D01*
G02X517853Y880647I1299J-1D01*
G01X517883Y880733D01*
X517077Y882131D01*
X516987Y882148D01*
G02X515932Y883423I243J1275D01*
G37*
G36*
G01X528880Y873810D02*
G02X531476I1298J0D01*
G01Y873808D01*
G02X531403Y873381I-1298J2D01*
G01X531373Y873295D01*
X532179Y871898D01*
X532269Y871881D01*
G02X533326Y870606I-240J-1275D01*
G02X530732I-1297J0D01*
G01Y870607D01*
G02X530803Y871032I1297J2D01*
G01X530833Y871118D01*
X530026Y872518D01*
X529936Y872535D01*
G02X528880Y873810I242J1275D01*
G37*
G36*
G01X1505022D02*
G02X1507618I1298J0D01*
G01Y873808D01*
G02X1507545Y873381I-1298J2D01*
G01X1507515Y873295D01*
X1508321Y871898D01*
X1508411Y871881D01*
G02X1509468Y870606I-240J-1275D01*
G02X1506874I-1297J0D01*
G01Y870607D01*
G02X1506945Y871032I1297J2D01*
G01X1506975Y871118D01*
X1506168Y872518D01*
X1506078Y872535D01*
G02X1505022Y873810I242J1275D01*
G37*
G36*
G01X523332Y883423D02*
G02X525926I1297J0D01*
G01Y883421D01*
G02X525854Y882994I-1298J-1D01*
G01X525824Y882908D01*
X526630Y881511D01*
X526720Y881494D01*
G02X527776Y880219I-242J-1275D01*
G02X525182I-1297J0D01*
G01Y880221D01*
G02X525254Y880646I1297J-1D01*
G01X525284Y880732D01*
X524477Y882131D01*
X524387Y882148D01*
G02X523332Y883423I243J1275D01*
G37*
G36*
G01X1330101Y541552D02*
X1333143D01*
G02Y538546I0J-1503D01*
G01X1330101D01*
G02Y541552I0J1503D01*
G37*
G36*
G01X1492074Y883423D02*
G02X1494668I1297J0D01*
G01Y883421D01*
G02X1494596Y882994I-1298J-1D01*
G01X1494566Y882908D01*
X1495372Y881511D01*
X1495462Y881494D01*
G02X1496518Y880219I-242J-1275D01*
G02X1493922I-1298J0D01*
G02X1493995Y880647I1299J-1D01*
G01X1494025Y880733D01*
X1493219Y882131D01*
X1493129Y882148D01*
G02X1492074Y883423I243J1275D01*
G37*
G36*
G01X1358624Y283142D02*
X1355224D01*
G02Y286146I0J1502D01*
G01X1358624D01*
G02Y283142I0J-1502D01*
G37*
G36*
G01X1348084Y278756D02*
X1344684D01*
G02Y281762I0J1503D01*
G01X1348084D01*
G02Y278756I0J-1503D01*
G37*
G36*
G01X1368524Y281242D02*
X1365124D01*
G02Y284246I0J1502D01*
G01X1368524D01*
G02Y281242I0J-1502D01*
G37*
G36*
G01X528882Y886625D02*
Y886627D01*
G02X531476I1297J0D01*
G02X530421Y885352I-1298J0D01*
G01X530331Y885335D01*
X529524Y883937D01*
X529554Y883851D01*
G02X529626Y883423I-1226J-426D01*
G02X527032I-1297J0D01*
G02X528088Y884698I1298J0D01*
G01X528178Y884715D01*
X528984Y886112D01*
X528954Y886198D01*
G02X528882Y886625I1226J426D01*
G37*
G36*
G01X1328480Y322400D02*
X1325080D01*
G02Y325404I0J1502D01*
G01X1328480D01*
G02Y322400I0J-1502D01*
G37*
G36*
G01X613970Y190254D02*
X617370D01*
G02Y187250I0J-1502D01*
G01X613970D01*
G02Y190254I0J1502D01*
G37*
G36*
G01X64571Y427304D02*
X61171D01*
G02Y430308I0J1502D01*
G01X64571D01*
G02Y427304I0J-1502D01*
G37*
G36*
G01X626640Y190254D02*
X630040D01*
G02Y187250I0J-1502D01*
G01X626640D01*
G02Y190254I0J1502D01*
G37*
G36*
G01X423180Y1601300D02*
X419780D01*
G02Y1604304I0J1502D01*
G01X423180D01*
G02Y1601300I0J-1502D01*
G37*
G36*
G01X49360Y427304D02*
X45960D01*
G02Y430308I0J1502D01*
G01X49360D01*
G02Y427304I0J-1502D01*
G37*
G36*
G01X1400985Y242432D02*
X1404385D01*
G02Y239426I0J-1503D01*
G01X1400985D01*
G02Y242432I0J1503D01*
G37*
G36*
G01X930731Y531982D02*
X933773D01*
G02Y528976I0J-1503D01*
G01X930731D01*
G02Y531982I0J1503D01*
G37*
G36*
G01X285377Y1591596D02*
X288777D01*
G02Y1588592I0J-1502D01*
G01X285377D01*
G02Y1591596I0J1502D01*
G37*
G36*
G01X229131Y49144D02*
X225731D01*
G02Y52148I0J1502D01*
G01X229131D01*
G02Y49144I0J-1502D01*
G37*
G36*
G01X284230D02*
X280830D01*
G02Y52148I0J1502D01*
G01X284230D01*
G02Y49144I0J-1502D01*
G37*
G36*
G01X1755272Y27934D02*
X1758672D01*
G02Y24928I0J-1503D01*
G01X1755272D01*
G02Y27934I0J1503D01*
G37*
G36*
G01X1530660Y101664D02*
X1534060D01*
G02Y98660I0J-1502D01*
G01X1530660D01*
G02Y101664I0J1502D01*
G37*
G36*
G01X1549308Y27934D02*
X1552708D01*
G02Y24928I0J-1503D01*
G01X1549308D01*
G02Y27934I0J1503D01*
G37*
G36*
G01X1556413Y20998D02*
X1559813D01*
G02Y17992I0J-1503D01*
G01X1556413D01*
G02Y20998I0J1503D01*
G37*
G36*
G01X1563481Y27934D02*
X1566881D01*
G02Y24928I0J-1503D01*
G01X1563481D01*
G02Y27934I0J1503D01*
G37*
G36*
G01X1570586Y20998D02*
X1573986D01*
G02Y17992I0J-1503D01*
G01X1570586D01*
G02Y20998I0J1503D01*
G37*
G36*
G01X1577654Y27934D02*
X1581054D01*
G02Y24928I0J-1503D01*
G01X1577654D01*
G02Y27934I0J1503D01*
G37*
G36*
G01X1584759Y20998D02*
X1588159D01*
G02Y17992I0J-1503D01*
G01X1584759D01*
G02Y20998I0J1503D01*
G37*
G36*
G01X1591828Y27934D02*
X1595228D01*
G02Y24928I0J-1503D01*
G01X1591828D01*
G02Y27934I0J1503D01*
G37*
G36*
G01X1598933Y20998D02*
X1602333D01*
G02Y17992I0J-1503D01*
G01X1598933D01*
G02Y20998I0J1503D01*
G37*
G36*
G01X1627694Y27934D02*
X1631094D01*
G02Y24928I0J-1503D01*
G01X1627694D01*
G02Y27934I0J1503D01*
G37*
G36*
G01X1634799Y20998D02*
X1638199D01*
G02Y17992I0J-1503D01*
G01X1634799D01*
G02Y20998I0J1503D01*
G37*
G36*
G01X218667Y21040D02*
X222067D01*
G02Y18036I0J-1502D01*
G01X218667D01*
G02Y21040I0J1502D01*
G37*
G36*
G01X211562Y27976D02*
X214962D01*
G02Y24972I0J-1502D01*
G01X211562D01*
G02Y27976I0J1502D01*
G37*
G36*
G01X204494Y21040D02*
X207894D01*
G02Y18036I0J-1502D01*
G01X204494D01*
G02Y21040I0J1502D01*
G37*
G36*
G01X197389Y27976D02*
X200789D01*
G02Y24972I0J-1502D01*
G01X197389D01*
G02Y27976I0J1502D01*
G37*
G36*
G01X167428D02*
X170828D01*
G02Y24972I0J-1502D01*
G01X167428D01*
G02Y27976I0J1502D01*
G37*
G36*
G01X174533Y21040D02*
X177933D01*
G02Y18036I0J-1502D01*
G01X174533D01*
G02Y21040I0J1502D01*
G37*
G36*
G01X153255Y27976D02*
X156655D01*
G02Y24972I0J-1502D01*
G01X153255D01*
G02Y27976I0J1502D01*
G37*
G36*
G01X160360Y21040D02*
X163760D01*
G02Y18036I0J-1502D01*
G01X160360D01*
G02Y21040I0J1502D01*
G37*
G36*
G01X124494D02*
X127894D01*
G02Y18036I0J-1502D01*
G01X124494D01*
G02Y21040I0J1502D01*
G37*
G36*
G01X117389Y27976D02*
X120789D01*
G02Y24972I0J-1502D01*
G01X117389D01*
G02Y27976I0J1502D01*
G37*
G36*
G01X103215D02*
X106615D01*
G02Y24972I0J-1502D01*
G01X103215D01*
G02Y27976I0J1502D01*
G37*
G36*
G01X110320Y21040D02*
X113720D01*
G02Y18036I0J-1502D01*
G01X110320D01*
G02Y21040I0J1502D01*
G37*
G36*
G01X89042Y27976D02*
X92442D01*
G02Y24972I0J-1502D01*
G01X89042D01*
G02Y27976I0J1502D01*
G37*
G36*
G01X96147Y21040D02*
X99547D01*
G02Y18036I0J-1502D01*
G01X96147D01*
G02Y21040I0J1502D01*
G37*
G36*
G01X74869Y27976D02*
X78269D01*
G02Y24972I0J-1502D01*
G01X74869D01*
G02Y27976I0J1502D01*
G37*
G36*
G01X81974Y21040D02*
X85374D01*
G02Y18036I0J-1502D01*
G01X81974D01*
G02Y21040I0J1502D01*
G37*
G36*
G01X1641867Y27934D02*
X1645267D01*
G02Y24928I0J-1503D01*
G01X1641867D01*
G02Y27934I0J1503D01*
G37*
G36*
G01X1648972Y20998D02*
X1652372D01*
G02Y17992I0J-1503D01*
G01X1648972D01*
G02Y20998I0J1503D01*
G37*
G36*
G01X1671828Y27934D02*
X1675228D01*
G02Y24928I0J-1503D01*
G01X1671828D01*
G02Y27934I0J1503D01*
G37*
G36*
G01X1678933Y20998D02*
X1682333D01*
G02Y17992I0J-1503D01*
G01X1678933D01*
G02Y20998I0J1503D01*
G37*
G36*
G01X1686001Y27934D02*
X1689401D01*
G02Y24928I0J-1503D01*
G01X1686001D01*
G02Y27934I0J1503D01*
G37*
G36*
G01X1693106Y20998D02*
X1696506D01*
G02Y17992I0J-1503D01*
G01X1693106D01*
G02Y20998I0J1503D01*
G37*
G36*
G01X1700217Y27962D02*
X1703617D01*
G02Y24956I0J-1503D01*
G01X1700217D01*
G02Y27962I0J1503D01*
G37*
G36*
G01X1700170Y52152D02*
X1703570D01*
G02Y49146I0J-1503D01*
G01X1700170D01*
G02Y52152I0J1503D01*
G37*
G36*
G01X670612Y48766D02*
X674012D01*
G02Y45762I0J-1502D01*
G01X670612D01*
G02Y48766I0J1502D01*
G37*
G36*
G01X284233Y24972D02*
X280833D01*
G02Y27976I0J1502D01*
G01X284233D01*
G02Y24972I0J-1502D01*
G37*
G36*
G01X1307442Y305496D02*
X1304042D01*
G02Y308500I0J1502D01*
G01X1307442D01*
G02Y305496I0J-1502D01*
G37*
G36*
G01X1382972Y1603882D02*
X1386372D01*
G02Y1600878I0J-1502D01*
G01X1382972D01*
G02Y1603882I0J1502D01*
G37*
G36*
G01Y1615794D02*
X1386372D01*
G02Y1612790I0J-1502D01*
G01X1382972D01*
G02Y1615794I0J1502D01*
G37*
G36*
G01X229135Y24972D02*
X225735D01*
G02Y27976I0J1502D01*
G01X229135D01*
G02Y24972I0J-1502D01*
G37*
G36*
G01X350977Y1603882D02*
X354377D01*
G02Y1600878I0J-1502D01*
G01X350977D01*
G02Y1603882I0J1502D01*
G37*
G36*
G01X1307042Y291134D02*
X1303642D01*
G02Y294138I0J1502D01*
G01X1307042D01*
G02Y291134I0J-1502D01*
G37*
G36*
G01X405990Y1617450D02*
X402590D01*
G02Y1620454I0J1502D01*
G01X405990D01*
G02Y1617450I0J-1502D01*
G37*
G36*
G01X441740Y1650764D02*
X438340D01*
G02Y1653768I0J1502D01*
G01X441740D01*
G02Y1650764I0J-1502D01*
G37*
G36*
G01X49212Y450100D02*
X45812D01*
G02Y453104I0J1502D01*
G01X49212D01*
G02Y450100I0J-1502D01*
G37*
G36*
G01X1418630Y221520D02*
X1422030D01*
G02Y218516I0J-1502D01*
G01X1418630D01*
G02Y221520I0J1502D01*
G37*
G36*
G01X1407420D02*
X1410820D01*
G02Y218516I0J-1502D01*
G01X1407420D01*
G02Y221520I0J1502D01*
G37*
G36*
G01X1432660D02*
X1436060D01*
G02Y218516I0J-1502D01*
G01X1432660D01*
G02Y221520I0J1502D01*
G37*
G36*
G01X862930Y71574D02*
X866330D01*
G02Y68570I0J-1502D01*
G01X862930D01*
G02Y71574I0J1502D01*
G37*
G36*
G01X1348824Y327478D02*
X1345424D01*
G02Y330484I0J1503D01*
G01X1348824D01*
G02Y327478I0J-1503D01*
G37*
G36*
G01X1341431Y321190D02*
X1338031D01*
G02Y324196I0J1503D01*
G01X1341431D01*
G02Y321190I0J-1503D01*
G37*
G36*
G01X1335145Y331114D02*
X1331745D01*
G02Y334118I0J1502D01*
G01X1335145D01*
G02Y331114I0J-1502D01*
G37*
G36*
G01X1319618Y316570D02*
X1316218D01*
G02Y319576I0J1503D01*
G01X1319618D01*
G02Y316570I0J-1503D01*
G37*
G36*
G01X1311077Y321494D02*
X1307677D01*
G02Y324498I0J1502D01*
G01X1311077D01*
G02Y321494I0J-1502D01*
G37*
G36*
G01X1380602Y199170D02*
X1384002D01*
G02Y196166I0J-1502D01*
G01X1380602D01*
G02Y199170I0J1502D01*
G37*
G36*
G01X1398006D02*
X1401406D01*
G02Y196166I0J-1502D01*
G01X1398006D01*
G02Y199170I0J1502D01*
G37*
G36*
G01X1373591Y177932D02*
X1376991D01*
G02Y174928I0J-1502D01*
G01X1373591D01*
G02Y177932I0J1502D01*
G37*
G36*
G01X1169820Y637554D02*
X1173220D01*
G02Y634550I0J-1502D01*
G01X1169820D01*
G02Y637554I0J1502D01*
G37*
G36*
G01X519764Y41830D02*
X523164D01*
G02Y38826I0J-1502D01*
G01X519764D01*
G02Y41830I0J1502D01*
G37*
G36*
G01X732793Y72938D02*
X736193D01*
G02Y69934I0J-1502D01*
G01X732793D01*
G02Y72938I0J1502D01*
G37*
G36*
G01X1161860Y643614D02*
X1165260D01*
G02Y640610I0J-1502D01*
G01X1161860D01*
G02Y643614I0J1502D01*
G37*
G36*
G01X663543Y44830D02*
X666943D01*
G02Y41826I0J-1502D01*
G01X663543D01*
G02Y44830I0J1502D01*
G37*
G36*
G01X656439Y48766D02*
X659839D01*
G02Y45762I0J-1502D01*
G01X656439D01*
G02Y48766I0J1502D01*
G37*
G36*
G01X562771Y1603882D02*
X566171D01*
G02Y1600878I0J-1502D01*
G01X562771D01*
G02Y1603882I0J1502D01*
G37*
G36*
G01X538651D02*
X542051D01*
G02Y1600878I0J-1502D01*
G01X538651D01*
G02Y1603882I0J1502D01*
G37*
G36*
G01X1406970Y140244D02*
X1410370D01*
G02Y137240I0J-1502D01*
G01X1406970D01*
G02Y140244I0J1502D01*
G37*
G36*
G01X1323303Y297674D02*
X1319903D01*
G02Y300678I0J1502D01*
G01X1323303D01*
G02Y297674I0J-1502D01*
G37*
G36*
G01X1361771Y330772D02*
X1358371D01*
G02Y333778I0J1503D01*
G01X1361771D01*
G02Y330772I0J-1503D01*
G37*
G36*
G01X555175Y72938D02*
X558575D01*
G02Y69934I0J-1502D01*
G01X555175D01*
G02Y72938I0J1502D01*
G37*
G36*
G01X541002D02*
X544402D01*
G02Y69934I0J-1502D01*
G01X541002D01*
G02Y72938I0J1502D01*
G37*
G36*
G01X519742D02*
X523142D01*
G02Y69934I0J-1502D01*
G01X519742D01*
G02Y72938I0J1502D01*
G37*
G36*
G01X533915Y61324D02*
X537315D01*
G02Y58320I0J-1502D01*
G01X533915D01*
G02Y61324I0J1502D01*
G37*
G36*
G01X1294500Y298190D02*
X1291100D01*
G02Y301194I0J1502D01*
G01X1294500D01*
G02Y298190I0J-1502D01*
G37*
G36*
G01X1404829Y185766D02*
X1408229D01*
G02Y182760I0J-1503D01*
G01X1404829D01*
G02Y185766I0J1503D01*
G37*
G36*
G01X538651Y1615794D02*
X542051D01*
G02Y1612790I0J-1502D01*
G01X538651D01*
G02Y1615794I0J1502D01*
G37*
G36*
G01X526591Y1603882D02*
X529991D01*
G02Y1600878I0J-1502D01*
G01X526591D01*
G02Y1603882I0J1502D01*
G37*
G36*
G01X514531D02*
X517931D01*
G02Y1600878I0J-1502D01*
G01X514531D01*
G02Y1603882I0J1502D01*
G37*
G36*
G01X526591Y1615794D02*
X529991D01*
G02Y1612790I0J-1502D01*
G01X526591D01*
G02Y1615794I0J1502D01*
G37*
G36*
G01X514531D02*
X517931D01*
G02Y1612790I0J-1502D01*
G01X514531D01*
G02Y1615794I0J1502D01*
G37*
G36*
G01X490411Y1603882D02*
X493811D01*
G02Y1600878I0J-1502D01*
G01X490411D01*
G02Y1603882I0J1502D01*
G37*
G36*
G01X478351Y1615794D02*
X481751D01*
G02Y1612790I0J-1502D01*
G01X478351D01*
G02Y1615794I0J1502D01*
G37*
G36*
G01X502471D02*
X505871D01*
G02Y1612790I0J-1502D01*
G01X502471D01*
G02Y1615794I0J1502D01*
G37*
G36*
G01X478351Y1603882D02*
X481751D01*
G02Y1600878I0J-1502D01*
G01X478351D01*
G02Y1603882I0J1502D01*
G37*
G36*
G01X1412284Y173198D02*
X1415684D01*
G02Y170194I0J-1502D01*
G01X1412284D01*
G02Y173198I0J1502D01*
G37*
G36*
G01X598951Y1603882D02*
X602351D01*
G02Y1600878I0J-1502D01*
G01X598951D01*
G02Y1603882I0J1502D01*
G37*
G36*
G01Y1615794D02*
X602351D01*
G02Y1612790I0J-1502D01*
G01X598951D01*
G02Y1615794I0J1502D01*
G37*
G36*
G01X586891Y1603882D02*
X590291D01*
G02Y1600878I0J-1502D01*
G01X586891D01*
G02Y1603882I0J1502D01*
G37*
G36*
G01X647191D02*
X650591D01*
G02Y1600878I0J-1502D01*
G01X647191D01*
G02Y1603882I0J1502D01*
G37*
G36*
G01X635131Y1615794D02*
X638531D01*
G02Y1612790I0J-1502D01*
G01X635131D01*
G02Y1615794I0J1502D01*
G37*
G36*
G01X647191D02*
X650591D01*
G02Y1612790I0J-1502D01*
G01X647191D01*
G02Y1615794I0J1502D01*
G37*
G36*
G01X623071D02*
X626471D01*
G02Y1612790I0J-1502D01*
G01X623071D01*
G02Y1615794I0J1502D01*
G37*
G36*
G01X1355200Y336340D02*
X1351800D01*
G02Y339346I0J1503D01*
G01X1355200D01*
G02Y336340I0J-1503D01*
G37*
G36*
G01X1328814Y292054D02*
X1325414D01*
G02Y295058I0J1502D01*
G01X1328814D01*
G02Y292054I0J-1502D01*
G37*
G36*
G01X1340161Y291902D02*
X1336761D01*
G02Y294906I0J1502D01*
G01X1340161D01*
G02Y291902I0J-1502D01*
G37*
G36*
G01X1413950Y185766D02*
X1417350D01*
G02Y182760I0J-1503D01*
G01X1413950D01*
G02Y185766I0J1503D01*
G37*
G36*
G01X1423110D02*
X1426510D01*
G02Y182760I0J-1503D01*
G01X1423110D01*
G02Y185766I0J1503D01*
G37*
G36*
G01X1401341Y178662D02*
X1404741D01*
G02Y175656I0J-1503D01*
G01X1401341D01*
G02Y178662I0J1503D01*
G37*
G36*
G01X1403778Y173186D02*
X1407178D01*
G02Y170182I0J-1502D01*
G01X1403778D01*
G02Y173186I0J1502D01*
G37*
G36*
G01X1389256Y199170D02*
X1392656D01*
G02Y196166I0J-1502D01*
G01X1389256D01*
G02Y199170I0J1502D01*
G37*
G36*
G01X550711Y1603882D02*
X554111D01*
G02Y1600878I0J-1502D01*
G01X550711D01*
G02Y1603882I0J1502D01*
G37*
G36*
G01X502471D02*
X505871D01*
G02Y1600878I0J-1502D01*
G01X502471D01*
G02Y1603882I0J1502D01*
G37*
G36*
G01X490411Y1615794D02*
X493811D01*
G02Y1612790I0J-1502D01*
G01X490411D01*
G02Y1615794I0J1502D01*
G37*
G36*
G01X987440Y432696D02*
X990840D01*
G02Y429690I0J-1503D01*
G01X987440D01*
G02Y432696I0J1503D01*
G37*
G36*
G01X1471460Y631900D02*
X1468060D01*
G02Y634904I0J1502D01*
G01X1471460D01*
G02Y631900I0J-1502D01*
G37*
G36*
G01X934047Y459364D02*
X937447D01*
G02Y456360I0J-1502D01*
G01X934047D01*
G02Y459364I0J1502D01*
G37*
G36*
G01X942047Y464514D02*
X945447D01*
G02Y461510I0J-1502D01*
G01X942047D01*
G02Y464514I0J1502D01*
G37*
G36*
G01X550711Y1615794D02*
X554111D01*
G02Y1612790I0J-1502D01*
G01X550711D01*
G02Y1615794I0J1502D01*
G37*
G36*
G01X635131Y1603882D02*
X638531D01*
G02Y1600878I0J-1502D01*
G01X635131D01*
G02Y1603882I0J1502D01*
G37*
G36*
G01X909584Y459638D02*
X912984D01*
G02Y456632I0J-1503D01*
G01X909584D01*
G02Y459638I0J1503D01*
G37*
G36*
G01X913394Y523164D02*
X916794D01*
G02Y520160I0J-1502D01*
G01X913394D01*
G02Y523164I0J1502D01*
G37*
G36*
G01X574831Y1603882D02*
X578231D01*
G02Y1600878I0J-1502D01*
G01X574831D01*
G02Y1603882I0J1502D01*
G37*
G36*
G01X659251D02*
X662651D01*
G02Y1600878I0J-1502D01*
G01X659251D01*
G02Y1603882I0J1502D01*
G37*
G36*
G01X1153370Y639694D02*
X1156770D01*
G02Y636690I0J-1502D01*
G01X1153370D01*
G02Y639694I0J1502D01*
G37*
G36*
G01X1406786Y199170D02*
X1410186D01*
G02Y196166I0J-1502D01*
G01X1406786D01*
G02Y199170I0J1502D01*
G37*
G36*
G01X611011Y1615794D02*
X614411D01*
G02Y1612790I0J-1502D01*
G01X611011D01*
G02Y1615794I0J1502D01*
G37*
G36*
G01X1312136Y283446D02*
X1308736D01*
G02Y286450I0J1502D01*
G01X1312136D01*
G02Y283446I0J-1502D01*
G37*
G36*
G01X611011Y1603882D02*
X614411D01*
G02Y1600878I0J-1502D01*
G01X611011D01*
G02Y1603882I0J1502D01*
G37*
G36*
G01X586891Y1615794D02*
X590291D01*
G02Y1612790I0J-1502D01*
G01X586891D01*
G02Y1615794I0J1502D01*
G37*
G36*
G01X659251D02*
X662651D01*
G02Y1612790I0J-1502D01*
G01X659251D01*
G02Y1615794I0J1502D01*
G37*
G36*
G01X574831D02*
X578231D01*
G02Y1612790I0J-1502D01*
G01X574831D01*
G02Y1615794I0J1502D01*
G37*
G36*
G01X1183360Y643564D02*
X1186760D01*
G02Y640560I0J-1502D01*
G01X1183360D01*
G02Y643564I0J1502D01*
G37*
G36*
G01X562771Y1615794D02*
X566171D01*
G02Y1612790I0J-1502D01*
G01X562771D01*
G02Y1615794I0J1502D01*
G37*
G36*
G01X901230Y533114D02*
X904630D01*
G02Y530110I0J-1502D01*
G01X901230D01*
G02Y533114I0J1502D01*
G37*
G36*
G01X954390Y529098D02*
X957790D01*
G02Y526094I0J-1502D01*
G01X954390D01*
G02Y529098I0J1502D01*
G37*
G36*
G01X963930Y534864D02*
X967330D01*
G02Y531860I0J-1502D01*
G01X963930D01*
G02Y534864I0J1502D01*
G37*
G36*
G01X548070Y80874D02*
X551470D01*
G02Y77870I0J-1502D01*
G01X548070D01*
G02Y80874I0J1502D01*
G37*
G36*
G01X623071Y1603882D02*
X626471D01*
G02Y1600878I0J-1502D01*
G01X623071D01*
G02Y1603882I0J1502D01*
G37*
G36*
G01X888130Y534114D02*
X891530D01*
G02Y531110I0J-1502D01*
G01X888130D01*
G02Y534114I0J1502D01*
G37*
G36*
G01X297437Y1591596D02*
X300837D01*
G02Y1588592I0J-1502D01*
G01X297437D01*
G02Y1591596I0J1502D01*
G37*
G36*
G01X237137D02*
X240537D01*
G02Y1588592I0J-1502D01*
G01X237137D01*
G02Y1591596I0J1502D01*
G37*
G36*
G01X937340Y309612D02*
X920138D01*
G02X937340I8601J12041D01*
G37*
G36*
G01X921047Y464514D02*
X924447D01*
G02Y461510I0J-1502D01*
G01X921047D01*
G02Y464514I0J1502D01*
G37*
G36*
G01X371587Y173422D02*
X365287D01*
G02Y197050I0J11814D01*
G01X371587D01*
G02Y173422I0J-11814D01*
G37*
G36*
G01X253477D02*
X247176D01*
G02X247175Y197050I0J11814D01*
G01X253476D01*
G02X253477Y173422I0J-11814D01*
G37*
G36*
G01X1012861Y434390D02*
X1016261D01*
G02Y431386I0J-1502D01*
G01X1012861D01*
G02Y434390I0J1502D01*
G37*
G36*
G01X50772Y120610D02*
X55372Y124913D01*
G02X66448Y113076I5538J-5919D01*
G01X61848Y108773D01*
G02X50772Y120610I-5538J5918D01*
G37*
G36*
G01X62587Y23395D02*
G02X58024Y17311I-2280J-3043D01*
G02X62587Y23395I2279J3044D01*
G37*
G36*
G01X353132Y870606D02*
G02X355726I1297J0D01*
G02X355654Y870177I-1297J-3D01*
G01X355623Y870091D01*
X356430Y868693D01*
X356520Y868676D01*
G02X357576Y867401I-242J-1275D01*
G02X354980I-1298J0D01*
G02X355053Y867830I1297J0D01*
G01X355084Y867916D01*
X354277Y869314D01*
X354187Y869331D01*
G02X353132Y870606I243J1275D01*
G37*
G36*
G01X360532D02*
G02X363126I1297J0D01*
G02X363054Y870177I-1297J-3D01*
G01X363023Y870091D01*
X363830Y868693D01*
X363920Y868676D01*
G02X364976Y867401I-242J-1275D01*
G02X362380I-1298J0D01*
G02X362453Y867830I1297J0D01*
G01X362484Y867916D01*
X361677Y869314D01*
X361587Y869331D01*
G02X360532Y870606I243J1275D01*
G37*
G36*
G01X367932D02*
G02X370526I1297J0D01*
G02X370454Y870177I-1297J-3D01*
G01X370423Y870091D01*
X371230Y868693D01*
X371320Y868676D01*
G02X372376Y867401I-242J-1275D01*
G02X369780I-1298J0D01*
G02X369853Y867830I1297J0D01*
G01X369884Y867916D01*
X369077Y869314D01*
X368987Y869331D01*
G02X367932Y870606I243J1275D01*
G37*
G36*
G01X375332D02*
G02X377926I1297J0D01*
G02X377854Y870177I-1297J-3D01*
G01X377823Y870091D01*
X378630Y868693D01*
X378720Y868676D01*
G02X379776Y867401I-242J-1275D01*
G02X377180I-1298J0D01*
G02X377253Y867830I1297J0D01*
G01X377284Y867916D01*
X376477Y869314D01*
X376387Y869331D01*
G02X375332Y870606I243J1275D01*
G37*
G36*
G01X382732D02*
G02X385326I1297J0D01*
G02X385254Y870177I-1297J-3D01*
G01X385223Y870091D01*
X386030Y868693D01*
X386120Y868676D01*
G02X387176Y867401I-242J-1275D01*
G02X384580I-1298J0D01*
G02X384653Y867830I1297J0D01*
G01X384684Y867916D01*
X383877Y869314D01*
X383787Y869331D01*
G02X382732Y870606I243J1275D01*
G37*
G36*
G01X390132D02*
G02X392726I1297J0D01*
G02X392654Y870177I-1297J-3D01*
G01X392623Y870091D01*
X393430Y868693D01*
X393520Y868676D01*
G02X394576Y867401I-242J-1275D01*
G02X391980I-1298J0D01*
G02X392053Y867830I1297J0D01*
G01X392084Y867916D01*
X391277Y869314D01*
X391187Y869331D01*
G02X390132Y870606I243J1275D01*
G37*
G36*
G01X397532D02*
G02X400126I1297J0D01*
G02X400054Y870177I-1297J-3D01*
G01X400023Y870091D01*
X400830Y868693D01*
X400920Y868676D01*
G02X401976Y867401I-242J-1275D01*
G02X399380I-1298J0D01*
G02X399453Y867830I1297J0D01*
G01X399484Y867916D01*
X398677Y869314D01*
X398587Y869331D01*
G02X397532Y870606I243J1275D01*
G37*
G36*
G01X404932D02*
G02X407526I1297J0D01*
G02X407454Y870177I-1297J-3D01*
G01X407423Y870091D01*
X408230Y868693D01*
X408320Y868676D01*
G02X409376Y867401I-242J-1275D01*
G02X406780I-1298J0D01*
G02X406853Y867830I1297J0D01*
G01X406884Y867916D01*
X406077Y869314D01*
X405987Y869331D01*
G02X404932Y870606I243J1275D01*
G37*
G36*
G01X416032D02*
G02X418626I1297J0D01*
G02X417571Y869331I-1298J0D01*
G01X417481Y869314D01*
X416673Y867915D01*
X416703Y867828D01*
G02X416776Y867401I-1225J-429D01*
G02X414180I-1298J0D01*
G02X415238Y868676I1297J0D01*
G01X415328Y868693D01*
X416135Y870091D01*
X416104Y870178D01*
G02X416032Y870606I1225J426D01*
G37*
G36*
G01X423432D02*
G02X426026I1297J0D01*
G02X424971Y869331I-1298J0D01*
G01X424881Y869314D01*
X424073Y867915D01*
X424103Y867828D01*
G02X424176Y867401I-1225J-429D01*
G02X421580I-1298J0D01*
G02X422638Y868676I1297J0D01*
G01X422728Y868693D01*
X423535Y870091D01*
X423504Y870178D01*
G02X423432Y870606I1225J426D01*
G37*
G36*
G01X430832D02*
G02X433426I1297J0D01*
G02X432371Y869331I-1298J0D01*
G01X432281Y869314D01*
X431473Y867915D01*
X431503Y867828D01*
G02X431576Y867401I-1225J-429D01*
G02X428980I-1298J0D01*
G02X430038Y868676I1297J0D01*
G01X430128Y868693D01*
X430935Y870091D01*
X430904Y870178D01*
G02X430832Y870606I1225J426D01*
G37*
G36*
G01X438232D02*
G02X440826I1297J0D01*
G02X439771Y869331I-1298J0D01*
G01X439681Y869314D01*
X438873Y867915D01*
X438903Y867828D01*
G02X438976Y867401I-1225J-429D01*
G02X436380I-1298J0D01*
G02X437438Y868676I1297J0D01*
G01X437528Y868693D01*
X438335Y870091D01*
X438304Y870178D01*
G02X438232Y870606I1225J426D01*
G37*
G36*
G01X445632D02*
G02X448226I1297J0D01*
G02X447171Y869331I-1298J0D01*
G01X447081Y869314D01*
X446273Y867915D01*
X446303Y867828D01*
G02X446376Y867401I-1225J-429D01*
G02X443780I-1298J0D01*
G02X444838Y868676I1297J0D01*
G01X444928Y868693D01*
X445735Y870091D01*
X445704Y870178D01*
G02X445632Y870606I1225J426D01*
G37*
G36*
G01X453032D02*
G02X455626I1297J0D01*
G02X454571Y869331I-1298J0D01*
G01X454481Y869314D01*
X453673Y867915D01*
X453703Y867828D01*
G02X453776Y867401I-1225J-429D01*
G02X451180I-1298J0D01*
G02X452238Y868676I1297J0D01*
G01X452328Y868693D01*
X453135Y870091D01*
X453104Y870178D01*
G02X453032Y870606I1225J426D01*
G37*
G36*
G01X460432D02*
G02X463026I1297J0D01*
G02X461971Y869331I-1298J0D01*
G01X461881Y869314D01*
X461073Y867915D01*
X461103Y867828D01*
G02X461176Y867401I-1225J-429D01*
G02X458580I-1298J0D01*
G02X459638Y868676I1297J0D01*
G01X459728Y868693D01*
X460535Y870091D01*
X460504Y870178D01*
G02X460432Y870606I1225J426D01*
G37*
G36*
G01X467832D02*
G02X470426I1297J0D01*
G02X469371Y869331I-1298J0D01*
G01X469281Y869314D01*
X468473Y867915D01*
X468503Y867828D01*
G02X468576Y867401I-1225J-429D01*
G02X465980I-1298J0D01*
G02X467038Y868676I1297J0D01*
G01X467128Y868693D01*
X467935Y870091D01*
X467904Y870178D01*
G02X467832Y870606I1225J426D01*
G37*
G36*
G01X475232D02*
G02X477826I1297J0D01*
G02X476771Y869331I-1298J0D01*
G01X476681Y869314D01*
X475873Y867915D01*
X475903Y867828D01*
G02X475976Y867401I-1225J-429D01*
G02X473380I-1298J0D01*
G02X474438Y868676I1297J0D01*
G01X474528Y868693D01*
X475335Y870091D01*
X475304Y870178D01*
G02X475232Y870606I1225J426D01*
G37*
G36*
G01X482632D02*
G02X485226I1297J0D01*
G02X484171Y869331I-1298J0D01*
G01X484081Y869314D01*
X483273Y867915D01*
X483303Y867828D01*
G02X483376Y867401I-1225J-429D01*
G02X480780I-1298J0D01*
G02X481838Y868676I1297J0D01*
G01X481928Y868693D01*
X482735Y870091D01*
X482704Y870178D01*
G02X482632Y870606I1225J426D01*
G37*
G36*
G01X490032D02*
G02X492626I1297J0D01*
G02X491571Y869331I-1298J0D01*
G01X491481Y869314D01*
X490673Y867915D01*
X490703Y867828D01*
G02X490776Y867401I-1225J-429D01*
G02X488180I-1298J0D01*
G02X489238Y868676I1297J0D01*
G01X489328Y868693D01*
X490135Y870091D01*
X490104Y870178D01*
G02X490032Y870606I1225J426D01*
G37*
G36*
G01X497432D02*
G02X500026I1297J0D01*
G02X498971Y869331I-1298J0D01*
G01X498881Y869314D01*
X498073Y867915D01*
X498103Y867828D01*
G02X498176Y867401I-1225J-429D01*
G02X495580I-1298J0D01*
G02X496638Y868676I1297J0D01*
G01X496728Y868693D01*
X497535Y870091D01*
X497504Y870178D01*
G02X497432Y870606I1225J426D01*
G37*
G36*
G01X504832D02*
G02X507426I1297J0D01*
G02X506371Y869331I-1298J0D01*
G01X506281Y869314D01*
X505473Y867915D01*
X505503Y867828D01*
G02X505576Y867401I-1225J-429D01*
G02X502980I-1298J0D01*
G02X504038Y868676I1297J0D01*
G01X504128Y868693D01*
X504935Y870091D01*
X504904Y870178D01*
G02X504832Y870606I1225J426D01*
G37*
G36*
G01X512232D02*
G02X514826I1297J0D01*
G02X513771Y869331I-1298J0D01*
G01X513681Y869314D01*
X512873Y867915D01*
X512903Y867828D01*
G02X512976Y867401I-1225J-429D01*
G02X510380I-1298J0D01*
G02X511438Y868676I1297J0D01*
G01X511528Y868693D01*
X512335Y870091D01*
X512304Y870178D01*
G02X512232Y870606I1225J426D01*
G37*
G36*
G01X519632D02*
G02X522226I1297J0D01*
G02X521171Y869331I-1298J0D01*
G01X521081Y869314D01*
X520273Y867915D01*
X520303Y867828D01*
G02X520376Y867401I-1225J-429D01*
G02X517780I-1298J0D01*
G02X518838Y868676I1297J0D01*
G01X518928Y868693D01*
X519735Y870091D01*
X519704Y870178D01*
G02X519632Y870606I1225J426D01*
G37*
G36*
G01X527032D02*
G02X529626I1297J0D01*
G02X528571Y869331I-1298J0D01*
G01X528481Y869314D01*
X527674Y867916D01*
X527704Y867829D01*
G02X527776Y867401I-1225J-426D01*
G02X525182I-1297J0D01*
G02X526238Y868676I1298J0D01*
G01X526328Y868693D01*
X527135Y870091D01*
X527104Y870178D01*
G02X527032Y870606I1225J426D01*
G37*
G36*
G01X1329274D02*
G02X1331868I1297J0D01*
G02X1331796Y870177I-1297J-3D01*
G01X1331765Y870091D01*
X1332572Y868693D01*
X1332662Y868676D01*
G02X1333718Y867401I-242J-1275D01*
G02X1331122I-1298J0D01*
G02X1331195Y867830I1297J0D01*
G01X1331226Y867916D01*
X1330419Y869314D01*
X1330329Y869331D01*
G02X1329274Y870606I243J1275D01*
G37*
G36*
G01X1336674D02*
G02X1339268I1297J0D01*
G02X1339196Y870177I-1297J-3D01*
G01X1339165Y870091D01*
X1339972Y868693D01*
X1340062Y868676D01*
G02X1341118Y867401I-242J-1275D01*
G02X1338522I-1298J0D01*
G02X1338595Y867830I1297J0D01*
G01X1338626Y867916D01*
X1337819Y869314D01*
X1337729Y869331D01*
G02X1336674Y870606I243J1275D01*
G37*
G36*
G01X1344074D02*
G02X1346668I1297J0D01*
G02X1346596Y870177I-1297J-3D01*
G01X1346565Y870091D01*
X1347372Y868693D01*
X1347462Y868676D01*
G02X1348518Y867401I-242J-1275D01*
G02X1345922I-1298J0D01*
G02X1345995Y867830I1297J0D01*
G01X1346026Y867916D01*
X1345219Y869314D01*
X1345129Y869331D01*
G02X1344074Y870606I243J1275D01*
G37*
G36*
G01X1351474D02*
G02X1354068I1297J0D01*
G02X1353996Y870177I-1297J-3D01*
G01X1353965Y870091D01*
X1354772Y868693D01*
X1354862Y868676D01*
G02X1355918Y867401I-242J-1275D01*
G02X1353322I-1298J0D01*
G02X1353395Y867830I1297J0D01*
G01X1353426Y867916D01*
X1352619Y869314D01*
X1352529Y869331D01*
G02X1351474Y870606I243J1275D01*
G37*
G36*
G01X1358874D02*
G02X1361468I1297J0D01*
G02X1361396Y870177I-1297J-3D01*
G01X1361365Y870091D01*
X1362172Y868693D01*
X1362262Y868676D01*
G02X1363318Y867401I-242J-1275D01*
G02X1360722I-1298J0D01*
G02X1360795Y867830I1297J0D01*
G01X1360826Y867916D01*
X1360019Y869314D01*
X1359929Y869331D01*
G02X1358874Y870606I243J1275D01*
G37*
G36*
G01X1366274D02*
G02X1368868I1297J0D01*
G02X1368796Y870177I-1297J-3D01*
G01X1368765Y870091D01*
X1369572Y868693D01*
X1369662Y868676D01*
G02X1370718Y867401I-242J-1275D01*
G02X1368122I-1298J0D01*
G02X1368195Y867830I1297J0D01*
G01X1368226Y867916D01*
X1367419Y869314D01*
X1367329Y869331D01*
G02X1366274Y870606I243J1275D01*
G37*
G36*
G01X1373674D02*
G02X1376268I1297J0D01*
G02X1376196Y870177I-1297J-3D01*
G01X1376165Y870091D01*
X1376972Y868693D01*
X1377062Y868676D01*
G02X1378118Y867401I-242J-1275D01*
G02X1375522I-1298J0D01*
G02X1375595Y867830I1297J0D01*
G01X1375626Y867916D01*
X1374819Y869314D01*
X1374729Y869331D01*
G02X1373674Y870606I243J1275D01*
G37*
G36*
G01X1381074D02*
G02X1383668I1297J0D01*
G02X1383596Y870177I-1297J-3D01*
G01X1383565Y870091D01*
X1384372Y868693D01*
X1384462Y868676D01*
G02X1385518Y867401I-242J-1275D01*
G02X1382922I-1298J0D01*
G02X1382995Y867830I1297J0D01*
G01X1383026Y867916D01*
X1382219Y869314D01*
X1382129Y869331D01*
G02X1381074Y870606I243J1275D01*
G37*
G36*
G01X1392174D02*
G02X1394768I1297J0D01*
G02X1393713Y869331I-1298J0D01*
G01X1393623Y869314D01*
X1392815Y867915D01*
X1392845Y867828D01*
G02X1392918Y867401I-1225J-429D01*
G02X1390322I-1298J0D01*
G02X1391380Y868676I1297J0D01*
G01X1391470Y868693D01*
X1392277Y870091D01*
X1392246Y870178D01*
G02X1392174Y870606I1225J426D01*
G37*
G36*
G01X1399574D02*
G02X1402168I1297J0D01*
G02X1401113Y869331I-1298J0D01*
G01X1401023Y869314D01*
X1400215Y867915D01*
X1400245Y867828D01*
G02X1400318Y867401I-1225J-429D01*
G02X1397722I-1298J0D01*
G02X1398780Y868676I1297J0D01*
G01X1398870Y868693D01*
X1399677Y870091D01*
X1399646Y870178D01*
G02X1399574Y870606I1225J426D01*
G37*
G36*
G01X1406974D02*
G02X1409568I1297J0D01*
G02X1408513Y869331I-1298J0D01*
G01X1408423Y869314D01*
X1407615Y867915D01*
X1407645Y867828D01*
G02X1407718Y867401I-1225J-429D01*
G02X1405122I-1298J0D01*
G02X1406180Y868676I1297J0D01*
G01X1406270Y868693D01*
X1407077Y870091D01*
X1407046Y870178D01*
G02X1406974Y870606I1225J426D01*
G37*
G36*
G01X1414374D02*
G02X1416968I1297J0D01*
G02X1415913Y869331I-1298J0D01*
G01X1415823Y869314D01*
X1415015Y867915D01*
X1415045Y867828D01*
G02X1415118Y867401I-1225J-429D01*
G02X1412522I-1298J0D01*
G02X1413580Y868676I1297J0D01*
G01X1413670Y868693D01*
X1414477Y870091D01*
X1414446Y870178D01*
G02X1414374Y870606I1225J426D01*
G37*
G36*
G01X1421774D02*
G02X1424368I1297J0D01*
G02X1423313Y869331I-1298J0D01*
G01X1423223Y869314D01*
X1422415Y867915D01*
X1422445Y867828D01*
G02X1422518Y867401I-1225J-429D01*
G02X1419922I-1298J0D01*
G02X1420980Y868676I1297J0D01*
G01X1421070Y868693D01*
X1421877Y870091D01*
X1421846Y870178D01*
G02X1421774Y870606I1225J426D01*
G37*
G36*
G01X1429174D02*
G02X1431768I1297J0D01*
G02X1430713Y869331I-1298J0D01*
G01X1430623Y869314D01*
X1429815Y867915D01*
X1429845Y867828D01*
G02X1429918Y867401I-1225J-429D01*
G02X1427322I-1298J0D01*
G02X1428380Y868676I1297J0D01*
G01X1428470Y868693D01*
X1429277Y870091D01*
X1429246Y870178D01*
G02X1429174Y870606I1225J426D01*
G37*
G36*
G01X1436574D02*
G02X1439168I1297J0D01*
G02X1438113Y869331I-1298J0D01*
G01X1438023Y869314D01*
X1437215Y867915D01*
X1437245Y867828D01*
G02X1437318Y867401I-1225J-429D01*
G02X1434722I-1298J0D01*
G02X1435780Y868676I1297J0D01*
G01X1435870Y868693D01*
X1436677Y870091D01*
X1436646Y870178D01*
G02X1436574Y870606I1225J426D01*
G37*
G36*
G01X1443974D02*
G02X1446568I1297J0D01*
G02X1445513Y869331I-1298J0D01*
G01X1445423Y869314D01*
X1444615Y867915D01*
X1444645Y867828D01*
G02X1444718Y867401I-1225J-429D01*
G02X1442122I-1298J0D01*
G02X1443180Y868676I1297J0D01*
G01X1443270Y868693D01*
X1444077Y870091D01*
X1444046Y870178D01*
G02X1443974Y870606I1225J426D01*
G37*
G36*
G01X1451374D02*
G02X1453968I1297J0D01*
G02X1452913Y869331I-1298J0D01*
G01X1452823Y869314D01*
X1452015Y867915D01*
X1452045Y867828D01*
G02X1452118Y867401I-1225J-429D01*
G02X1449522I-1298J0D01*
G02X1450580Y868676I1297J0D01*
G01X1450670Y868693D01*
X1451477Y870091D01*
X1451446Y870178D01*
G02X1451374Y870606I1225J426D01*
G37*
G36*
G01X1458774D02*
G02X1461368I1297J0D01*
G02X1460313Y869331I-1298J0D01*
G01X1460223Y869314D01*
X1459415Y867915D01*
X1459445Y867828D01*
G02X1459518Y867401I-1225J-429D01*
G02X1456922I-1298J0D01*
G02X1457980Y868676I1297J0D01*
G01X1458070Y868693D01*
X1458877Y870091D01*
X1458846Y870178D01*
G02X1458774Y870606I1225J426D01*
G37*
G36*
G01X1466174D02*
G02X1468768I1297J0D01*
G02X1467713Y869331I-1298J0D01*
G01X1467623Y869314D01*
X1466815Y867915D01*
X1466845Y867828D01*
G02X1466918Y867401I-1225J-429D01*
G02X1464322I-1298J0D01*
G02X1465380Y868676I1297J0D01*
G01X1465470Y868693D01*
X1466277Y870091D01*
X1466246Y870178D01*
G02X1466174Y870606I1225J426D01*
G37*
G36*
G01X1473574D02*
G02X1476168I1297J0D01*
G02X1475113Y869331I-1298J0D01*
G01X1475023Y869314D01*
X1474215Y867915D01*
X1474245Y867828D01*
G02X1474318Y867401I-1225J-429D01*
G02X1471722I-1298J0D01*
G02X1472780Y868676I1297J0D01*
G01X1472870Y868693D01*
X1473677Y870091D01*
X1473646Y870178D01*
G02X1473574Y870606I1225J426D01*
G37*
G36*
G01X1480974D02*
G02X1483568I1297J0D01*
G02X1482513Y869331I-1298J0D01*
G01X1482423Y869314D01*
X1481615Y867915D01*
X1481645Y867828D01*
G02X1481718Y867401I-1225J-429D01*
G02X1479122I-1298J0D01*
G02X1480180Y868676I1297J0D01*
G01X1480270Y868693D01*
X1481077Y870091D01*
X1481046Y870178D01*
G02X1480974Y870606I1225J426D01*
G37*
G36*
G01X1488374D02*
G02X1490968I1297J0D01*
G02X1489913Y869331I-1298J0D01*
G01X1489823Y869314D01*
X1489015Y867915D01*
X1489045Y867828D01*
G02X1489118Y867401I-1225J-429D01*
G02X1486522I-1298J0D01*
G02X1487580Y868676I1297J0D01*
G01X1487670Y868693D01*
X1488477Y870091D01*
X1488446Y870178D01*
G02X1488374Y870606I1225J426D01*
G37*
G36*
G01X1495774D02*
G02X1498368I1297J0D01*
G02X1497313Y869331I-1298J0D01*
G01X1497223Y869314D01*
X1496415Y867915D01*
X1496445Y867828D01*
G02X1496518Y867401I-1225J-429D01*
G02X1493922I-1298J0D01*
G02X1494980Y868676I1297J0D01*
G01X1495070Y868693D01*
X1495877Y870091D01*
X1495846Y870178D01*
G02X1495774Y870606I1225J426D01*
G37*
G36*
G01X1503174D02*
G02X1505768I1297J0D01*
G02X1504713Y869331I-1298J0D01*
G01X1504623Y869314D01*
X1503816Y867916D01*
X1503846Y867829D01*
G02X1503918Y867401I-1225J-426D01*
G02X1501324I-1297J0D01*
G02X1502380Y868676I1298J0D01*
G01X1502470Y868693D01*
X1503277Y870091D01*
X1503246Y870178D01*
G02X1503174Y870606I1225J426D01*
G37*
G36*
G01X351280Y873810D02*
G02X353876I1298J0D01*
G02X352820Y872535I-1298J0D01*
G01X352730Y872518D01*
X351923Y871121D01*
X351954Y871034D01*
G02X352026Y870606I-1225J-426D01*
G02X349432I-1297J0D01*
G02X350487Y871881I1298J0D01*
G01X350577Y871898D01*
X351384Y873295D01*
X351353Y873382D01*
G02X351280Y873810I1225J429D01*
G37*
G36*
G01X358680D02*
G02X361276I1298J0D01*
G02X360220Y872535I-1298J0D01*
G01X360130Y872518D01*
X359323Y871121D01*
X359354Y871034D01*
G02X359426Y870606I-1225J-426D01*
G02X356832I-1297J0D01*
G02X357887Y871881I1298J0D01*
G01X357977Y871898D01*
X358784Y873295D01*
X358753Y873382D01*
G02X358680Y873810I1225J429D01*
G37*
G36*
G01X366080D02*
G02X368676I1298J0D01*
G02X367620Y872535I-1298J0D01*
G01X367530Y872518D01*
X366723Y871121D01*
X366754Y871034D01*
G02X366826Y870606I-1225J-426D01*
G02X364232I-1297J0D01*
G02X365287Y871881I1298J0D01*
G01X365377Y871898D01*
X366184Y873295D01*
X366153Y873382D01*
G02X366080Y873810I1225J429D01*
G37*
G36*
G01X373480D02*
G02X376076I1298J0D01*
G02X375020Y872535I-1298J0D01*
G01X374930Y872518D01*
X374123Y871121D01*
X374154Y871034D01*
G02X374226Y870606I-1225J-426D01*
G02X371632I-1297J0D01*
G02X372687Y871881I1298J0D01*
G01X372777Y871898D01*
X373584Y873295D01*
X373553Y873382D01*
G02X373480Y873810I1225J429D01*
G37*
G36*
G01X380880D02*
G02X383476I1298J0D01*
G02X382420Y872535I-1298J0D01*
G01X382330Y872518D01*
X381523Y871121D01*
X381554Y871034D01*
G02X381626Y870606I-1225J-426D01*
G02X379032I-1297J0D01*
G02X380087Y871881I1298J0D01*
G01X380177Y871898D01*
X380984Y873295D01*
X380953Y873382D01*
G02X380880Y873810I1225J429D01*
G37*
G36*
G01X388280D02*
G02X390876I1298J0D01*
G02X389820Y872535I-1298J0D01*
G01X389730Y872518D01*
X388923Y871121D01*
X388954Y871034D01*
G02X389026Y870606I-1225J-426D01*
G02X386432I-1297J0D01*
G02X387487Y871881I1298J0D01*
G01X387577Y871898D01*
X388384Y873295D01*
X388353Y873382D01*
G02X388280Y873810I1225J429D01*
G37*
G36*
G01X395680D02*
G02X398276I1298J0D01*
G02X397220Y872535I-1298J0D01*
G01X397130Y872518D01*
X396323Y871121D01*
X396354Y871034D01*
G02X396426Y870606I-1225J-426D01*
G02X393832I-1297J0D01*
G02X394887Y871881I1298J0D01*
G01X394977Y871898D01*
X395784Y873295D01*
X395753Y873382D01*
G02X395680Y873810I1225J429D01*
G37*
G36*
G01X403080D02*
G02X405676I1298J0D01*
G02X404620Y872535I-1298J0D01*
G01X404530Y872518D01*
X403723Y871121D01*
X403754Y871034D01*
G02X403826Y870606I-1225J-426D01*
G02X401232I-1297J0D01*
G02X402287Y871881I1298J0D01*
G01X402377Y871898D01*
X403184Y873295D01*
X403153Y873382D01*
G02X403080Y873810I1225J429D01*
G37*
G36*
G01X410480D02*
G02X413076I1298J0D01*
G02X413003Y873381I-1297J0D01*
G01X412972Y873295D01*
X413778Y871898D01*
X413868Y871881D01*
G02X414926Y870606I-239J-1275D01*
G02X412332I-1297J0D01*
G02X412403Y871032I1297J3D01*
G01X412434Y871119D01*
X411626Y872518D01*
X411536Y872535D01*
G02X410480Y873810I242J1275D01*
G37*
G36*
G01X417880D02*
G02X420476I1298J0D01*
G02X420403Y873381I-1297J0D01*
G01X420372Y873295D01*
X421178Y871898D01*
X421268Y871881D01*
G02X422326Y870606I-239J-1275D01*
G02X419732I-1297J0D01*
G02X419803Y871032I1297J3D01*
G01X419834Y871119D01*
X419026Y872518D01*
X418936Y872535D01*
G02X417880Y873810I242J1275D01*
G37*
G36*
G01X425280D02*
G02X427876I1298J0D01*
G02X427803Y873381I-1297J0D01*
G01X427772Y873295D01*
X428578Y871898D01*
X428668Y871881D01*
G02X429726Y870606I-239J-1275D01*
G02X427132I-1297J0D01*
G02X427203Y871032I1297J3D01*
G01X427234Y871119D01*
X426426Y872518D01*
X426336Y872535D01*
G02X425280Y873810I242J1275D01*
G37*
G36*
G01X432682D02*
G02X435276I1297J0D01*
G02X435204Y873381I-1297J-3D01*
G01X435173Y873295D01*
X435979Y871898D01*
X436069Y871881D01*
G02X437126Y870606I-240J-1275D01*
G02X434532I-1297J0D01*
G01Y870608D01*
G02X434604Y871033I1297J-1D01*
G01X434634Y871120D01*
X433827Y872518D01*
X433737Y872535D01*
G02X432682Y873810I243J1275D01*
G37*
G36*
G01X440080D02*
G02X442676I1298J0D01*
G02X442603Y873381I-1297J0D01*
G01X442572Y873295D01*
X443378Y871898D01*
X443468Y871881D01*
G02X444526Y870606I-239J-1275D01*
G02X441932I-1297J0D01*
G02X442003Y871032I1297J3D01*
G01X442034Y871119D01*
X441226Y872518D01*
X441136Y872535D01*
G02X440080Y873810I242J1275D01*
G37*
G36*
G01X447482D02*
G02X450076I1297J0D01*
G02X450004Y873381I-1297J-3D01*
G01X449973Y873295D01*
X450779Y871898D01*
X450869Y871881D01*
G02X451926Y870606I-240J-1275D01*
G02X449332I-1297J0D01*
G01Y870608D01*
G02X449404Y871033I1297J-1D01*
G01X449434Y871120D01*
X448627Y872518D01*
X448537Y872535D01*
G02X447482Y873810I243J1275D01*
G37*
G36*
G01X454880D02*
G02X457476I1298J0D01*
G02X457403Y873381I-1297J0D01*
G01X457372Y873295D01*
X458178Y871898D01*
X458268Y871881D01*
G02X459326Y870606I-239J-1275D01*
G02X456732I-1297J0D01*
G02X456803Y871032I1297J3D01*
G01X456834Y871119D01*
X456026Y872518D01*
X455936Y872535D01*
G02X454880Y873810I242J1275D01*
G37*
G36*
G01X462280D02*
G02X464876I1298J0D01*
G02X464803Y873381I-1297J0D01*
G01X464772Y873295D01*
X465578Y871898D01*
X465668Y871881D01*
G02X466726Y870606I-239J-1275D01*
G02X464132I-1297J0D01*
G02X464203Y871032I1297J3D01*
G01X464234Y871119D01*
X463426Y872518D01*
X463336Y872535D01*
G02X462280Y873810I242J1275D01*
G37*
G36*
G01X477080D02*
G02X479676I1298J0D01*
G02X479603Y873381I-1297J0D01*
G01X479572Y873295D01*
X480378Y871898D01*
X480468Y871881D01*
G02X481526Y870606I-239J-1275D01*
G02X478932I-1297J0D01*
G02X479003Y871032I1297J3D01*
G01X479034Y871119D01*
X478226Y872518D01*
X478136Y872535D01*
G02X477080Y873810I242J1275D01*
G37*
G36*
G01X484480D02*
G02X487076I1298J0D01*
G02X487003Y873381I-1297J0D01*
G01X486972Y873295D01*
X487778Y871898D01*
X487868Y871881D01*
G02X488926Y870606I-239J-1275D01*
G02X486332I-1297J0D01*
G02X486403Y871032I1297J3D01*
G01X486434Y871119D01*
X485626Y872518D01*
X485536Y872535D01*
G02X484480Y873810I242J1275D01*
G37*
G36*
G01X491880D02*
G02X494476I1298J0D01*
G02X494403Y873381I-1297J0D01*
G01X494372Y873295D01*
X495178Y871898D01*
X495268Y871881D01*
G02X496326Y870606I-239J-1275D01*
G02X493732I-1297J0D01*
G02X493803Y871032I1297J3D01*
G01X493834Y871119D01*
X493026Y872518D01*
X492936Y872535D01*
G02X491880Y873810I242J1275D01*
G37*
G36*
G01X499280D02*
G02X501876I1298J0D01*
G02X501803Y873381I-1297J0D01*
G01X501772Y873295D01*
X502578Y871898D01*
X502668Y871881D01*
G02X503726Y870606I-239J-1275D01*
G02X501132I-1297J0D01*
G02X501203Y871032I1297J3D01*
G01X501234Y871119D01*
X500426Y872518D01*
X500336Y872535D01*
G02X499280Y873810I242J1275D01*
G37*
G36*
G01X506680D02*
G02X509276I1298J0D01*
G02X509203Y873381I-1297J0D01*
G01X509172Y873295D01*
X509978Y871898D01*
X510068Y871881D01*
G02X511126Y870606I-239J-1275D01*
G02X508532I-1297J0D01*
G02X508603Y871032I1297J3D01*
G01X508634Y871119D01*
X507826Y872518D01*
X507736Y872535D01*
G02X506680Y873810I242J1275D01*
G37*
G36*
G01X514080D02*
G02X516676I1298J0D01*
G02X516603Y873381I-1297J0D01*
G01X516572Y873295D01*
X517378Y871898D01*
X517468Y871881D01*
G02X518526Y870606I-239J-1275D01*
G02X515932I-1297J0D01*
G02X516003Y871032I1297J3D01*
G01X516034Y871119D01*
X515226Y872518D01*
X515136Y872535D01*
G02X514080Y873810I242J1275D01*
G37*
G36*
G01X1327422D02*
G02X1330018I1298J0D01*
G02X1328962Y872535I-1298J0D01*
G01X1328872Y872518D01*
X1328065Y871121D01*
X1328096Y871034D01*
G02X1328168Y870606I-1225J-426D01*
G02X1325574I-1297J0D01*
G02X1326629Y871881I1298J0D01*
G01X1326719Y871898D01*
X1327526Y873295D01*
X1327495Y873382D01*
G02X1327422Y873810I1225J429D01*
G37*
G36*
G01X1334822D02*
G02X1337418I1298J0D01*
G02X1336362Y872535I-1298J0D01*
G01X1336272Y872518D01*
X1335465Y871121D01*
X1335496Y871034D01*
G02X1335568Y870606I-1225J-426D01*
G02X1332974I-1297J0D01*
G02X1334029Y871881I1298J0D01*
G01X1334119Y871898D01*
X1334926Y873295D01*
X1334895Y873382D01*
G02X1334822Y873810I1225J429D01*
G37*
G36*
G01X1342222D02*
G02X1344818I1298J0D01*
G02X1343762Y872535I-1298J0D01*
G01X1343672Y872518D01*
X1342865Y871121D01*
X1342896Y871034D01*
G02X1342968Y870606I-1225J-426D01*
G02X1340374I-1297J0D01*
G02X1341429Y871881I1298J0D01*
G01X1341519Y871898D01*
X1342326Y873295D01*
X1342295Y873382D01*
G02X1342222Y873810I1225J429D01*
G37*
G36*
G01X1349622D02*
G02X1352218I1298J0D01*
G02X1351162Y872535I-1298J0D01*
G01X1351072Y872518D01*
X1350265Y871121D01*
X1350296Y871034D01*
G02X1350368Y870606I-1225J-426D01*
G02X1347774I-1297J0D01*
G02X1348829Y871881I1298J0D01*
G01X1348919Y871898D01*
X1349726Y873295D01*
X1349695Y873382D01*
G02X1349622Y873810I1225J429D01*
G37*
G36*
G01X1357022D02*
G02X1359618I1298J0D01*
G02X1358562Y872535I-1298J0D01*
G01X1358472Y872518D01*
X1357665Y871121D01*
X1357696Y871034D01*
G02X1357768Y870606I-1225J-426D01*
G02X1355174I-1297J0D01*
G02X1356229Y871881I1298J0D01*
G01X1356319Y871898D01*
X1357126Y873295D01*
X1357095Y873382D01*
G02X1357022Y873810I1225J429D01*
G37*
G36*
G01X1364422D02*
G02X1367018I1298J0D01*
G02X1365962Y872535I-1298J0D01*
G01X1365872Y872518D01*
X1365065Y871121D01*
X1365096Y871034D01*
G02X1365168Y870606I-1225J-426D01*
G02X1362574I-1297J0D01*
G02X1363629Y871881I1298J0D01*
G01X1363719Y871898D01*
X1364526Y873295D01*
X1364495Y873382D01*
G02X1364422Y873810I1225J429D01*
G37*
G36*
G01X1371822D02*
G02X1374418I1298J0D01*
G02X1373362Y872535I-1298J0D01*
G01X1373272Y872518D01*
X1372465Y871121D01*
X1372496Y871034D01*
G02X1372568Y870606I-1225J-426D01*
G02X1369974I-1297J0D01*
G02X1371029Y871881I1298J0D01*
G01X1371119Y871898D01*
X1371926Y873295D01*
X1371895Y873382D01*
G02X1371822Y873810I1225J429D01*
G37*
G36*
G01X1379222D02*
G02X1381818I1298J0D01*
G02X1380762Y872535I-1298J0D01*
G01X1380672Y872518D01*
X1379865Y871121D01*
X1379896Y871034D01*
G02X1379968Y870606I-1225J-426D01*
G02X1377374I-1297J0D01*
G02X1378429Y871881I1298J0D01*
G01X1378519Y871898D01*
X1379326Y873295D01*
X1379295Y873382D01*
G02X1379222Y873810I1225J429D01*
G37*
G36*
G01X1386622D02*
G02X1389218I1298J0D01*
G02X1389145Y873381I-1297J0D01*
G01X1389114Y873295D01*
X1389920Y871898D01*
X1390010Y871881D01*
G02X1391068Y870606I-239J-1275D01*
G02X1388474I-1297J0D01*
G02X1388545Y871032I1297J3D01*
G01X1388576Y871119D01*
X1387768Y872518D01*
X1387678Y872535D01*
G02X1386622Y873810I242J1275D01*
G37*
G36*
G01X1394022D02*
G02X1396618I1298J0D01*
G02X1396545Y873381I-1297J0D01*
G01X1396514Y873295D01*
X1397320Y871898D01*
X1397410Y871881D01*
G02X1398468Y870606I-239J-1275D01*
G02X1395874I-1297J0D01*
G02X1395945Y871032I1297J3D01*
G01X1395976Y871119D01*
X1395168Y872518D01*
X1395078Y872535D01*
G02X1394022Y873810I242J1275D01*
G37*
G36*
G01X1401422D02*
G02X1404018I1298J0D01*
G02X1403945Y873381I-1297J0D01*
G01X1403914Y873295D01*
X1404720Y871898D01*
X1404810Y871881D01*
G02X1405868Y870606I-239J-1275D01*
G02X1403274I-1297J0D01*
G02X1403345Y871032I1297J3D01*
G01X1403376Y871119D01*
X1402568Y872518D01*
X1402478Y872535D01*
G02X1401422Y873810I242J1275D01*
G37*
G36*
G01X1408824D02*
G02X1411418I1297J0D01*
G02X1411346Y873381I-1297J-3D01*
G01X1411315Y873295D01*
X1412121Y871898D01*
X1412211Y871881D01*
G02X1413268Y870606I-240J-1275D01*
G02X1410674I-1297J0D01*
G01Y870608D01*
G02X1410746Y871033I1297J-1D01*
G01X1410776Y871120D01*
X1409969Y872518D01*
X1409879Y872535D01*
G02X1408824Y873810I243J1275D01*
G37*
G36*
G01X1416222D02*
G02X1418818I1298J0D01*
G02X1418745Y873381I-1297J0D01*
G01X1418714Y873295D01*
X1419520Y871898D01*
X1419610Y871881D01*
G02X1420668Y870606I-239J-1275D01*
G02X1418074I-1297J0D01*
G02X1418145Y871032I1297J3D01*
G01X1418176Y871119D01*
X1417368Y872518D01*
X1417278Y872535D01*
G02X1416222Y873810I242J1275D01*
G37*
G36*
G01X1423624D02*
G02X1426218I1297J0D01*
G02X1426146Y873381I-1297J-3D01*
G01X1426115Y873295D01*
X1426921Y871898D01*
X1427011Y871881D01*
G02X1428068Y870606I-240J-1275D01*
G02X1425474I-1297J0D01*
G01Y870608D01*
G02X1425546Y871033I1297J-1D01*
G01X1425576Y871120D01*
X1424769Y872518D01*
X1424679Y872535D01*
G02X1423624Y873810I243J1275D01*
G37*
G36*
G01X1431022D02*
G02X1433618I1298J0D01*
G02X1433545Y873381I-1297J0D01*
G01X1433514Y873295D01*
X1434320Y871898D01*
X1434410Y871881D01*
G02X1435468Y870606I-239J-1275D01*
G02X1432874I-1297J0D01*
G02X1432945Y871032I1297J3D01*
G01X1432976Y871119D01*
X1432168Y872518D01*
X1432078Y872535D01*
G02X1431022Y873810I242J1275D01*
G37*
G36*
G01X1438422D02*
G02X1441018I1298J0D01*
G02X1440945Y873381I-1297J0D01*
G01X1440914Y873295D01*
X1441720Y871898D01*
X1441810Y871881D01*
G02X1442868Y870606I-239J-1275D01*
G02X1440274I-1297J0D01*
G02X1440345Y871032I1297J3D01*
G01X1440376Y871119D01*
X1439568Y872518D01*
X1439478Y872535D01*
G02X1438422Y873810I242J1275D01*
G37*
G36*
G01X1453222D02*
G02X1455818I1298J0D01*
G02X1455745Y873381I-1297J0D01*
G01X1455714Y873295D01*
X1456520Y871898D01*
X1456610Y871881D01*
G02X1457668Y870606I-239J-1275D01*
G02X1455074I-1297J0D01*
G02X1455145Y871032I1297J3D01*
G01X1455176Y871119D01*
X1454368Y872518D01*
X1454278Y872535D01*
G02X1453222Y873810I242J1275D01*
G37*
G36*
G01X1460622D02*
G02X1463218I1298J0D01*
G02X1463145Y873381I-1297J0D01*
G01X1463114Y873295D01*
X1463920Y871898D01*
X1464010Y871881D01*
G02X1465068Y870606I-239J-1275D01*
G02X1462474I-1297J0D01*
G02X1462545Y871032I1297J3D01*
G01X1462576Y871119D01*
X1461768Y872518D01*
X1461678Y872535D01*
G02X1460622Y873810I242J1275D01*
G37*
G36*
G01X1468022D02*
G02X1470618I1298J0D01*
G02X1470545Y873381I-1297J0D01*
G01X1470514Y873295D01*
X1471320Y871898D01*
X1471410Y871881D01*
G02X1472468Y870606I-239J-1275D01*
G02X1469874I-1297J0D01*
G02X1469945Y871032I1297J3D01*
G01X1469976Y871119D01*
X1469168Y872518D01*
X1469078Y872535D01*
G02X1468022Y873810I242J1275D01*
G37*
G36*
G01X1475422D02*
G02X1478018I1298J0D01*
G02X1477945Y873381I-1297J0D01*
G01X1477914Y873295D01*
X1478720Y871898D01*
X1478810Y871881D01*
G02X1479868Y870606I-239J-1275D01*
G02X1477274I-1297J0D01*
G02X1477345Y871032I1297J3D01*
G01X1477376Y871119D01*
X1476568Y872518D01*
X1476478Y872535D01*
G02X1475422Y873810I242J1275D01*
G37*
G36*
G01X1482822D02*
G02X1485418I1298J0D01*
G02X1485345Y873381I-1297J0D01*
G01X1485314Y873295D01*
X1486120Y871898D01*
X1486210Y871881D01*
G02X1487268Y870606I-239J-1275D01*
G02X1484674I-1297J0D01*
G02X1484745Y871032I1297J3D01*
G01X1484776Y871119D01*
X1483968Y872518D01*
X1483878Y872535D01*
G02X1482822Y873810I242J1275D01*
G37*
G36*
G01X1490222D02*
G02X1492818I1298J0D01*
G02X1492745Y873381I-1297J0D01*
G01X1492714Y873295D01*
X1493520Y871898D01*
X1493610Y871881D01*
G02X1494668Y870606I-239J-1275D01*
G02X1492074I-1297J0D01*
G02X1492145Y871032I1297J3D01*
G01X1492176Y871119D01*
X1491368Y872518D01*
X1491278Y872535D01*
G02X1490222Y873810I242J1275D01*
G37*
G36*
G01X367932Y883423D02*
G02X370526I1297J0D01*
G02X370454Y882994I-1297J-3D01*
G01X370423Y882908D01*
X371229Y881511D01*
X371319Y881494D01*
G02X372376Y880219I-240J-1275D01*
G02X369780I-1298J0D01*
G02X369853Y880647I1298J-1D01*
G01X369883Y880734D01*
X369077Y882131D01*
X368987Y882148D01*
G02X367932Y883423I243J1275D01*
G37*
G36*
G01X375332D02*
G02X377926I1297J0D01*
G02X377854Y882994I-1297J-3D01*
G01X377823Y882908D01*
X378629Y881511D01*
X378719Y881494D01*
G02X379776Y880219I-240J-1275D01*
G02X377180I-1298J0D01*
G02X377253Y880647I1298J-1D01*
G01X377283Y880734D01*
X376477Y882131D01*
X376387Y882148D01*
G02X375332Y883423I243J1275D01*
G37*
G36*
G01X382732D02*
G02X385326I1297J0D01*
G02X385254Y882994I-1297J-3D01*
G01X385223Y882908D01*
X386029Y881511D01*
X386119Y881494D01*
G02X387176Y880219I-240J-1275D01*
G02X384580I-1298J0D01*
G02X384653Y880647I1298J-1D01*
G01X384683Y880734D01*
X383877Y882131D01*
X383787Y882148D01*
G02X382732Y883423I243J1275D01*
G37*
G36*
G01X390132D02*
G02X392726I1297J0D01*
G02X392654Y882994I-1297J-3D01*
G01X392623Y882908D01*
X393429Y881511D01*
X393519Y881494D01*
G02X394576Y880219I-240J-1275D01*
G02X391980I-1298J0D01*
G02X392053Y880647I1298J-1D01*
G01X392083Y880734D01*
X391277Y882131D01*
X391187Y882148D01*
G02X390132Y883423I243J1275D01*
G37*
G36*
G01X397532D02*
G02X400126I1297J0D01*
G02X400054Y882994I-1297J-3D01*
G01X400023Y882908D01*
X400829Y881511D01*
X400919Y881494D01*
G02X401976Y880219I-240J-1275D01*
G02X399380I-1298J0D01*
G02X399453Y880647I1298J-1D01*
G01X399483Y880734D01*
X398677Y882131D01*
X398587Y882148D01*
G02X397532Y883423I243J1275D01*
G37*
G36*
G01X404932D02*
G02X407526I1297J0D01*
G02X407454Y882994I-1297J-3D01*
G01X407423Y882908D01*
X408229Y881511D01*
X408319Y881494D01*
G02X409376Y880219I-240J-1275D01*
G02X406780I-1298J0D01*
G02X406853Y880647I1298J-1D01*
G01X406883Y880734D01*
X406077Y882131D01*
X405987Y882148D01*
G02X404932Y883423I243J1275D01*
G37*
G36*
G01X412332D02*
G02X414926I1297J0D01*
G02X414854Y882994I-1297J-3D01*
G01X414823Y882908D01*
X415629Y881511D01*
X415719Y881494D01*
G02X416776Y880219I-240J-1275D01*
G02X414180I-1298J0D01*
G02X414253Y880647I1298J-1D01*
G01X414283Y880734D01*
X413477Y882131D01*
X413387Y882148D01*
G02X412332Y883423I243J1275D01*
G37*
G36*
G01X419732D02*
G02X422326I1297J0D01*
G02X422254Y882994I-1297J-3D01*
G01X422223Y882908D01*
X423029Y881511D01*
X423119Y881494D01*
G02X424176Y880219I-240J-1275D01*
G02X421580I-1298J0D01*
G02X421653Y880647I1298J-1D01*
G01X421683Y880734D01*
X420877Y882131D01*
X420787Y882148D01*
G02X419732Y883423I243J1275D01*
G37*
G36*
G01X427132D02*
G02X429726I1297J0D01*
G02X429654Y882994I-1297J-3D01*
G01X429623Y882908D01*
X430429Y881511D01*
X430519Y881494D01*
G02X431576Y880219I-240J-1275D01*
G02X428980I-1298J0D01*
G02X429053Y880647I1298J-1D01*
G01X429083Y880734D01*
X428277Y882131D01*
X428187Y882148D01*
G02X427132Y883423I243J1275D01*
G37*
G36*
G01X434532D02*
G02X437126I1297J0D01*
G02X437054Y882994I-1297J-3D01*
G01X437023Y882908D01*
X437829Y881511D01*
X437919Y881494D01*
G02X438976Y880219I-240J-1275D01*
G02X436380I-1298J0D01*
G02X436453Y880647I1298J-1D01*
G01X436483Y880734D01*
X435677Y882131D01*
X435587Y882148D01*
G02X434532Y883423I243J1275D01*
G37*
G36*
G01X441932D02*
G02X444526I1297J0D01*
G02X444454Y882994I-1297J-3D01*
G01X444423Y882908D01*
X445229Y881511D01*
X445319Y881494D01*
G02X446376Y880219I-240J-1275D01*
G02X443780I-1298J0D01*
G02X443853Y880647I1298J-1D01*
G01X443883Y880734D01*
X443077Y882131D01*
X442987Y882148D01*
G02X441932Y883423I243J1275D01*
G37*
G36*
G01X449332D02*
G02X451926I1297J0D01*
G02X451854Y882994I-1297J-3D01*
G01X451823Y882908D01*
X452629Y881511D01*
X452719Y881494D01*
G02X453776Y880219I-240J-1275D01*
G02X451182I-1297J0D01*
G01Y880221D01*
G02X451254Y880646I1297J-1D01*
G01X451284Y880733D01*
X450477Y882131D01*
X450387Y882148D01*
G02X449332Y883423I243J1275D01*
G37*
G36*
G01X456732D02*
G02X459326I1297J0D01*
G02X459254Y882994I-1297J-3D01*
G01X459223Y882908D01*
X460029Y881511D01*
X460119Y881494D01*
G02X461176Y880219I-240J-1275D01*
G02X458580I-1298J0D01*
G02X458653Y880647I1298J-1D01*
G01X458683Y880734D01*
X457877Y882131D01*
X457787Y882148D01*
G02X456732Y883423I243J1275D01*
G37*
G36*
G01X464132D02*
G02X466726I1297J0D01*
G02X466654Y882994I-1297J-3D01*
G01X466623Y882908D01*
X467429Y881511D01*
X467519Y881494D01*
G02X468576Y880219I-240J-1275D01*
G02X465980I-1298J0D01*
G02X466053Y880647I1298J-1D01*
G01X466083Y880734D01*
X465277Y882131D01*
X465187Y882148D01*
G02X464132Y883423I243J1275D01*
G37*
G36*
G01X471532D02*
G02X474126I1297J0D01*
G02X474054Y882994I-1297J-3D01*
G01X474023Y882908D01*
X474829Y881511D01*
X474919Y881494D01*
G02X475976Y880219I-240J-1275D01*
G02X473380I-1298J0D01*
G02X473453Y880647I1298J-1D01*
G01X473483Y880734D01*
X472677Y882131D01*
X472587Y882148D01*
G02X471532Y883423I243J1275D01*
G37*
G36*
G01X478932D02*
G02X481526I1297J0D01*
G02X481454Y882994I-1297J-3D01*
G01X481423Y882908D01*
X482229Y881511D01*
X482319Y881494D01*
G02X483376Y880219I-240J-1275D01*
G02X480780I-1298J0D01*
G02X480853Y880647I1298J-1D01*
G01X480883Y880734D01*
X480077Y882131D01*
X479987Y882148D01*
G02X478932Y883423I243J1275D01*
G37*
G36*
G01X486332D02*
G02X488926I1297J0D01*
G02X488854Y882994I-1297J-3D01*
G01X488823Y882908D01*
X489629Y881511D01*
X489719Y881494D01*
G02X490776Y880219I-240J-1275D01*
G02X488180I-1298J0D01*
G02X488253Y880647I1298J-1D01*
G01X488283Y880734D01*
X487477Y882131D01*
X487387Y882148D01*
G02X486332Y883423I243J1275D01*
G37*
G36*
G01X493732D02*
G02X496326I1297J0D01*
G02X496254Y882994I-1297J-3D01*
G01X496223Y882908D01*
X497029Y881511D01*
X497119Y881494D01*
G02X498176Y880219I-240J-1275D01*
G02X495580I-1298J0D01*
G02X495653Y880647I1298J-1D01*
G01X495683Y880734D01*
X494877Y882131D01*
X494787Y882148D01*
G02X493732Y883423I243J1275D01*
G37*
G36*
G01X501132D02*
G02X503726I1297J0D01*
G02X503654Y882994I-1297J-3D01*
G01X503623Y882908D01*
X504429Y881511D01*
X504519Y881494D01*
G02X505576Y880219I-240J-1275D01*
G02X502980I-1298J0D01*
G02X503053Y880647I1298J-1D01*
G01X503083Y880734D01*
X502277Y882131D01*
X502187Y882148D01*
G02X501132Y883423I243J1275D01*
G37*
G36*
G01X508532D02*
G02X511126I1297J0D01*
G02X511054Y882994I-1297J-3D01*
G01X511023Y882908D01*
X511829Y881511D01*
X511919Y881494D01*
G02X512976Y880219I-240J-1275D01*
G02X510380I-1298J0D01*
G02X510453Y880647I1298J-1D01*
G01X510483Y880734D01*
X509677Y882131D01*
X509587Y882148D01*
G02X508532Y883423I243J1275D01*
G37*
G36*
G01X1344074D02*
G02X1346668I1297J0D01*
G02X1346596Y882994I-1297J-3D01*
G01X1346565Y882908D01*
X1347371Y881511D01*
X1347461Y881494D01*
G02X1348518Y880219I-240J-1275D01*
G02X1345922I-1298J0D01*
G02X1345995Y880647I1298J-1D01*
G01X1346025Y880734D01*
X1345219Y882131D01*
X1345129Y882148D01*
G02X1344074Y883423I243J1275D01*
G37*
G36*
G01X1351474D02*
G02X1354068I1297J0D01*
G02X1353996Y882994I-1297J-3D01*
G01X1353965Y882908D01*
X1354771Y881511D01*
X1354861Y881494D01*
G02X1355918Y880219I-240J-1275D01*
G02X1353322I-1298J0D01*
G02X1353395Y880647I1298J-1D01*
G01X1353425Y880734D01*
X1352619Y882131D01*
X1352529Y882148D01*
G02X1351474Y883423I243J1275D01*
G37*
G36*
G01X1358874D02*
G02X1361468I1297J0D01*
G02X1361396Y882994I-1297J-3D01*
G01X1361365Y882908D01*
X1362171Y881511D01*
X1362261Y881494D01*
G02X1363318Y880219I-240J-1275D01*
G02X1360722I-1298J0D01*
G02X1360795Y880647I1298J-1D01*
G01X1360825Y880734D01*
X1360019Y882131D01*
X1359929Y882148D01*
G02X1358874Y883423I243J1275D01*
G37*
G36*
G01X1366274D02*
G02X1368868I1297J0D01*
G02X1368796Y882994I-1297J-3D01*
G01X1368765Y882908D01*
X1369571Y881511D01*
X1369661Y881494D01*
G02X1370718Y880219I-240J-1275D01*
G02X1368122I-1298J0D01*
G02X1368195Y880647I1298J-1D01*
G01X1368225Y880734D01*
X1367419Y882131D01*
X1367329Y882148D01*
G02X1366274Y883423I243J1275D01*
G37*
G36*
G01X1373674D02*
G02X1376268I1297J0D01*
G02X1376196Y882994I-1297J-3D01*
G01X1376165Y882908D01*
X1376971Y881511D01*
X1377061Y881494D01*
G02X1378118Y880219I-240J-1275D01*
G02X1375522I-1298J0D01*
G02X1375595Y880647I1298J-1D01*
G01X1375625Y880734D01*
X1374819Y882131D01*
X1374729Y882148D01*
G02X1373674Y883423I243J1275D01*
G37*
G36*
G01X1381074D02*
G02X1383668I1297J0D01*
G02X1383596Y882994I-1297J-3D01*
G01X1383565Y882908D01*
X1384371Y881511D01*
X1384461Y881494D01*
G02X1385518Y880219I-240J-1275D01*
G02X1382922I-1298J0D01*
G02X1382995Y880647I1298J-1D01*
G01X1383025Y880734D01*
X1382219Y882131D01*
X1382129Y882148D01*
G02X1381074Y883423I243J1275D01*
G37*
G36*
G01X1388474D02*
G02X1391068I1297J0D01*
G02X1390996Y882994I-1297J-3D01*
G01X1390965Y882908D01*
X1391771Y881511D01*
X1391861Y881494D01*
G02X1392918Y880219I-240J-1275D01*
G02X1390322I-1298J0D01*
G02X1390395Y880647I1298J-1D01*
G01X1390425Y880734D01*
X1389619Y882131D01*
X1389529Y882148D01*
G02X1388474Y883423I243J1275D01*
G37*
G36*
G01X1395874D02*
G02X1398468I1297J0D01*
G02X1398396Y882994I-1297J-3D01*
G01X1398365Y882908D01*
X1399171Y881511D01*
X1399261Y881494D01*
G02X1400318Y880219I-240J-1275D01*
G02X1397722I-1298J0D01*
G02X1397795Y880647I1298J-1D01*
G01X1397825Y880734D01*
X1397019Y882131D01*
X1396929Y882148D01*
G02X1395874Y883423I243J1275D01*
G37*
G36*
G01X1403274D02*
G02X1405868I1297J0D01*
G02X1405796Y882994I-1297J-3D01*
G01X1405765Y882908D01*
X1406571Y881511D01*
X1406661Y881494D01*
G02X1407718Y880219I-240J-1275D01*
G02X1405122I-1298J0D01*
G02X1405195Y880647I1298J-1D01*
G01X1405225Y880734D01*
X1404419Y882131D01*
X1404329Y882148D01*
G02X1403274Y883423I243J1275D01*
G37*
G36*
G01X1410674D02*
G02X1413268I1297J0D01*
G02X1413196Y882994I-1297J-3D01*
G01X1413165Y882908D01*
X1413971Y881511D01*
X1414061Y881494D01*
G02X1415118Y880219I-240J-1275D01*
G02X1412522I-1298J0D01*
G02X1412595Y880647I1298J-1D01*
G01X1412625Y880734D01*
X1411819Y882131D01*
X1411729Y882148D01*
G02X1410674Y883423I243J1275D01*
G37*
G36*
G01X1418074D02*
G02X1420668I1297J0D01*
G02X1420596Y882994I-1297J-3D01*
G01X1420565Y882908D01*
X1421371Y881511D01*
X1421461Y881494D01*
G02X1422518Y880219I-240J-1275D01*
G02X1419922I-1298J0D01*
G02X1419995Y880647I1298J-1D01*
G01X1420025Y880734D01*
X1419219Y882131D01*
X1419129Y882148D01*
G02X1418074Y883423I243J1275D01*
G37*
G36*
G01X1425474D02*
G02X1428068I1297J0D01*
G02X1427996Y882994I-1297J-3D01*
G01X1427965Y882908D01*
X1428771Y881511D01*
X1428861Y881494D01*
G02X1429918Y880219I-240J-1275D01*
G02X1427324I-1297J0D01*
G01Y880221D01*
G02X1427396Y880646I1297J-1D01*
G01X1427426Y880733D01*
X1426619Y882131D01*
X1426529Y882148D01*
G02X1425474Y883423I243J1275D01*
G37*
G36*
G01X1432874D02*
G02X1435468I1297J0D01*
G02X1435396Y882994I-1297J-3D01*
G01X1435365Y882908D01*
X1436171Y881511D01*
X1436261Y881494D01*
G02X1437318Y880219I-240J-1275D01*
G02X1434722I-1298J0D01*
G02X1434795Y880647I1298J-1D01*
G01X1434825Y880734D01*
X1434019Y882131D01*
X1433929Y882148D01*
G02X1432874Y883423I243J1275D01*
G37*
G36*
G01X1440274D02*
G02X1442868I1297J0D01*
G02X1442796Y882994I-1297J-3D01*
G01X1442765Y882908D01*
X1443571Y881511D01*
X1443661Y881494D01*
G02X1444718Y880219I-240J-1275D01*
G02X1442122I-1298J0D01*
G02X1442195Y880647I1298J-1D01*
G01X1442225Y880734D01*
X1441419Y882131D01*
X1441329Y882148D01*
G02X1440274Y883423I243J1275D01*
G37*
G36*
G01X1447674D02*
G02X1450268I1297J0D01*
G02X1450196Y882994I-1297J-3D01*
G01X1450165Y882908D01*
X1450971Y881511D01*
X1451061Y881494D01*
G02X1452118Y880219I-240J-1275D01*
G02X1449522I-1298J0D01*
G02X1449595Y880647I1298J-1D01*
G01X1449625Y880734D01*
X1448819Y882131D01*
X1448729Y882148D01*
G02X1447674Y883423I243J1275D01*
G37*
G36*
G01X1455074D02*
G02X1457668I1297J0D01*
G02X1457596Y882994I-1297J-3D01*
G01X1457565Y882908D01*
X1458371Y881511D01*
X1458461Y881494D01*
G02X1459518Y880219I-240J-1275D01*
G02X1456922I-1298J0D01*
G02X1456995Y880647I1298J-1D01*
G01X1457025Y880734D01*
X1456219Y882131D01*
X1456129Y882148D01*
G02X1455074Y883423I243J1275D01*
G37*
G36*
G01X1462474D02*
G02X1465068I1297J0D01*
G02X1464996Y882994I-1297J-3D01*
G01X1464965Y882908D01*
X1465771Y881511D01*
X1465861Y881494D01*
G02X1466918Y880219I-240J-1275D01*
G02X1464322I-1298J0D01*
G02X1464395Y880647I1298J-1D01*
G01X1464425Y880734D01*
X1463619Y882131D01*
X1463529Y882148D01*
G02X1462474Y883423I243J1275D01*
G37*
G36*
G01X1469874D02*
G02X1472468I1297J0D01*
G02X1472396Y882994I-1297J-3D01*
G01X1472365Y882908D01*
X1473171Y881511D01*
X1473261Y881494D01*
G02X1474318Y880219I-240J-1275D01*
G02X1471722I-1298J0D01*
G02X1471795Y880647I1298J-1D01*
G01X1471825Y880734D01*
X1471019Y882131D01*
X1470929Y882148D01*
G02X1469874Y883423I243J1275D01*
G37*
G36*
G01X1477274D02*
G02X1479868I1297J0D01*
G02X1479796Y882994I-1297J-3D01*
G01X1479765Y882908D01*
X1480571Y881511D01*
X1480661Y881494D01*
G02X1481718Y880219I-240J-1275D01*
G02X1479122I-1298J0D01*
G02X1479195Y880647I1298J-1D01*
G01X1479225Y880734D01*
X1478419Y882131D01*
X1478329Y882148D01*
G02X1477274Y883423I243J1275D01*
G37*
G36*
G01X1484674D02*
G02X1487268I1297J0D01*
G02X1487196Y882994I-1297J-3D01*
G01X1487165Y882908D01*
X1487971Y881511D01*
X1488061Y881494D01*
G02X1489118Y880219I-240J-1275D01*
G02X1486522I-1298J0D01*
G02X1486595Y880647I1298J-1D01*
G01X1486625Y880734D01*
X1485819Y882131D01*
X1485729Y882148D01*
G02X1484674Y883423I243J1275D01*
G37*
G36*
G01X373480Y886627D02*
G02X376076I1298J0D01*
G02X375020Y885352I-1298J0D01*
G01X374930Y885335D01*
X374123Y883938D01*
X374154Y883851D01*
G02X374226Y883423I-1225J-426D01*
G02X371632I-1297J0D01*
G02X372687Y884698I1298J0D01*
G01X372777Y884715D01*
X373584Y886112D01*
X373553Y886199D01*
G02X373480Y886627I1225J429D01*
G37*
G36*
G01X380880D02*
G02X383476I1298J0D01*
G02X382420Y885352I-1298J0D01*
G01X382330Y885335D01*
X381523Y883938D01*
X381554Y883851D01*
G02X381626Y883423I-1225J-426D01*
G02X379032I-1297J0D01*
G02X380087Y884698I1298J0D01*
G01X380177Y884715D01*
X380984Y886112D01*
X380953Y886199D01*
G02X380880Y886627I1225J429D01*
G37*
G36*
G01X388280D02*
G02X390876I1298J0D01*
G02X389820Y885352I-1298J0D01*
G01X389730Y885335D01*
X388923Y883938D01*
X388954Y883851D01*
G02X389026Y883423I-1225J-426D01*
G02X386432I-1297J0D01*
G02X387487Y884698I1298J0D01*
G01X387577Y884715D01*
X388384Y886112D01*
X388353Y886199D01*
G02X388280Y886627I1225J429D01*
G37*
G36*
G01X395680D02*
G02X398276I1298J0D01*
G02X397220Y885352I-1298J0D01*
G01X397130Y885335D01*
X396323Y883938D01*
X396354Y883851D01*
G02X396426Y883423I-1225J-426D01*
G02X393832I-1297J0D01*
G02X394887Y884698I1298J0D01*
G01X394977Y884715D01*
X395784Y886112D01*
X395753Y886199D01*
G02X395680Y886627I1225J429D01*
G37*
G36*
G01X403080D02*
G02X405676I1298J0D01*
G02X404620Y885352I-1298J0D01*
G01X404530Y885335D01*
X403723Y883938D01*
X403754Y883851D01*
G02X403826Y883423I-1225J-426D01*
G02X401232I-1297J0D01*
G02X402287Y884698I1298J0D01*
G01X402377Y884715D01*
X403184Y886112D01*
X403153Y886199D01*
G02X403080Y886627I1225J429D01*
G37*
G36*
G01X410480D02*
G02X413076I1298J0D01*
G02X412020Y885352I-1298J0D01*
G01X411930Y885335D01*
X411123Y883938D01*
X411154Y883851D01*
G02X411226Y883423I-1225J-426D01*
G02X408632I-1297J0D01*
G02X409687Y884698I1298J0D01*
G01X409777Y884715D01*
X410584Y886112D01*
X410553Y886199D01*
G02X410480Y886627I1225J429D01*
G37*
G36*
G01X417880D02*
G02X420476I1298J0D01*
G02X419420Y885352I-1298J0D01*
G01X419330Y885335D01*
X418523Y883938D01*
X418554Y883851D01*
G02X418626Y883423I-1225J-426D01*
G02X416032I-1297J0D01*
G02X417087Y884698I1298J0D01*
G01X417177Y884715D01*
X417984Y886112D01*
X417953Y886199D01*
G02X417880Y886627I1225J429D01*
G37*
G36*
G01X425280D02*
G02X427876I1298J0D01*
G02X426820Y885352I-1298J0D01*
G01X426730Y885335D01*
X425923Y883938D01*
X425954Y883851D01*
G02X426026Y883423I-1225J-426D01*
G02X423432I-1297J0D01*
G02X424487Y884698I1298J0D01*
G01X424577Y884715D01*
X425384Y886112D01*
X425353Y886199D01*
G02X425280Y886627I1225J429D01*
G37*
G36*
G01X432680D02*
G02X435276I1298J0D01*
G02X434220Y885352I-1298J0D01*
G01X434130Y885335D01*
X433323Y883938D01*
X433354Y883851D01*
G02X433426Y883423I-1225J-426D01*
G02X430832I-1297J0D01*
G02X431887Y884698I1298J0D01*
G01X431977Y884715D01*
X432784Y886112D01*
X432753Y886199D01*
G02X432680Y886627I1225J429D01*
G37*
G36*
G01X440080D02*
G02X442676I1298J0D01*
G02X441620Y885352I-1298J0D01*
G01X441530Y885335D01*
X440723Y883938D01*
X440754Y883851D01*
G02X440826Y883423I-1225J-426D01*
G02X438232I-1297J0D01*
G02X439287Y884698I1298J0D01*
G01X439377Y884715D01*
X440184Y886112D01*
X440153Y886199D01*
G02X440080Y886627I1225J429D01*
G37*
G36*
G01X447480D02*
G02X450076I1298J0D01*
G02X449020Y885352I-1298J0D01*
G01X448930Y885335D01*
X448123Y883938D01*
X448154Y883851D01*
G02X448226Y883423I-1225J-426D01*
G02X445632I-1297J0D01*
G02X446687Y884698I1298J0D01*
G01X446777Y884715D01*
X447584Y886112D01*
X447553Y886199D01*
G02X447480Y886627I1225J429D01*
G37*
G36*
G01X454880D02*
G02X457476I1298J0D01*
G02X456420Y885352I-1298J0D01*
G01X456330Y885335D01*
X455523Y883938D01*
X455554Y883851D01*
G02X455626Y883423I-1225J-426D01*
G02X453032I-1297J0D01*
G02X454087Y884698I1298J0D01*
G01X454177Y884715D01*
X454984Y886112D01*
X454953Y886199D01*
G02X454880Y886627I1225J429D01*
G37*
G36*
G01X462280D02*
G02X464876I1298J0D01*
G02X463820Y885352I-1298J0D01*
G01X463730Y885335D01*
X462923Y883938D01*
X462954Y883851D01*
G02X463026Y883423I-1225J-426D01*
G02X460432I-1297J0D01*
G02X461487Y884698I1298J0D01*
G01X461577Y884715D01*
X462384Y886112D01*
X462353Y886199D01*
G02X462280Y886627I1225J429D01*
G37*
G36*
G01X469680D02*
G02X472276I1298J0D01*
G02X471220Y885352I-1298J0D01*
G01X471130Y885335D01*
X470323Y883938D01*
X470354Y883851D01*
G02X470426Y883423I-1225J-426D01*
G02X467832I-1297J0D01*
G02X468887Y884698I1298J0D01*
G01X468977Y884715D01*
X469784Y886112D01*
X469753Y886199D01*
G02X469680Y886627I1225J429D01*
G37*
G36*
G01X477080D02*
G02X479676I1298J0D01*
G02X478620Y885352I-1298J0D01*
G01X478530Y885335D01*
X477723Y883938D01*
X477754Y883851D01*
G02X477826Y883423I-1225J-426D01*
G02X475232I-1297J0D01*
G02X476287Y884698I1298J0D01*
G01X476377Y884715D01*
X477184Y886112D01*
X477153Y886199D01*
G02X477080Y886627I1225J429D01*
G37*
G36*
G01X484480D02*
G02X487076I1298J0D01*
G02X486020Y885352I-1298J0D01*
G01X485930Y885335D01*
X485123Y883938D01*
X485154Y883851D01*
G02X485226Y883423I-1225J-426D01*
G02X482632I-1297J0D01*
G02X483687Y884698I1298J0D01*
G01X483777Y884715D01*
X484584Y886112D01*
X484553Y886199D01*
G02X484480Y886627I1225J429D01*
G37*
G36*
G01X491880D02*
G02X494476I1298J0D01*
G02X493420Y885352I-1298J0D01*
G01X493330Y885335D01*
X492523Y883938D01*
X492554Y883851D01*
G02X492626Y883423I-1225J-426D01*
G02X490032I-1297J0D01*
G02X491087Y884698I1298J0D01*
G01X491177Y884715D01*
X491984Y886112D01*
X491953Y886199D01*
G02X491880Y886627I1225J429D01*
G37*
G36*
G01X499280D02*
G02X501876I1298J0D01*
G02X500820Y885352I-1298J0D01*
G01X500730Y885335D01*
X499923Y883938D01*
X499954Y883851D01*
G02X500026Y883423I-1225J-426D01*
G02X497432I-1297J0D01*
G02X498487Y884698I1298J0D01*
G01X498577Y884715D01*
X499384Y886112D01*
X499353Y886199D01*
G02X499280Y886627I1225J429D01*
G37*
G36*
G01X506680D02*
G02X509276I1298J0D01*
G02X508220Y885352I-1298J0D01*
G01X508130Y885335D01*
X507323Y883938D01*
X507354Y883851D01*
G02X507426Y883423I-1225J-426D01*
G02X504832I-1297J0D01*
G02X505887Y884698I1298J0D01*
G01X505977Y884715D01*
X506784Y886112D01*
X506753Y886199D01*
G02X506680Y886627I1225J429D01*
G37*
G36*
G01X514080D02*
G02X516676I1298J0D01*
G02X515620Y885352I-1298J0D01*
G01X515530Y885335D01*
X514723Y883938D01*
X514754Y883851D01*
G02X514826Y883423I-1225J-426D01*
G02X512232I-1297J0D01*
G02X513287Y884698I1298J0D01*
G01X513377Y884715D01*
X514184Y886112D01*
X514153Y886199D01*
G02X514080Y886627I1225J429D01*
G37*
G36*
G01X521480D02*
G02X524076I1298J0D01*
G02X523020Y885352I-1298J0D01*
G01X522930Y885335D01*
X522123Y883938D01*
X522154Y883851D01*
G02X522226Y883423I-1225J-426D01*
G02X519632I-1297J0D01*
G02X520687Y884698I1298J0D01*
G01X520777Y884715D01*
X521584Y886112D01*
X521553Y886199D01*
G02X521480Y886627I1225J429D01*
G37*
G36*
G01X1349622D02*
G02X1352218I1298J0D01*
G02X1351162Y885352I-1298J0D01*
G01X1351072Y885335D01*
X1350265Y883938D01*
X1350296Y883851D01*
G02X1350368Y883423I-1225J-426D01*
G02X1347774I-1297J0D01*
G02X1348829Y884698I1298J0D01*
G01X1348919Y884715D01*
X1349726Y886112D01*
X1349695Y886199D01*
G02X1349622Y886627I1225J429D01*
G37*
G36*
G01X1357022D02*
G02X1359618I1298J0D01*
G02X1358562Y885352I-1298J0D01*
G01X1358472Y885335D01*
X1357665Y883938D01*
X1357696Y883851D01*
G02X1357768Y883423I-1225J-426D01*
G02X1355174I-1297J0D01*
G02X1356229Y884698I1298J0D01*
G01X1356319Y884715D01*
X1357126Y886112D01*
X1357095Y886199D01*
G02X1357022Y886627I1225J429D01*
G37*
G36*
G01X1364422D02*
G02X1367018I1298J0D01*
G02X1365962Y885352I-1298J0D01*
G01X1365872Y885335D01*
X1365065Y883938D01*
X1365096Y883851D01*
G02X1365168Y883423I-1225J-426D01*
G02X1362574I-1297J0D01*
G02X1363629Y884698I1298J0D01*
G01X1363719Y884715D01*
X1364526Y886112D01*
X1364495Y886199D01*
G02X1364422Y886627I1225J429D01*
G37*
G36*
G01X1371822D02*
G02X1374418I1298J0D01*
G02X1373362Y885352I-1298J0D01*
G01X1373272Y885335D01*
X1372465Y883938D01*
X1372496Y883851D01*
G02X1372568Y883423I-1225J-426D01*
G02X1369974I-1297J0D01*
G02X1371029Y884698I1298J0D01*
G01X1371119Y884715D01*
X1371926Y886112D01*
X1371895Y886199D01*
G02X1371822Y886627I1225J429D01*
G37*
G36*
G01X1379222D02*
G02X1381818I1298J0D01*
G02X1380762Y885352I-1298J0D01*
G01X1380672Y885335D01*
X1379865Y883938D01*
X1379896Y883851D01*
G02X1379968Y883423I-1225J-426D01*
G02X1377374I-1297J0D01*
G02X1378429Y884698I1298J0D01*
G01X1378519Y884715D01*
X1379326Y886112D01*
X1379295Y886199D01*
G02X1379222Y886627I1225J429D01*
G37*
G36*
G01X1386622D02*
G02X1389218I1298J0D01*
G02X1388162Y885352I-1298J0D01*
G01X1388072Y885335D01*
X1387265Y883938D01*
X1387296Y883851D01*
G02X1387368Y883423I-1225J-426D01*
G02X1384774I-1297J0D01*
G02X1385829Y884698I1298J0D01*
G01X1385919Y884715D01*
X1386726Y886112D01*
X1386695Y886199D01*
G02X1386622Y886627I1225J429D01*
G37*
G36*
G01X1394022D02*
G02X1396618I1298J0D01*
G02X1395562Y885352I-1298J0D01*
G01X1395472Y885335D01*
X1394665Y883938D01*
X1394696Y883851D01*
G02X1394768Y883423I-1225J-426D01*
G02X1392174I-1297J0D01*
G02X1393229Y884698I1298J0D01*
G01X1393319Y884715D01*
X1394126Y886112D01*
X1394095Y886199D01*
G02X1394022Y886627I1225J429D01*
G37*
G36*
G01X1401422D02*
G02X1404018I1298J0D01*
G02X1402962Y885352I-1298J0D01*
G01X1402872Y885335D01*
X1402065Y883938D01*
X1402096Y883851D01*
G02X1402168Y883423I-1225J-426D01*
G02X1399574I-1297J0D01*
G02X1400629Y884698I1298J0D01*
G01X1400719Y884715D01*
X1401526Y886112D01*
X1401495Y886199D01*
G02X1401422Y886627I1225J429D01*
G37*
G36*
G01X1408822D02*
G02X1411418I1298J0D01*
G02X1410362Y885352I-1298J0D01*
G01X1410272Y885335D01*
X1409465Y883938D01*
X1409496Y883851D01*
G02X1409568Y883423I-1225J-426D01*
G02X1406974I-1297J0D01*
G02X1408029Y884698I1298J0D01*
G01X1408119Y884715D01*
X1408926Y886112D01*
X1408895Y886199D01*
G02X1408822Y886627I1225J429D01*
G37*
G36*
G01X1416222D02*
G02X1418818I1298J0D01*
G02X1417762Y885352I-1298J0D01*
G01X1417672Y885335D01*
X1416865Y883938D01*
X1416896Y883851D01*
G02X1416968Y883423I-1225J-426D01*
G02X1414374I-1297J0D01*
G02X1415429Y884698I1298J0D01*
G01X1415519Y884715D01*
X1416326Y886112D01*
X1416295Y886199D01*
G02X1416222Y886627I1225J429D01*
G37*
G36*
G01X1423622D02*
G02X1426218I1298J0D01*
G02X1425162Y885352I-1298J0D01*
G01X1425072Y885335D01*
X1424265Y883938D01*
X1424296Y883851D01*
G02X1424368Y883423I-1225J-426D01*
G02X1421774I-1297J0D01*
G02X1422829Y884698I1298J0D01*
G01X1422919Y884715D01*
X1423726Y886112D01*
X1423695Y886199D01*
G02X1423622Y886627I1225J429D01*
G37*
G36*
G01X1431022D02*
G02X1433618I1298J0D01*
G02X1432562Y885352I-1298J0D01*
G01X1432472Y885335D01*
X1431665Y883938D01*
X1431696Y883851D01*
G02X1431768Y883423I-1225J-426D01*
G02X1429174I-1297J0D01*
G02X1430229Y884698I1298J0D01*
G01X1430319Y884715D01*
X1431126Y886112D01*
X1431095Y886199D01*
G02X1431022Y886627I1225J429D01*
G37*
G36*
G01X1438422D02*
G02X1441018I1298J0D01*
G02X1439962Y885352I-1298J0D01*
G01X1439872Y885335D01*
X1439065Y883938D01*
X1439096Y883851D01*
G02X1439168Y883423I-1225J-426D01*
G02X1436574I-1297J0D01*
G02X1437629Y884698I1298J0D01*
G01X1437719Y884715D01*
X1438526Y886112D01*
X1438495Y886199D01*
G02X1438422Y886627I1225J429D01*
G37*
G36*
G01X1445822D02*
G02X1448418I1298J0D01*
G02X1447362Y885352I-1298J0D01*
G01X1447272Y885335D01*
X1446465Y883938D01*
X1446496Y883851D01*
G02X1446568Y883423I-1225J-426D01*
G02X1443974I-1297J0D01*
G02X1445029Y884698I1298J0D01*
G01X1445119Y884715D01*
X1445926Y886112D01*
X1445895Y886199D01*
G02X1445822Y886627I1225J429D01*
G37*
G36*
G01X1453222D02*
G02X1455818I1298J0D01*
G02X1454762Y885352I-1298J0D01*
G01X1454672Y885335D01*
X1453865Y883938D01*
X1453896Y883851D01*
G02X1453968Y883423I-1225J-426D01*
G02X1451374I-1297J0D01*
G02X1452429Y884698I1298J0D01*
G01X1452519Y884715D01*
X1453326Y886112D01*
X1453295Y886199D01*
G02X1453222Y886627I1225J429D01*
G37*
G36*
G01X1460622D02*
G02X1463218I1298J0D01*
G02X1462162Y885352I-1298J0D01*
G01X1462072Y885335D01*
X1461265Y883938D01*
X1461296Y883851D01*
G02X1461368Y883423I-1225J-426D01*
G02X1458774I-1297J0D01*
G02X1459829Y884698I1298J0D01*
G01X1459919Y884715D01*
X1460726Y886112D01*
X1460695Y886199D01*
G02X1460622Y886627I1225J429D01*
G37*
G36*
G01X1468022D02*
G02X1470618I1298J0D01*
G02X1469562Y885352I-1298J0D01*
G01X1469472Y885335D01*
X1468665Y883938D01*
X1468696Y883851D01*
G02X1468768Y883423I-1225J-426D01*
G02X1466174I-1297J0D01*
G02X1467229Y884698I1298J0D01*
G01X1467319Y884715D01*
X1468126Y886112D01*
X1468095Y886199D01*
G02X1468022Y886627I1225J429D01*
G37*
G36*
G01X1475422D02*
G02X1478018I1298J0D01*
G02X1476962Y885352I-1298J0D01*
G01X1476872Y885335D01*
X1476065Y883938D01*
X1476096Y883851D01*
G02X1476168Y883423I-1225J-426D01*
G02X1473574I-1297J0D01*
G02X1474629Y884698I1298J0D01*
G01X1474719Y884715D01*
X1475526Y886112D01*
X1475495Y886199D01*
G02X1475422Y886627I1225J429D01*
G37*
G36*
G01X1482822D02*
G02X1485418I1298J0D01*
G02X1484362Y885352I-1298J0D01*
G01X1484272Y885335D01*
X1483465Y883938D01*
X1483496Y883851D01*
G02X1483568Y883423I-1225J-426D01*
G02X1480974I-1297J0D01*
G02X1482029Y884698I1298J0D01*
G01X1482119Y884715D01*
X1482926Y886112D01*
X1482895Y886199D01*
G02X1482822Y886627I1225J429D01*
G37*
G36*
G01X1490222D02*
G02X1492818I1298J0D01*
G02X1491762Y885352I-1298J0D01*
G01X1491672Y885335D01*
X1490865Y883938D01*
X1490896Y883851D01*
G02X1490968Y883423I-1225J-426D01*
G02X1488374I-1297J0D01*
G02X1489429Y884698I1298J0D01*
G01X1489519Y884715D01*
X1490326Y886112D01*
X1490295Y886199D01*
G02X1490222Y886627I1225J429D01*
G37*
G36*
G01X1497622D02*
G02X1500218I1298J0D01*
G02X1499162Y885352I-1298J0D01*
G01X1499072Y885335D01*
X1498265Y883938D01*
X1498296Y883851D01*
G02X1498368Y883423I-1225J-426D01*
G02X1495774I-1297J0D01*
G02X1496829Y884698I1298J0D01*
G01X1496919Y884715D01*
X1497726Y886112D01*
X1497695Y886199D01*
G02X1497622Y886627I1225J429D01*
G37*
G36*
G01X355414Y1124651D02*
G02X358010I1298J0D01*
G02X357937Y1124223I-1298J1D01*
G01X357906Y1124136D01*
X358713Y1122739D01*
X358803Y1122722D01*
G02X359858Y1121447I-243J-1275D01*
G02X357264I-1297J0D01*
G02X357336Y1121876I1297J3D01*
G01X357367Y1121962D01*
X356560Y1123359D01*
X356470Y1123376D01*
G02X355414Y1124651I242J1275D01*
G37*
G36*
G01X362814D02*
G02X365408I1297J0D01*
G02X365336Y1124223I-1297J-2D01*
G01X365305Y1124136D01*
X366112Y1122739D01*
X366202Y1122722D01*
G02X367260Y1121447I-239J-1275D01*
G02X364664I-1298J0D01*
G02X364737Y1121874I1298J-2D01*
G01X364767Y1121960D01*
X363959Y1123359D01*
X363869Y1123376D01*
G02X362814Y1124651I243J1275D01*
G37*
G36*
G01X370214D02*
G02X372808I1297J0D01*
G02X372736Y1124223I-1297J-2D01*
G01X372705Y1124136D01*
X373512Y1122739D01*
X373602Y1122722D01*
G02X374660Y1121447I-239J-1275D01*
G02X372064I-1298J0D01*
G02X372137Y1121874I1298J-2D01*
G01X372167Y1121960D01*
X371359Y1123359D01*
X371269Y1123376D01*
G02X370214Y1124651I243J1275D01*
G37*
G36*
G01X377614D02*
G02X380208I1297J0D01*
G02X380136Y1124223I-1297J-2D01*
G01X380105Y1124136D01*
X380912Y1122739D01*
X381002Y1122722D01*
G02X382060Y1121447I-239J-1275D01*
G02X379464I-1298J0D01*
G02X379537Y1121874I1298J-2D01*
G01X379567Y1121960D01*
X378759Y1123359D01*
X378669Y1123376D01*
G02X377614Y1124651I243J1275D01*
G37*
G36*
G01X385014D02*
G02X387608I1297J0D01*
G02X387536Y1124223I-1297J-2D01*
G01X387505Y1124136D01*
X388312Y1122739D01*
X388402Y1122722D01*
G02X389460Y1121447I-239J-1275D01*
G02X386864I-1298J0D01*
G02X386937Y1121874I1298J-2D01*
G01X386967Y1121960D01*
X386159Y1123359D01*
X386069Y1123376D01*
G02X385014Y1124651I243J1275D01*
G37*
G36*
G01X392414D02*
G02X395008I1297J0D01*
G02X394936Y1124223I-1297J-2D01*
G01X394905Y1124136D01*
X395712Y1122739D01*
X395802Y1122722D01*
G02X396860Y1121447I-239J-1275D01*
G02X394264I-1298J0D01*
G02X394337Y1121874I1298J-2D01*
G01X394367Y1121960D01*
X393559Y1123359D01*
X393469Y1123376D01*
G02X392414Y1124651I243J1275D01*
G37*
G36*
G01X399814D02*
G02X402408I1297J0D01*
G02X402336Y1124223I-1297J-2D01*
G01X402305Y1124136D01*
X403112Y1122739D01*
X403202Y1122722D01*
G02X404260Y1121447I-239J-1275D01*
G02X401664I-1298J0D01*
G02X401737Y1121874I1298J-2D01*
G01X401767Y1121960D01*
X400959Y1123359D01*
X400869Y1123376D01*
G02X399814Y1124651I243J1275D01*
G37*
G36*
G01X407214D02*
G02X409808I1297J0D01*
G02X409736Y1124223I-1297J-2D01*
G01X409705Y1124136D01*
X410512Y1122739D01*
X410602Y1122722D01*
G02X411660Y1121447I-239J-1275D01*
G02X409064I-1298J0D01*
G02X409137Y1121874I1298J-2D01*
G01X409167Y1121960D01*
X408359Y1123359D01*
X408269Y1123376D01*
G02X407214Y1124651I243J1275D01*
G37*
G36*
G01X470114D02*
G02X472708I1297J0D01*
G02X471653Y1123376I-1298J0D01*
G01X471563Y1123359D01*
X470756Y1121962D01*
X470787Y1121875D01*
G02X470860Y1121447I-1225J-429D01*
G02X468264I-1298J0D01*
G02X469320Y1122722I1298J0D01*
G01X469410Y1122739D01*
X470217Y1124136D01*
X470186Y1124223D01*
G02X470114Y1124651I1225J426D01*
G37*
G36*
G01X477514D02*
G02X480108I1297J0D01*
G02X479053Y1123376I-1298J0D01*
G01X478963Y1123359D01*
X478156Y1121962D01*
X478187Y1121875D01*
G02X478260Y1121447I-1225J-429D01*
G02X475664I-1298J0D01*
G02X476720Y1122722I1298J0D01*
G01X476810Y1122739D01*
X477617Y1124136D01*
X477586Y1124223D01*
G02X477514Y1124651I1225J426D01*
G37*
G36*
G01X484914D02*
G02X487508I1297J0D01*
G02X486453Y1123376I-1298J0D01*
G01X486363Y1123359D01*
X485556Y1121962D01*
X485587Y1121875D01*
G02X485660Y1121447I-1225J-429D01*
G02X483064I-1298J0D01*
G02X484120Y1122722I1298J0D01*
G01X484210Y1122739D01*
X485017Y1124136D01*
X484986Y1124223D01*
G02X484914Y1124651I1225J426D01*
G37*
G36*
G01X492314D02*
G02X494908I1297J0D01*
G02X493853Y1123376I-1298J0D01*
G01X493763Y1123359D01*
X492956Y1121962D01*
X492987Y1121875D01*
G02X493060Y1121447I-1225J-429D01*
G02X490464I-1298J0D01*
G02X491520Y1122722I1298J0D01*
G01X491610Y1122739D01*
X492417Y1124136D01*
X492386Y1124223D01*
G02X492314Y1124651I1225J426D01*
G37*
G36*
G01X499714D02*
G02X502308I1297J0D01*
G02X501253Y1123376I-1298J0D01*
G01X501163Y1123359D01*
X500356Y1121962D01*
X500387Y1121875D01*
G02X500460Y1121447I-1225J-429D01*
G02X497864I-1298J0D01*
G02X498920Y1122722I1298J0D01*
G01X499010Y1122739D01*
X499817Y1124136D01*
X499786Y1124223D01*
G02X499714Y1124651I1225J426D01*
G37*
G36*
G01X507114D02*
G02X509708I1297J0D01*
G02X508653Y1123376I-1298J0D01*
G01X508563Y1123359D01*
X507756Y1121962D01*
X507787Y1121875D01*
G02X507860Y1121447I-1225J-429D01*
G02X505264I-1298J0D01*
G02X506320Y1122722I1298J0D01*
G01X506410Y1122739D01*
X507217Y1124136D01*
X507186Y1124223D01*
G02X507114Y1124651I1225J426D01*
G37*
G36*
G01X514514D02*
G02X517108I1297J0D01*
G02X516053Y1123376I-1298J0D01*
G01X515963Y1123359D01*
X515156Y1121962D01*
X515187Y1121875D01*
G02X515260Y1121447I-1225J-429D01*
G02X512664I-1298J0D01*
G02X513720Y1122722I1298J0D01*
G01X513810Y1122739D01*
X514617Y1124136D01*
X514586Y1124223D01*
G02X514514Y1124651I1225J426D01*
G37*
G36*
G01X521914D02*
G02X524508I1297J0D01*
G02X523453Y1123376I-1298J0D01*
G01X523363Y1123359D01*
X522556Y1121962D01*
X522587Y1121875D01*
G02X522660Y1121447I-1225J-429D01*
G02X520064I-1298J0D01*
G02X521120Y1122722I1298J0D01*
G01X521210Y1122739D01*
X522017Y1124136D01*
X521986Y1124223D01*
G02X521914Y1124651I1225J426D01*
G37*
G36*
G01X1331556D02*
G02X1334152I1298J0D01*
G02X1334079Y1124223I-1298J1D01*
G01X1334048Y1124136D01*
X1334855Y1122739D01*
X1334945Y1122722D01*
G02X1336000Y1121447I-243J-1275D01*
G02X1333406I-1297J0D01*
G02X1333478Y1121876I1297J3D01*
G01X1333509Y1121962D01*
X1332702Y1123359D01*
X1332612Y1123376D01*
G02X1331556Y1124651I242J1275D01*
G37*
G36*
G01X1338956D02*
G02X1341550I1297J0D01*
G02X1341478Y1124223I-1297J-2D01*
G01X1341447Y1124136D01*
X1342254Y1122739D01*
X1342344Y1122722D01*
G02X1343402Y1121447I-239J-1275D01*
G02X1340806I-1298J0D01*
G02X1340879Y1121874I1298J-2D01*
G01X1340909Y1121960D01*
X1340101Y1123359D01*
X1340011Y1123376D01*
G02X1338956Y1124651I243J1275D01*
G37*
G36*
G01X1346356D02*
G02X1348950I1297J0D01*
G02X1348878Y1124223I-1297J-2D01*
G01X1348847Y1124136D01*
X1349654Y1122739D01*
X1349744Y1122722D01*
G02X1350802Y1121447I-239J-1275D01*
G02X1348206I-1298J0D01*
G02X1348279Y1121874I1298J-2D01*
G01X1348309Y1121960D01*
X1347501Y1123359D01*
X1347411Y1123376D01*
G02X1346356Y1124651I243J1275D01*
G37*
G36*
G01X1353756D02*
G02X1356350I1297J0D01*
G02X1356278Y1124223I-1297J-2D01*
G01X1356247Y1124136D01*
X1357054Y1122739D01*
X1357144Y1122722D01*
G02X1358202Y1121447I-239J-1275D01*
G02X1355606I-1298J0D01*
G02X1355679Y1121874I1298J-2D01*
G01X1355709Y1121960D01*
X1354901Y1123359D01*
X1354811Y1123376D01*
G02X1353756Y1124651I243J1275D01*
G37*
G36*
G01X1361156D02*
G02X1363750I1297J0D01*
G02X1363678Y1124223I-1297J-2D01*
G01X1363647Y1124136D01*
X1364454Y1122739D01*
X1364544Y1122722D01*
G02X1365602Y1121447I-239J-1275D01*
G02X1363006I-1298J0D01*
G02X1363079Y1121874I1298J-2D01*
G01X1363109Y1121960D01*
X1362301Y1123359D01*
X1362211Y1123376D01*
G02X1361156Y1124651I243J1275D01*
G37*
G36*
G01X1368556D02*
G02X1371150I1297J0D01*
G02X1371078Y1124223I-1297J-2D01*
G01X1371047Y1124136D01*
X1371854Y1122739D01*
X1371944Y1122722D01*
G02X1373002Y1121447I-239J-1275D01*
G02X1370406I-1298J0D01*
G02X1370479Y1121874I1298J-2D01*
G01X1370509Y1121960D01*
X1369701Y1123359D01*
X1369611Y1123376D01*
G02X1368556Y1124651I243J1275D01*
G37*
G36*
G01X1375956D02*
G02X1378550I1297J0D01*
G02X1378478Y1124223I-1297J-2D01*
G01X1378447Y1124136D01*
X1379254Y1122739D01*
X1379344Y1122722D01*
G02X1380402Y1121447I-239J-1275D01*
G02X1377806I-1298J0D01*
G02X1377879Y1121874I1298J-2D01*
G01X1377909Y1121960D01*
X1377101Y1123359D01*
X1377011Y1123376D01*
G02X1375956Y1124651I243J1275D01*
G37*
G36*
G01X1383356D02*
G02X1385950I1297J0D01*
G02X1385878Y1124223I-1297J-2D01*
G01X1385847Y1124136D01*
X1386654Y1122739D01*
X1386744Y1122722D01*
G02X1387802Y1121447I-239J-1275D01*
G02X1385206I-1298J0D01*
G02X1385279Y1121874I1298J-2D01*
G01X1385309Y1121960D01*
X1384501Y1123359D01*
X1384411Y1123376D01*
G02X1383356Y1124651I243J1275D01*
G37*
G36*
G01X1446256D02*
G02X1448850I1297J0D01*
G02X1447795Y1123376I-1298J0D01*
G01X1447705Y1123359D01*
X1446898Y1121962D01*
X1446929Y1121875D01*
G02X1447002Y1121447I-1225J-429D01*
G02X1444406I-1298J0D01*
G02X1445462Y1122722I1298J0D01*
G01X1445552Y1122739D01*
X1446359Y1124136D01*
X1446328Y1124223D01*
G02X1446256Y1124651I1225J426D01*
G37*
G36*
G01X1453656D02*
G02X1456250I1297J0D01*
G02X1455195Y1123376I-1298J0D01*
G01X1455105Y1123359D01*
X1454298Y1121962D01*
X1454329Y1121875D01*
G02X1454402Y1121447I-1225J-429D01*
G02X1451806I-1298J0D01*
G02X1452862Y1122722I1298J0D01*
G01X1452952Y1122739D01*
X1453759Y1124136D01*
X1453728Y1124223D01*
G02X1453656Y1124651I1225J426D01*
G37*
G36*
G01X1461056D02*
G02X1463650I1297J0D01*
G02X1462595Y1123376I-1298J0D01*
G01X1462505Y1123359D01*
X1461698Y1121962D01*
X1461729Y1121875D01*
G02X1461802Y1121447I-1225J-429D01*
G02X1459206I-1298J0D01*
G02X1460262Y1122722I1298J0D01*
G01X1460352Y1122739D01*
X1461159Y1124136D01*
X1461128Y1124223D01*
G02X1461056Y1124651I1225J426D01*
G37*
G36*
G01X1468456D02*
G02X1471050I1297J0D01*
G02X1469995Y1123376I-1298J0D01*
G01X1469905Y1123359D01*
X1469098Y1121962D01*
X1469129Y1121875D01*
G02X1469202Y1121447I-1225J-429D01*
G02X1466606I-1298J0D01*
G02X1467662Y1122722I1298J0D01*
G01X1467752Y1122739D01*
X1468559Y1124136D01*
X1468528Y1124223D01*
G02X1468456Y1124651I1225J426D01*
G37*
G36*
G01X1475856D02*
G02X1478450I1297J0D01*
G02X1477395Y1123376I-1298J0D01*
G01X1477305Y1123359D01*
X1476498Y1121962D01*
X1476529Y1121875D01*
G02X1476602Y1121447I-1225J-429D01*
G02X1474006I-1298J0D01*
G02X1475062Y1122722I1298J0D01*
G01X1475152Y1122739D01*
X1475959Y1124136D01*
X1475928Y1124223D01*
G02X1475856Y1124651I1225J426D01*
G37*
G36*
G01X1483256D02*
G02X1485850I1297J0D01*
G02X1484795Y1123376I-1298J0D01*
G01X1484705Y1123359D01*
X1483898Y1121962D01*
X1483929Y1121875D01*
G02X1484002Y1121447I-1225J-429D01*
G02X1481406I-1298J0D01*
G02X1482462Y1122722I1298J0D01*
G01X1482552Y1122739D01*
X1483359Y1124136D01*
X1483328Y1124223D01*
G02X1483256Y1124651I1225J426D01*
G37*
G36*
G01X1490656D02*
G02X1493250I1297J0D01*
G02X1492195Y1123376I-1298J0D01*
G01X1492105Y1123359D01*
X1491298Y1121962D01*
X1491329Y1121875D01*
G02X1491402Y1121447I-1225J-429D01*
G02X1488806I-1298J0D01*
G02X1489862Y1122722I1298J0D01*
G01X1489952Y1122739D01*
X1490759Y1124136D01*
X1490728Y1124223D01*
G02X1490656Y1124651I1225J426D01*
G37*
G36*
G01X1498056D02*
G02X1500650I1297J0D01*
G02X1499595Y1123376I-1298J0D01*
G01X1499505Y1123359D01*
X1498698Y1121962D01*
X1498729Y1121875D01*
G02X1498802Y1121447I-1225J-429D01*
G02X1496206I-1298J0D01*
G02X1497262Y1122722I1298J0D01*
G01X1497352Y1122739D01*
X1498159Y1124136D01*
X1498128Y1124223D01*
G02X1498056Y1124651I1225J426D01*
G37*
G36*
G01X353564Y1127856D02*
G02X356158I1297J0D01*
G02X355103Y1126581I-1298J0D01*
G01X355013Y1126564D01*
X354205Y1125166D01*
X354236Y1125079D01*
G02X354308Y1124651I-1225J-426D01*
G02X351714I-1297J0D01*
G02X352769Y1125926I1298J0D01*
G01X352859Y1125943D01*
X353667Y1127341D01*
X353636Y1127428D01*
G02X353564Y1127856I1225J426D01*
G37*
G36*
G01X360964D02*
G02X363560I1298J0D01*
G02X362504Y1126581I-1298J0D01*
G01X362414Y1126564D01*
X361606Y1125166D01*
X361637Y1125079D01*
G02X361710Y1124651I-1225J-429D01*
G02X359114I-1298J0D01*
G02X360170Y1125926I1298J0D01*
G01X360260Y1125943D01*
X361068Y1127341D01*
X361037Y1127428D01*
G02X360964Y1127856I1225J429D01*
G37*
G36*
G01X368364D02*
G02X370960I1298J0D01*
G02X369904Y1126581I-1298J0D01*
G01X369814Y1126564D01*
X369006Y1125165D01*
X369036Y1125078D01*
G02X369108Y1124653I-1225J-426D01*
G01Y1124651D01*
G02X366514I-1297J0D01*
G02X367570Y1125926I1298J0D01*
G01X367661Y1125943D01*
X368468Y1127341D01*
X368437Y1127428D01*
G02X368364Y1127856I1225J429D01*
G37*
G36*
G01X375764D02*
G02X378360I1298J0D01*
G02X377304Y1126581I-1298J0D01*
G01X377214Y1126564D01*
X376406Y1125165D01*
X376436Y1125078D01*
G02X376508Y1124653I-1225J-426D01*
G01Y1124651D01*
G02X373914I-1297J0D01*
G02X374970Y1125926I1298J0D01*
G01X375061Y1125943D01*
X375868Y1127341D01*
X375837Y1127428D01*
G02X375764Y1127856I1225J429D01*
G37*
G36*
G01X383164D02*
G02X385760I1298J0D01*
G02X384704Y1126581I-1298J0D01*
G01X384614Y1126564D01*
X383806Y1125165D01*
X383836Y1125078D01*
G02X383908Y1124653I-1225J-426D01*
G01Y1124651D01*
G02X381314I-1297J0D01*
G02X382370Y1125926I1298J0D01*
G01X382461Y1125943D01*
X383268Y1127341D01*
X383237Y1127428D01*
G02X383164Y1127856I1225J429D01*
G37*
G36*
G01X390564D02*
G02X393160I1298J0D01*
G02X392104Y1126581I-1298J0D01*
G01X392014Y1126564D01*
X391206Y1125165D01*
X391236Y1125078D01*
G02X391308Y1124653I-1225J-426D01*
G01Y1124651D01*
G02X388714I-1297J0D01*
G02X389770Y1125926I1298J0D01*
G01X389861Y1125943D01*
X390668Y1127341D01*
X390637Y1127428D01*
G02X390564Y1127856I1225J429D01*
G37*
G36*
G01X397964D02*
G02X400560I1298J0D01*
G02X399504Y1126581I-1298J0D01*
G01X399414Y1126564D01*
X398606Y1125165D01*
X398636Y1125078D01*
G02X398708Y1124653I-1225J-426D01*
G01Y1124651D01*
G02X396114I-1297J0D01*
G02X397170Y1125926I1298J0D01*
G01X397261Y1125943D01*
X398068Y1127341D01*
X398037Y1127428D01*
G02X397964Y1127856I1225J429D01*
G37*
G36*
G01X405364D02*
G02X407960I1298J0D01*
G02X406904Y1126581I-1298J0D01*
G01X406814Y1126564D01*
X406006Y1125165D01*
X406036Y1125078D01*
G02X406108Y1124653I-1225J-426D01*
G01Y1124651D01*
G02X403514I-1297J0D01*
G02X404570Y1125926I1298J0D01*
G01X404661Y1125943D01*
X405468Y1127341D01*
X405437Y1127428D01*
G02X405364Y1127856I1225J429D01*
G37*
G36*
G01X471964D02*
G02X474560I1298J0D01*
G02X474487Y1127427I-1297J0D01*
G01X474456Y1127341D01*
X475263Y1125943D01*
X475353Y1125926D01*
G02X476408Y1124651I-243J-1275D01*
G02X473814I-1297J0D01*
G02X473886Y1125080I1297J3D01*
G01X473917Y1125166D01*
X473110Y1126564D01*
X473020Y1126581D01*
G02X471964Y1127856I242J1275D01*
G37*
G36*
G01X479364D02*
G02X481960I1298J0D01*
G02X481887Y1127427I-1297J0D01*
G01X481856Y1127341D01*
X482663Y1125943D01*
X482753Y1125926D01*
G02X483808Y1124651I-243J-1275D01*
G02X481214I-1297J0D01*
G02X481286Y1125080I1297J3D01*
G01X481317Y1125166D01*
X480510Y1126564D01*
X480420Y1126581D01*
G02X479364Y1127856I242J1275D01*
G37*
G36*
G01X486764D02*
G02X489360I1298J0D01*
G02X489287Y1127427I-1297J0D01*
G01X489256Y1127341D01*
X490063Y1125943D01*
X490153Y1125926D01*
G02X491208Y1124651I-243J-1275D01*
G02X488614I-1297J0D01*
G02X488686Y1125080I1297J3D01*
G01X488717Y1125166D01*
X487910Y1126564D01*
X487820Y1126581D01*
G02X486764Y1127856I242J1275D01*
G37*
G36*
G01X494164D02*
G02X496760I1298J0D01*
G02X496687Y1127427I-1297J0D01*
G01X496656Y1127341D01*
X497463Y1125943D01*
X497553Y1125926D01*
G02X498608Y1124651I-243J-1275D01*
G02X496014I-1297J0D01*
G02X496086Y1125080I1297J3D01*
G01X496117Y1125166D01*
X495310Y1126564D01*
X495220Y1126581D01*
G02X494164Y1127856I242J1275D01*
G37*
G36*
G01X501564D02*
G02X504160I1298J0D01*
G02X504087Y1127427I-1297J0D01*
G01X504056Y1127341D01*
X504863Y1125943D01*
X504953Y1125926D01*
G02X506008Y1124651I-243J-1275D01*
G02X503414I-1297J0D01*
G02X503486Y1125080I1297J3D01*
G01X503517Y1125166D01*
X502710Y1126564D01*
X502620Y1126581D01*
G02X501564Y1127856I242J1275D01*
G37*
G36*
G01X508964D02*
G02X511560I1298J0D01*
G02X511487Y1127427I-1297J0D01*
G01X511456Y1127341D01*
X512263Y1125943D01*
X512353Y1125926D01*
G02X513408Y1124651I-243J-1275D01*
G02X510814I-1297J0D01*
G02X510886Y1125080I1297J3D01*
G01X510917Y1125166D01*
X510110Y1126564D01*
X510020Y1126581D01*
G02X508964Y1127856I242J1275D01*
G37*
G36*
G01X516364D02*
G02X518960I1298J0D01*
G02X518887Y1127427I-1297J0D01*
G01X518856Y1127341D01*
X519663Y1125943D01*
X519753Y1125926D01*
G02X520808Y1124651I-243J-1275D01*
G02X518214I-1297J0D01*
G02X518286Y1125080I1297J3D01*
G01X518317Y1125166D01*
X517510Y1126564D01*
X517420Y1126581D01*
G02X516364Y1127856I242J1275D01*
G37*
G36*
G01X523764D02*
G02X526360I1298J0D01*
G02X526287Y1127427I-1297J0D01*
G01X526256Y1127341D01*
X527063Y1125943D01*
X527153Y1125926D01*
G02X528208Y1124651I-243J-1275D01*
G02X525614I-1297J0D01*
G02X525686Y1125080I1297J3D01*
G01X525717Y1125166D01*
X524910Y1126564D01*
X524820Y1126581D01*
G02X523764Y1127856I242J1275D01*
G37*
G36*
G01X1329706D02*
G02X1332300I1297J0D01*
G02X1331245Y1126581I-1298J0D01*
G01X1331155Y1126564D01*
X1330347Y1125166D01*
X1330378Y1125079D01*
G02X1330450Y1124651I-1225J-426D01*
G02X1327856I-1297J0D01*
G02X1328911Y1125926I1298J0D01*
G01X1329001Y1125943D01*
X1329809Y1127341D01*
X1329778Y1127428D01*
G02X1329706Y1127856I1225J426D01*
G37*
G36*
G01X1337106D02*
G02X1339702I1298J0D01*
G02X1338646Y1126581I-1298J0D01*
G01X1338556Y1126564D01*
X1337748Y1125166D01*
X1337779Y1125079D01*
G02X1337852Y1124651I-1225J-429D01*
G02X1335256I-1298J0D01*
G02X1336312Y1125926I1298J0D01*
G01X1336402Y1125943D01*
X1337210Y1127341D01*
X1337179Y1127428D01*
G02X1337106Y1127856I1225J429D01*
G37*
G36*
G01X1344506D02*
G02X1347102I1298J0D01*
G02X1346046Y1126581I-1298J0D01*
G01X1345956Y1126564D01*
X1345148Y1125165D01*
X1345178Y1125078D01*
G02X1345250Y1124653I-1225J-426D01*
G01Y1124651D01*
G02X1342656I-1297J0D01*
G02X1343712Y1125926I1298J0D01*
G01X1343803Y1125943D01*
X1344610Y1127341D01*
X1344579Y1127428D01*
G02X1344506Y1127856I1225J429D01*
G37*
G36*
G01X1351906D02*
G02X1354502I1298J0D01*
G02X1353446Y1126581I-1298J0D01*
G01X1353356Y1126564D01*
X1352548Y1125165D01*
X1352578Y1125078D01*
G02X1352650Y1124653I-1225J-426D01*
G01Y1124651D01*
G02X1350056I-1297J0D01*
G02X1351112Y1125926I1298J0D01*
G01X1351203Y1125943D01*
X1352010Y1127341D01*
X1351979Y1127428D01*
G02X1351906Y1127856I1225J429D01*
G37*
G36*
G01X1359306D02*
G02X1361902I1298J0D01*
G02X1360846Y1126581I-1298J0D01*
G01X1360756Y1126564D01*
X1359948Y1125165D01*
X1359978Y1125078D01*
G02X1360050Y1124653I-1225J-426D01*
G01Y1124651D01*
G02X1357456I-1297J0D01*
G02X1358512Y1125926I1298J0D01*
G01X1358603Y1125943D01*
X1359410Y1127341D01*
X1359379Y1127428D01*
G02X1359306Y1127856I1225J429D01*
G37*
G36*
G01X1366706D02*
G02X1369302I1298J0D01*
G02X1368246Y1126581I-1298J0D01*
G01X1368156Y1126564D01*
X1367348Y1125165D01*
X1367378Y1125078D01*
G02X1367450Y1124653I-1225J-426D01*
G01Y1124651D01*
G02X1364856I-1297J0D01*
G02X1365912Y1125926I1298J0D01*
G01X1366003Y1125943D01*
X1366810Y1127341D01*
X1366779Y1127428D01*
G02X1366706Y1127856I1225J429D01*
G37*
G36*
G01X1374106D02*
G02X1376702I1298J0D01*
G02X1375646Y1126581I-1298J0D01*
G01X1375556Y1126564D01*
X1374748Y1125165D01*
X1374778Y1125078D01*
G02X1374850Y1124653I-1225J-426D01*
G01Y1124651D01*
G02X1372256I-1297J0D01*
G02X1373312Y1125926I1298J0D01*
G01X1373403Y1125943D01*
X1374210Y1127341D01*
X1374179Y1127428D01*
G02X1374106Y1127856I1225J429D01*
G37*
G36*
G01X1381506D02*
G02X1384102I1298J0D01*
G02X1383046Y1126581I-1298J0D01*
G01X1382956Y1126564D01*
X1382148Y1125165D01*
X1382178Y1125078D01*
G02X1382250Y1124653I-1225J-426D01*
G01Y1124651D01*
G02X1379656I-1297J0D01*
G02X1380712Y1125926I1298J0D01*
G01X1380803Y1125943D01*
X1381610Y1127341D01*
X1381579Y1127428D01*
G02X1381506Y1127856I1225J429D01*
G37*
G36*
G01X1448106D02*
G02X1450702I1298J0D01*
G02X1450629Y1127427I-1297J0D01*
G01X1450598Y1127341D01*
X1451405Y1125943D01*
X1451495Y1125926D01*
G02X1452550Y1124651I-243J-1275D01*
G02X1449956I-1297J0D01*
G02X1450028Y1125080I1297J3D01*
G01X1450059Y1125166D01*
X1449252Y1126564D01*
X1449162Y1126581D01*
G02X1448106Y1127856I242J1275D01*
G37*
G36*
G01X1455506D02*
G02X1458102I1298J0D01*
G02X1458029Y1127427I-1297J0D01*
G01X1457998Y1127341D01*
X1458805Y1125943D01*
X1458895Y1125926D01*
G02X1459950Y1124651I-243J-1275D01*
G02X1457356I-1297J0D01*
G02X1457428Y1125080I1297J3D01*
G01X1457459Y1125166D01*
X1456652Y1126564D01*
X1456562Y1126581D01*
G02X1455506Y1127856I242J1275D01*
G37*
G36*
G01X1462906D02*
G02X1465502I1298J0D01*
G02X1465429Y1127427I-1297J0D01*
G01X1465398Y1127341D01*
X1466205Y1125943D01*
X1466295Y1125926D01*
G02X1467350Y1124651I-243J-1275D01*
G02X1464756I-1297J0D01*
G02X1464828Y1125080I1297J3D01*
G01X1464859Y1125166D01*
X1464052Y1126564D01*
X1463962Y1126581D01*
G02X1462906Y1127856I242J1275D01*
G37*
G36*
G01X1470306D02*
G02X1472902I1298J0D01*
G02X1472829Y1127427I-1297J0D01*
G01X1472798Y1127341D01*
X1473605Y1125943D01*
X1473695Y1125926D01*
G02X1474750Y1124651I-243J-1275D01*
G02X1472156I-1297J0D01*
G02X1472228Y1125080I1297J3D01*
G01X1472259Y1125166D01*
X1471452Y1126564D01*
X1471362Y1126581D01*
G02X1470306Y1127856I242J1275D01*
G37*
G36*
G01X1477706D02*
G02X1480302I1298J0D01*
G02X1480229Y1127427I-1297J0D01*
G01X1480198Y1127341D01*
X1481005Y1125943D01*
X1481095Y1125926D01*
G02X1482150Y1124651I-243J-1275D01*
G02X1479556I-1297J0D01*
G02X1479628Y1125080I1297J3D01*
G01X1479659Y1125166D01*
X1478852Y1126564D01*
X1478762Y1126581D01*
G02X1477706Y1127856I242J1275D01*
G37*
G36*
G01X1485106D02*
G02X1487702I1298J0D01*
G02X1487629Y1127427I-1297J0D01*
G01X1487598Y1127341D01*
X1488405Y1125943D01*
X1488495Y1125926D01*
G02X1489550Y1124651I-243J-1275D01*
G02X1486956I-1297J0D01*
G02X1487028Y1125080I1297J3D01*
G01X1487059Y1125166D01*
X1486252Y1126564D01*
X1486162Y1126581D01*
G02X1485106Y1127856I242J1275D01*
G37*
G36*
G01X1492506D02*
G02X1495102I1298J0D01*
G02X1495029Y1127427I-1297J0D01*
G01X1494998Y1127341D01*
X1495805Y1125943D01*
X1495895Y1125926D01*
G02X1496950Y1124651I-243J-1275D01*
G02X1494356I-1297J0D01*
G02X1494428Y1125080I1297J3D01*
G01X1494459Y1125166D01*
X1493652Y1126564D01*
X1493562Y1126581D01*
G02X1492506Y1127856I242J1275D01*
G37*
G36*
G01X1499906D02*
G02X1502502I1298J0D01*
G02X1502429Y1127427I-1297J0D01*
G01X1502398Y1127341D01*
X1503205Y1125943D01*
X1503295Y1125926D01*
G02X1504350Y1124651I-243J-1275D01*
G02X1501756I-1297J0D01*
G02X1501828Y1125080I1297J3D01*
G01X1501859Y1125166D01*
X1501052Y1126564D01*
X1500962Y1126581D01*
G02X1499906Y1127856I242J1275D01*
G37*
G36*
G01X348014Y1137469D02*
G02X350610I1298J0D01*
G02X350537Y1137040I-1297J0D01*
G01X350506Y1136954D01*
X351313Y1135556D01*
X351403Y1135539D01*
G02X352458Y1134264I-243J-1275D01*
G02X349864I-1297J0D01*
G02X349936Y1134693I1297J3D01*
G01X349967Y1134779D01*
X349160Y1136177D01*
X349070Y1136194D01*
G02X348014Y1137469I242J1275D01*
G37*
G36*
G01X355414D02*
G02X358010I1298J0D01*
G02X357937Y1137040I-1297J0D01*
G01X357906Y1136954D01*
X358713Y1135556D01*
X358803Y1135539D01*
G02X359858Y1134264I-243J-1275D01*
G02X357264I-1297J0D01*
G02X357336Y1134693I1297J3D01*
G01X357367Y1134779D01*
X356560Y1136177D01*
X356470Y1136194D01*
G02X355414Y1137469I242J1275D01*
G37*
G36*
G01X362814D02*
G02X365410I1298J0D01*
G02X365337Y1137041I-1298J1D01*
G01X365306Y1136954D01*
X366114Y1135556D01*
X366204Y1135539D01*
G02X367260Y1134264I-242J-1275D01*
G02X364664I-1298J0D01*
G02X364737Y1134692I1298J-1D01*
G01X364768Y1134779D01*
X363960Y1136177D01*
X363870Y1136194D01*
G02X362814Y1137469I242J1275D01*
G37*
G36*
G01X370214D02*
G02X372810I1298J0D01*
G02X372737Y1137041I-1298J1D01*
G01X372706Y1136954D01*
X373514Y1135556D01*
X373604Y1135539D01*
G02X374660Y1134264I-242J-1275D01*
G02X372064I-1298J0D01*
G02X372137Y1134692I1298J-1D01*
G01X372168Y1134779D01*
X371360Y1136177D01*
X371270Y1136194D01*
G02X370214Y1137469I242J1275D01*
G37*
G36*
G01X377614D02*
G02X380210I1298J0D01*
G02X380137Y1137041I-1298J1D01*
G01X380106Y1136954D01*
X380914Y1135556D01*
X381004Y1135539D01*
G02X382060Y1134264I-242J-1275D01*
G02X379464I-1298J0D01*
G02X379537Y1134692I1298J-1D01*
G01X379568Y1134779D01*
X378760Y1136177D01*
X378670Y1136194D01*
G02X377614Y1137469I242J1275D01*
G37*
G36*
G01X385014D02*
G02X387610I1298J0D01*
G02X387537Y1137041I-1298J1D01*
G01X387506Y1136954D01*
X388314Y1135556D01*
X388404Y1135539D01*
G02X389460Y1134264I-242J-1275D01*
G02X386864I-1298J0D01*
G02X386937Y1134692I1298J-1D01*
G01X386968Y1134779D01*
X386160Y1136177D01*
X386070Y1136194D01*
G02X385014Y1137469I242J1275D01*
G37*
G36*
G01X392414D02*
G02X395010I1298J0D01*
G02X394937Y1137041I-1298J1D01*
G01X394906Y1136954D01*
X395714Y1135556D01*
X395804Y1135539D01*
G02X396860Y1134264I-242J-1275D01*
G02X394264I-1298J0D01*
G02X394337Y1134692I1298J-1D01*
G01X394368Y1134779D01*
X393560Y1136177D01*
X393470Y1136194D01*
G02X392414Y1137469I242J1275D01*
G37*
G36*
G01X399814D02*
G02X402410I1298J0D01*
G02X402337Y1137041I-1298J1D01*
G01X402306Y1136954D01*
X403114Y1135556D01*
X403204Y1135539D01*
G02X404260Y1134264I-242J-1275D01*
G02X401664I-1298J0D01*
G02X401737Y1134692I1298J-1D01*
G01X401768Y1134779D01*
X400960Y1136177D01*
X400870Y1136194D01*
G02X399814Y1137469I242J1275D01*
G37*
G36*
G01X407214D02*
G02X409810I1298J0D01*
G02X409737Y1137041I-1298J1D01*
G01X409706Y1136954D01*
X410514Y1135556D01*
X410604Y1135539D01*
G02X411660Y1134264I-242J-1275D01*
G02X409064I-1298J0D01*
G02X409137Y1134692I1298J-1D01*
G01X409168Y1134779D01*
X408360Y1136177D01*
X408270Y1136194D01*
G02X407214Y1137469I242J1275D01*
G37*
G36*
G01X477514D02*
G02X480110I1298J0D01*
G02X479054Y1136194I-1298J0D01*
G01X478964Y1136177D01*
X478156Y1134779D01*
X478187Y1134692D01*
G02X478260Y1134264I-1225J-429D01*
G02X475664I-1298J0D01*
G02X476720Y1135539I1298J0D01*
G01X476810Y1135556D01*
X477618Y1136954D01*
X477587Y1137041D01*
G02X477514Y1137469I1225J429D01*
G37*
G36*
G01X484914D02*
G02X487510I1298J0D01*
G02X486454Y1136194I-1298J0D01*
G01X486364Y1136177D01*
X485557Y1134779D01*
X485587Y1134692D01*
G02X485660Y1134264I-1225J-429D01*
G02X483064I-1298J0D01*
G02X484121Y1135539I1297J0D01*
G01X484211Y1135556D01*
X485018Y1136954D01*
X484987Y1137041D01*
G02X484914Y1137469I1225J429D01*
G37*
G36*
G01X492314D02*
G02X494910I1298J0D01*
G02X493854Y1136194I-1298J0D01*
G01X493764Y1136177D01*
X492957Y1134779D01*
X492987Y1134692D01*
G02X493060Y1134264I-1225J-429D01*
G02X490464I-1298J0D01*
G02X491521Y1135539I1297J0D01*
G01X491611Y1135556D01*
X492418Y1136954D01*
X492387Y1137041D01*
G02X492314Y1137469I1225J429D01*
G37*
G36*
G01X499714D02*
G02X502310I1298J0D01*
G02X501254Y1136194I-1298J0D01*
G01X501164Y1136177D01*
X500357Y1134779D01*
X500387Y1134692D01*
G02X500460Y1134264I-1225J-429D01*
G02X497864I-1298J0D01*
G02X498921Y1135539I1297J0D01*
G01X499011Y1135556D01*
X499818Y1136954D01*
X499787Y1137041D01*
G02X499714Y1137469I1225J429D01*
G37*
G36*
G01X507114D02*
G02X509710I1298J0D01*
G02X508654Y1136194I-1298J0D01*
G01X508564Y1136177D01*
X507757Y1134779D01*
X507787Y1134692D01*
G02X507860Y1134264I-1225J-429D01*
G02X505264I-1298J0D01*
G02X506321Y1135539I1297J0D01*
G01X506411Y1135556D01*
X507218Y1136954D01*
X507187Y1137041D01*
G02X507114Y1137469I1225J429D01*
G37*
G36*
G01X514514D02*
G02X517110I1298J0D01*
G02X516054Y1136194I-1298J0D01*
G01X515964Y1136177D01*
X515157Y1134779D01*
X515187Y1134692D01*
G02X515260Y1134264I-1225J-429D01*
G02X512664I-1298J0D01*
G02X513721Y1135539I1297J0D01*
G01X513811Y1135556D01*
X514618Y1136954D01*
X514587Y1137041D01*
G02X514514Y1137469I1225J429D01*
G37*
G36*
G01X521914D02*
G02X524510I1298J0D01*
G02X523454Y1136194I-1298J0D01*
G01X523364Y1136177D01*
X522557Y1134779D01*
X522587Y1134692D01*
G02X522660Y1134264I-1225J-429D01*
G02X520064I-1298J0D01*
G02X521121Y1135539I1297J0D01*
G01X521211Y1135556D01*
X522018Y1136954D01*
X521987Y1137041D01*
G02X521914Y1137469I1225J429D01*
G37*
G36*
G01X533014D02*
G02X535610I1298J0D01*
G02X534554Y1136194I-1298J0D01*
G01X534464Y1136177D01*
X533656Y1134779D01*
X533687Y1134692D01*
G02X533760Y1134264I-1225J-429D01*
G02X531164I-1298J0D01*
G02X532220Y1135539I1298J0D01*
G01X532310Y1135556D01*
X533118Y1136954D01*
X533087Y1137041D01*
G02X533014Y1137469I1225J429D01*
G37*
G36*
G01X1324156D02*
G02X1326752I1298J0D01*
G02X1326679Y1137040I-1297J0D01*
G01X1326648Y1136954D01*
X1327455Y1135556D01*
X1327545Y1135539D01*
G02X1328600Y1134264I-243J-1275D01*
G02X1326006I-1297J0D01*
G02X1326078Y1134693I1297J3D01*
G01X1326109Y1134779D01*
X1325302Y1136177D01*
X1325212Y1136194D01*
G02X1324156Y1137469I242J1275D01*
G37*
G36*
G01X1331556D02*
G02X1334152I1298J0D01*
G02X1334079Y1137040I-1297J0D01*
G01X1334048Y1136954D01*
X1334855Y1135556D01*
X1334945Y1135539D01*
G02X1336000Y1134264I-243J-1275D01*
G02X1333406I-1297J0D01*
G02X1333478Y1134693I1297J3D01*
G01X1333509Y1134779D01*
X1332702Y1136177D01*
X1332612Y1136194D01*
G02X1331556Y1137469I242J1275D01*
G37*
G36*
G01X1338956D02*
G02X1341552I1298J0D01*
G02X1341479Y1137041I-1298J1D01*
G01X1341448Y1136954D01*
X1342256Y1135556D01*
X1342346Y1135539D01*
G02X1343402Y1134264I-242J-1275D01*
G02X1340806I-1298J0D01*
G02X1340879Y1134692I1298J-1D01*
G01X1340910Y1134779D01*
X1340102Y1136177D01*
X1340012Y1136194D01*
G02X1338956Y1137469I242J1275D01*
G37*
G36*
G01X1346356D02*
G02X1348952I1298J0D01*
G02X1348879Y1137041I-1298J1D01*
G01X1348848Y1136954D01*
X1349656Y1135556D01*
X1349746Y1135539D01*
G02X1350802Y1134264I-242J-1275D01*
G02X1348206I-1298J0D01*
G02X1348279Y1134692I1298J-1D01*
G01X1348310Y1134779D01*
X1347502Y1136177D01*
X1347412Y1136194D01*
G02X1346356Y1137469I242J1275D01*
G37*
G36*
G01X1353756D02*
G02X1356352I1298J0D01*
G02X1356279Y1137041I-1298J1D01*
G01X1356248Y1136954D01*
X1357056Y1135556D01*
X1357146Y1135539D01*
G02X1358202Y1134264I-242J-1275D01*
G02X1355606I-1298J0D01*
G02X1355679Y1134692I1298J-1D01*
G01X1355710Y1134779D01*
X1354902Y1136177D01*
X1354812Y1136194D01*
G02X1353756Y1137469I242J1275D01*
G37*
G36*
G01X1361156D02*
G02X1363752I1298J0D01*
G02X1363679Y1137041I-1298J1D01*
G01X1363648Y1136954D01*
X1364456Y1135556D01*
X1364546Y1135539D01*
G02X1365602Y1134264I-242J-1275D01*
G02X1363006I-1298J0D01*
G02X1363079Y1134692I1298J-1D01*
G01X1363110Y1134779D01*
X1362302Y1136177D01*
X1362212Y1136194D01*
G02X1361156Y1137469I242J1275D01*
G37*
G36*
G01X1368556D02*
G02X1371152I1298J0D01*
G02X1371079Y1137041I-1298J1D01*
G01X1371048Y1136954D01*
X1371856Y1135556D01*
X1371946Y1135539D01*
G02X1373002Y1134264I-242J-1275D01*
G02X1370406I-1298J0D01*
G02X1370479Y1134692I1298J-1D01*
G01X1370510Y1134779D01*
X1369702Y1136177D01*
X1369612Y1136194D01*
G02X1368556Y1137469I242J1275D01*
G37*
G36*
G01X1375956D02*
G02X1378552I1298J0D01*
G02X1378479Y1137041I-1298J1D01*
G01X1378448Y1136954D01*
X1379256Y1135556D01*
X1379346Y1135539D01*
G02X1380402Y1134264I-242J-1275D01*
G02X1377806I-1298J0D01*
G02X1377879Y1134692I1298J-1D01*
G01X1377910Y1134779D01*
X1377102Y1136177D01*
X1377012Y1136194D01*
G02X1375956Y1137469I242J1275D01*
G37*
G36*
G01X1383356D02*
G02X1385952I1298J0D01*
G02X1385879Y1137041I-1298J1D01*
G01X1385848Y1136954D01*
X1386656Y1135556D01*
X1386746Y1135539D01*
G02X1387802Y1134264I-242J-1275D01*
G02X1385206I-1298J0D01*
G02X1385279Y1134692I1298J-1D01*
G01X1385310Y1134779D01*
X1384502Y1136177D01*
X1384412Y1136194D01*
G02X1383356Y1137469I242J1275D01*
G37*
G36*
G01X1453656D02*
G02X1456252I1298J0D01*
G02X1455196Y1136194I-1298J0D01*
G01X1455106Y1136177D01*
X1454298Y1134779D01*
X1454329Y1134692D01*
G02X1454402Y1134264I-1225J-429D01*
G02X1451806I-1298J0D01*
G02X1452862Y1135539I1298J0D01*
G01X1452952Y1135556D01*
X1453760Y1136954D01*
X1453729Y1137041D01*
G02X1453656Y1137469I1225J429D01*
G37*
G36*
G01X1461056D02*
G02X1463652I1298J0D01*
G02X1462596Y1136194I-1298J0D01*
G01X1462506Y1136177D01*
X1461699Y1134779D01*
X1461729Y1134692D01*
G02X1461802Y1134264I-1225J-429D01*
G02X1459206I-1298J0D01*
G02X1460263Y1135539I1297J0D01*
G01X1460353Y1135556D01*
X1461160Y1136954D01*
X1461129Y1137041D01*
G02X1461056Y1137469I1225J429D01*
G37*
G36*
G01X1468456D02*
G02X1471052I1298J0D01*
G02X1469996Y1136194I-1298J0D01*
G01X1469906Y1136177D01*
X1469099Y1134779D01*
X1469129Y1134692D01*
G02X1469202Y1134264I-1225J-429D01*
G02X1466606I-1298J0D01*
G02X1467663Y1135539I1297J0D01*
G01X1467753Y1135556D01*
X1468560Y1136954D01*
X1468529Y1137041D01*
G02X1468456Y1137469I1225J429D01*
G37*
G36*
G01X1475856D02*
G02X1478452I1298J0D01*
G02X1477396Y1136194I-1298J0D01*
G01X1477306Y1136177D01*
X1476499Y1134779D01*
X1476529Y1134692D01*
G02X1476602Y1134264I-1225J-429D01*
G02X1474006I-1298J0D01*
G02X1475063Y1135539I1297J0D01*
G01X1475153Y1135556D01*
X1475960Y1136954D01*
X1475929Y1137041D01*
G02X1475856Y1137469I1225J429D01*
G37*
G36*
G01X1483256D02*
G02X1485852I1298J0D01*
G02X1484796Y1136194I-1298J0D01*
G01X1484706Y1136177D01*
X1483899Y1134779D01*
X1483929Y1134692D01*
G02X1484002Y1134264I-1225J-429D01*
G02X1481406I-1298J0D01*
G02X1482463Y1135539I1297J0D01*
G01X1482553Y1135556D01*
X1483360Y1136954D01*
X1483329Y1137041D01*
G02X1483256Y1137469I1225J429D01*
G37*
G36*
G01X1490656D02*
G02X1493252I1298J0D01*
G02X1492196Y1136194I-1298J0D01*
G01X1492106Y1136177D01*
X1491299Y1134779D01*
X1491329Y1134692D01*
G02X1491402Y1134264I-1225J-429D01*
G02X1488806I-1298J0D01*
G02X1489863Y1135539I1297J0D01*
G01X1489953Y1135556D01*
X1490760Y1136954D01*
X1490729Y1137041D01*
G02X1490656Y1137469I1225J429D01*
G37*
G36*
G01X1498056D02*
G02X1500652I1298J0D01*
G02X1499596Y1136194I-1298J0D01*
G01X1499506Y1136177D01*
X1498699Y1134779D01*
X1498729Y1134692D01*
G02X1498802Y1134264I-1225J-429D01*
G02X1496206I-1298J0D01*
G02X1497263Y1135539I1297J0D01*
G01X1497353Y1135556D01*
X1498160Y1136954D01*
X1498129Y1137041D01*
G02X1498056Y1137469I1225J429D01*
G37*
G36*
G01X1509156D02*
G02X1511752I1298J0D01*
G02X1510696Y1136194I-1298J0D01*
G01X1510606Y1136177D01*
X1509798Y1134779D01*
X1509829Y1134692D01*
G02X1509902Y1134264I-1225J-429D01*
G02X1507306I-1298J0D01*
G02X1508362Y1135539I1298J0D01*
G01X1508452Y1135556D01*
X1509260Y1136954D01*
X1509229Y1137041D01*
G02X1509156Y1137469I1225J429D01*
G37*
G36*
G01X360964Y1140973D02*
G02X363558I1297J0D01*
G02X362496Y1139697I-1298J0D01*
G01X362401Y1139679D01*
X361559Y1138084D01*
X361598Y1137995D01*
G02X361710Y1137469I-1186J-527D01*
G02X359114I-1298J0D01*
G02X360177Y1138745I1297J0D01*
G01X360272Y1138763D01*
X361114Y1140358D01*
X361075Y1140447D01*
G02X360964Y1140971I1186J525D01*
G01Y1140973D01*
G37*
G36*
G01X368364D02*
G02X370958I1297J0D01*
G02X369896Y1139697I-1298J0D01*
G01X369801Y1139679D01*
X368959Y1138084D01*
X368998Y1137995D01*
G02X369110Y1137469I-1186J-527D01*
G02X366514I-1298J0D01*
G02X367577Y1138745I1297J0D01*
G01X367672Y1138763D01*
X368514Y1140358D01*
X368475Y1140447D01*
G02X368364Y1140971I1186J525D01*
G01Y1140973D01*
G37*
G36*
G01X375764D02*
G02X378358I1297J0D01*
G02X377296Y1139697I-1298J0D01*
G01X377201Y1139679D01*
X376359Y1138084D01*
X376398Y1137995D01*
G02X376510Y1137469I-1186J-527D01*
G02X373914I-1298J0D01*
G02X374977Y1138745I1297J0D01*
G01X375072Y1138763D01*
X375914Y1140358D01*
X375875Y1140447D01*
G02X375764Y1140971I1186J525D01*
G01Y1140973D01*
G37*
G36*
G01X383164D02*
G02X385758I1297J0D01*
G02X384696Y1139697I-1298J0D01*
G01X384601Y1139679D01*
X383759Y1138084D01*
X383798Y1137995D01*
G02X383910Y1137469I-1186J-527D01*
G02X381314I-1298J0D01*
G02X382377Y1138745I1297J0D01*
G01X382472Y1138763D01*
X383314Y1140358D01*
X383275Y1140447D01*
G02X383164Y1140971I1186J525D01*
G01Y1140973D01*
G37*
G36*
G01X390564D02*
G02X393158I1297J0D01*
G02X392096Y1139697I-1298J0D01*
G01X392001Y1139679D01*
X391159Y1138084D01*
X391198Y1137995D01*
G02X391310Y1137469I-1186J-527D01*
G02X388714I-1298J0D01*
G02X389777Y1138745I1297J0D01*
G01X389872Y1138763D01*
X390714Y1140358D01*
X390675Y1140447D01*
G02X390564Y1140971I1186J525D01*
G01Y1140973D01*
G37*
G36*
G01X397964D02*
G02X400558I1297J0D01*
G02X399496Y1139697I-1298J0D01*
G01X399401Y1139679D01*
X398559Y1138084D01*
X398598Y1137995D01*
G02X398710Y1137469I-1186J-527D01*
G02X396114I-1298J0D01*
G02X397177Y1138745I1297J0D01*
G01X397272Y1138763D01*
X398114Y1140358D01*
X398075Y1140447D01*
G02X397964Y1140971I1186J525D01*
G01Y1140973D01*
G37*
G36*
G01X405364D02*
G02X407958I1297J0D01*
G02X406896Y1139697I-1298J0D01*
G01X406801Y1139679D01*
X405959Y1138084D01*
X405998Y1137995D01*
G02X406110Y1137469I-1186J-527D01*
G02X403514I-1298J0D01*
G02X404577Y1138745I1297J0D01*
G01X404672Y1138763D01*
X405514Y1140358D01*
X405475Y1140447D01*
G02X405364Y1140971I1186J525D01*
G01Y1140973D01*
G37*
G36*
G01X471964D02*
G02X474558I1297J0D01*
G02X474447Y1140448I-1297J0D01*
G01X474408Y1140359D01*
X475252Y1138763D01*
X475347Y1138745D01*
G02X476410Y1137469I-234J-1276D01*
G02X473814I-1298J0D01*
G02X473926Y1137994I1297J-2D01*
G01X473965Y1138083D01*
X473121Y1139679D01*
X473026Y1139697D01*
G02X471964Y1140973I236J1276D01*
G37*
G36*
G01X479364D02*
G02X481958I1297J0D01*
G02X481847Y1140448I-1297J0D01*
G01X481808Y1140359D01*
X482652Y1138763D01*
X482747Y1138745D01*
G02X483810Y1137469I-234J-1276D01*
G02X481214I-1298J0D01*
G02X481326Y1137994I1297J-2D01*
G01X481365Y1138083D01*
X480521Y1139679D01*
X480426Y1139697D01*
G02X479364Y1140973I236J1276D01*
G37*
G36*
G01X486764D02*
G02X489358I1297J0D01*
G02X489247Y1140448I-1297J0D01*
G01X489208Y1140359D01*
X490052Y1138763D01*
X490147Y1138745D01*
G02X491210Y1137469I-234J-1276D01*
G02X488614I-1298J0D01*
G02X488726Y1137994I1297J-2D01*
G01X488765Y1138083D01*
X487921Y1139679D01*
X487826Y1139697D01*
G02X486764Y1140973I236J1276D01*
G37*
G36*
G01X494164D02*
G02X496758I1297J0D01*
G02X496647Y1140448I-1297J0D01*
G01X496608Y1140359D01*
X497452Y1138763D01*
X497547Y1138745D01*
G02X498610Y1137469I-234J-1276D01*
G02X496014I-1298J0D01*
G02X496126Y1137994I1297J-2D01*
G01X496165Y1138083D01*
X495321Y1139679D01*
X495226Y1139697D01*
G02X494164Y1140973I236J1276D01*
G37*
G36*
G01X501564D02*
G02X504158I1297J0D01*
G02X504047Y1140448I-1297J0D01*
G01X504008Y1140359D01*
X504852Y1138763D01*
X504947Y1138745D01*
G02X506010Y1137469I-234J-1276D01*
G02X503414I-1298J0D01*
G02X503526Y1137994I1297J-2D01*
G01X503565Y1138083D01*
X502721Y1139679D01*
X502626Y1139697D01*
G02X501564Y1140973I236J1276D01*
G37*
G36*
G01X508964D02*
G02X511558I1297J0D01*
G02X511447Y1140448I-1297J0D01*
G01X511408Y1140359D01*
X512252Y1138763D01*
X512347Y1138745D01*
G02X513410Y1137469I-234J-1276D01*
G02X510814I-1298J0D01*
G02X510926Y1137994I1297J-2D01*
G01X510965Y1138083D01*
X510121Y1139679D01*
X510026Y1139697D01*
G02X508964Y1140973I236J1276D01*
G37*
G36*
G01X516364D02*
G02X518958I1297J0D01*
G02X518847Y1140448I-1297J0D01*
G01X518808Y1140359D01*
X519652Y1138763D01*
X519747Y1138745D01*
G02X520810Y1137469I-234J-1276D01*
G02X518214I-1298J0D01*
G02X518326Y1137994I1297J-2D01*
G01X518365Y1138083D01*
X517521Y1139679D01*
X517426Y1139697D01*
G02X516364Y1140973I236J1276D01*
G37*
G36*
G01X523764D02*
G02X526358I1297J0D01*
G02X526247Y1140448I-1297J0D01*
G01X526208Y1140359D01*
X527052Y1138763D01*
X527147Y1138745D01*
G02X528210Y1137469I-234J-1276D01*
G02X525614I-1298J0D01*
G02X525726Y1137994I1297J-2D01*
G01X525765Y1138083D01*
X524921Y1139679D01*
X524826Y1139697D01*
G02X523764Y1140973I236J1276D01*
G37*
G36*
G01X1337106D02*
G02X1339700I1297J0D01*
G02X1338638Y1139697I-1298J0D01*
G01X1338543Y1139679D01*
X1337701Y1138084D01*
X1337740Y1137995D01*
G02X1337852Y1137469I-1186J-527D01*
G02X1335256I-1298J0D01*
G02X1336319Y1138745I1297J0D01*
G01X1336414Y1138763D01*
X1337256Y1140358D01*
X1337217Y1140447D01*
G02X1337106Y1140971I1186J525D01*
G01Y1140973D01*
G37*
G36*
G01X1344506D02*
G02X1347100I1297J0D01*
G02X1346038Y1139697I-1298J0D01*
G01X1345943Y1139679D01*
X1345101Y1138084D01*
X1345140Y1137995D01*
G02X1345252Y1137469I-1186J-527D01*
G02X1342656I-1298J0D01*
G02X1343719Y1138745I1297J0D01*
G01X1343814Y1138763D01*
X1344656Y1140358D01*
X1344617Y1140447D01*
G02X1344506Y1140971I1186J525D01*
G01Y1140973D01*
G37*
G36*
G01X1351906D02*
G02X1354500I1297J0D01*
G02X1353438Y1139697I-1298J0D01*
G01X1353343Y1139679D01*
X1352501Y1138084D01*
X1352540Y1137995D01*
G02X1352652Y1137469I-1186J-527D01*
G02X1350056I-1298J0D01*
G02X1351119Y1138745I1297J0D01*
G01X1351214Y1138763D01*
X1352056Y1140358D01*
X1352017Y1140447D01*
G02X1351906Y1140971I1186J525D01*
G01Y1140973D01*
G37*
G36*
G01X1359306D02*
G02X1361900I1297J0D01*
G02X1360838Y1139697I-1298J0D01*
G01X1360743Y1139679D01*
X1359901Y1138084D01*
X1359940Y1137995D01*
G02X1360052Y1137469I-1186J-527D01*
G02X1357456I-1298J0D01*
G02X1358519Y1138745I1297J0D01*
G01X1358614Y1138763D01*
X1359456Y1140358D01*
X1359417Y1140447D01*
G02X1359306Y1140971I1186J525D01*
G01Y1140973D01*
G37*
G36*
G01X1366706D02*
G02X1369300I1297J0D01*
G02X1368238Y1139697I-1298J0D01*
G01X1368143Y1139679D01*
X1367301Y1138084D01*
X1367340Y1137995D01*
G02X1367452Y1137469I-1186J-527D01*
G02X1364856I-1298J0D01*
G02X1365919Y1138745I1297J0D01*
G01X1366014Y1138763D01*
X1366856Y1140358D01*
X1366817Y1140447D01*
G02X1366706Y1140971I1186J525D01*
G01Y1140973D01*
G37*
G36*
G01X1374106D02*
G02X1376700I1297J0D01*
G02X1375638Y1139697I-1298J0D01*
G01X1375543Y1139679D01*
X1374701Y1138084D01*
X1374740Y1137995D01*
G02X1374852Y1137469I-1186J-527D01*
G02X1372256I-1298J0D01*
G02X1373319Y1138745I1297J0D01*
G01X1373414Y1138763D01*
X1374256Y1140358D01*
X1374217Y1140447D01*
G02X1374106Y1140971I1186J525D01*
G01Y1140973D01*
G37*
G36*
G01X1381506D02*
G02X1384100I1297J0D01*
G02X1383038Y1139697I-1298J0D01*
G01X1382943Y1139679D01*
X1382101Y1138084D01*
X1382140Y1137995D01*
G02X1382252Y1137469I-1186J-527D01*
G02X1379656I-1298J0D01*
G02X1380719Y1138745I1297J0D01*
G01X1380814Y1138763D01*
X1381656Y1140358D01*
X1381617Y1140447D01*
G02X1381506Y1140971I1186J525D01*
G01Y1140973D01*
G37*
G36*
G01X1448106D02*
G02X1450700I1297J0D01*
G02X1450589Y1140448I-1297J0D01*
G01X1450550Y1140359D01*
X1451394Y1138763D01*
X1451489Y1138745D01*
G02X1452552Y1137469I-234J-1276D01*
G02X1449956I-1298J0D01*
G02X1450068Y1137994I1297J-2D01*
G01X1450107Y1138083D01*
X1449263Y1139679D01*
X1449168Y1139697D01*
G02X1448106Y1140973I236J1276D01*
G37*
G36*
G01X1455506D02*
G02X1458100I1297J0D01*
G02X1457989Y1140448I-1297J0D01*
G01X1457950Y1140359D01*
X1458794Y1138763D01*
X1458889Y1138745D01*
G02X1459952Y1137469I-234J-1276D01*
G02X1457356I-1298J0D01*
G02X1457468Y1137994I1297J-2D01*
G01X1457507Y1138083D01*
X1456663Y1139679D01*
X1456568Y1139697D01*
G02X1455506Y1140973I236J1276D01*
G37*
G36*
G01X1462906D02*
G02X1465500I1297J0D01*
G02X1465389Y1140448I-1297J0D01*
G01X1465350Y1140359D01*
X1466194Y1138763D01*
X1466289Y1138745D01*
G02X1467352Y1137469I-234J-1276D01*
G02X1464756I-1298J0D01*
G02X1464868Y1137994I1297J-2D01*
G01X1464907Y1138083D01*
X1464063Y1139679D01*
X1463968Y1139697D01*
G02X1462906Y1140973I236J1276D01*
G37*
G36*
G01X1470306D02*
G02X1472900I1297J0D01*
G02X1472789Y1140448I-1297J0D01*
G01X1472750Y1140359D01*
X1473594Y1138763D01*
X1473689Y1138745D01*
G02X1474752Y1137469I-234J-1276D01*
G02X1472156I-1298J0D01*
G02X1472268Y1137994I1297J-2D01*
G01X1472307Y1138083D01*
X1471463Y1139679D01*
X1471368Y1139697D01*
G02X1470306Y1140973I236J1276D01*
G37*
G36*
G01X1477706D02*
G02X1480300I1297J0D01*
G02X1480189Y1140448I-1297J0D01*
G01X1480150Y1140359D01*
X1480994Y1138763D01*
X1481089Y1138745D01*
G02X1482152Y1137469I-234J-1276D01*
G02X1479556I-1298J0D01*
G02X1479668Y1137994I1297J-2D01*
G01X1479707Y1138083D01*
X1478863Y1139679D01*
X1478768Y1139697D01*
G02X1477706Y1140973I236J1276D01*
G37*
G36*
G01X1485106D02*
G02X1487700I1297J0D01*
G02X1487589Y1140448I-1297J0D01*
G01X1487550Y1140359D01*
X1488394Y1138763D01*
X1488489Y1138745D01*
G02X1489552Y1137469I-234J-1276D01*
G02X1486956I-1298J0D01*
G02X1487068Y1137994I1297J-2D01*
G01X1487107Y1138083D01*
X1486263Y1139679D01*
X1486168Y1139697D01*
G02X1485106Y1140973I236J1276D01*
G37*
G36*
G01X1492506D02*
G02X1495100I1297J0D01*
G02X1494989Y1140448I-1297J0D01*
G01X1494950Y1140359D01*
X1495794Y1138763D01*
X1495889Y1138745D01*
G02X1496952Y1137469I-234J-1276D01*
G02X1494356I-1298J0D01*
G02X1494468Y1137994I1297J-2D01*
G01X1494507Y1138083D01*
X1493663Y1139679D01*
X1493568Y1139697D01*
G02X1492506Y1140973I236J1276D01*
G37*
G36*
G01X1499906D02*
G02X1502500I1297J0D01*
G02X1502389Y1140448I-1297J0D01*
G01X1502350Y1140359D01*
X1503194Y1138763D01*
X1503289Y1138745D01*
G02X1504352Y1137469I-234J-1276D01*
G02X1501756I-1298J0D01*
G02X1501868Y1137994I1297J-2D01*
G01X1501907Y1138083D01*
X1501063Y1139679D01*
X1500968Y1139697D01*
G02X1499906Y1140973I236J1276D01*
G37*
G36*
G01X1143020Y1540382D02*
G03X1143411Y1540758I-8J400D01*
G02X1145410Y1542642I1999J-119D01*
G02X1147412Y1540640I0J-2002D01*
G02X1145450Y1538638I-2002J0D01*
G03X1145059Y1538262I8J-400D01*
G02X1143060Y1536378I-1999J119D01*
G02X1141058Y1538380I0J2002D01*
G02X1143020Y1540382I2002J0D01*
G37*
G36*
G01X1162980Y1551449D02*
G03X1163635I328J229D01*
G02X1166917I1641J-1147D01*
G03X1167572I327J229D01*
G02X1169213Y1552304I1641J-1147D01*
G02Y1548298I0J-2003D01*
G02X1167572Y1549153I0J2002D01*
G03X1166917I-328J-229D01*
G02X1163635I-1641J1147D01*
G03X1162980I-327J-229D01*
G02X1159698I-1641J1147D01*
G03X1159043I-328J-229D01*
G02X1155761I-1641J1147D01*
G03X1155106I-328J-229D01*
G02X1151824I-1641J1147D01*
G03X1151169I-328J-229D01*
G02X1149528Y1548298I-1641J1147D01*
G02Y1552304I0J2003D01*
G02X1151169Y1551449I0J-2002D01*
G03X1151824I327J229D01*
G02X1155106I1641J-1147D01*
G03X1155761I328J229D01*
G02X1159043I1641J-1147D01*
G03X1159698I327J229D01*
G02X1162980I1641J-1147D01*
G37*
G36*
G01X1139652Y1550301D02*
Y1550302D01*
G02X1140157Y1551631I2002J0D01*
G02X1139688Y1552918I1533J1288D01*
G01Y1552920D01*
G02X1143692I2002J0D01*
G01Y1552919D01*
G02X1143187Y1551590I-2002J0D01*
G02X1143656Y1550303I-1533J-1288D01*
G01Y1550301D01*
G02X1139652I-2002J0D01*
G37*
G36*
G01X1101405Y1550386D02*
G03X1101083Y1550900I-382J119D01*
G02X1098098Y1554364I517J3464D01*
G02X1105102I3502J0D01*
G02X1104945Y1553324I-3502J-3D01*
G03X1105267Y1552810I382J-119D01*
G02X1108252Y1549346I-517J-3464D01*
G02X1101248I-3502J0D01*
G02X1101405Y1550386I3502J3D01*
G37*
G36*
G01X1143823Y1573272D02*
G03X1143551I-136J-147D01*
G02X1142188Y1572736I-1363J1466D01*
G01X1142187D01*
G02Y1576740I0J2002D01*
G01X1142188D01*
G02X1143551Y1576204I0J-2002D01*
G03X1143823I136J147D01*
G02X1145186Y1576740I1363J-1466D01*
G01X1145187D01*
G02Y1572736I0J-2002D01*
G01X1145186D01*
G02X1143823Y1573272I0J2002D01*
G37*
G36*
G01X1153823D02*
G03X1153551I-136J-147D01*
G02X1152188Y1572736I-1363J1466D01*
G01X1152187D01*
G02Y1576740I0J2002D01*
G01X1152188D01*
G02X1153551Y1576204I0J-2002D01*
G03X1153823I136J147D01*
G02X1155186Y1576740I1363J-1466D01*
G01X1155187D01*
G02Y1572736I0J-2002D01*
G01X1155186D01*
G02X1153823Y1573272I0J2002D01*
G37*
G36*
G01X1163231D02*
G03X1162959I-136J-147D01*
G02X1161596Y1572736I-1363J1466D01*
G01X1161595D01*
G02Y1576740I0J2002D01*
G01X1161596D01*
G02X1162959Y1576204I0J-2002D01*
G03X1163231I136J147D01*
G02X1164594Y1576740I1363J-1466D01*
G01X1164595D01*
G02Y1572736I0J-2002D01*
G01X1164594D01*
G02X1163231Y1573272I0J2002D01*
G37*
G36*
G01X1173231D02*
G03X1172959I-136J-147D01*
G02X1171596Y1572736I-1363J1466D01*
G01X1171595D01*
G02Y1576740I0J2002D01*
G01X1171596D01*
G02X1172959Y1576204I0J-2002D01*
G03X1173231I136J147D01*
G02X1174594Y1576740I1363J-1466D01*
G01X1174595D01*
G02Y1572736I0J-2002D01*
G01X1174594D01*
G02X1173231Y1573272I0J2002D01*
G37*
G36*
G01X1133823Y1581272D02*
G03X1133551I-136J-147D01*
G02X1132188Y1580736I-1363J1466D01*
G01X1132187D01*
G02Y1584740I0J2002D01*
G01X1132188D01*
G02X1133551Y1584204I0J-2002D01*
G03X1133823I136J147D01*
G02X1135186Y1584740I1363J-1466D01*
G01X1135187D01*
G02Y1580736I0J-2002D01*
G01X1135186D01*
G02X1133823Y1581272I0J2002D01*
G37*
G36*
G01X1143823D02*
G03X1143551I-136J-147D01*
G02X1142188Y1580736I-1363J1466D01*
G01X1142187D01*
G02Y1584740I0J2002D01*
G01X1142188D01*
G02X1143551Y1584204I0J-2002D01*
G03X1143823I136J147D01*
G02X1145186Y1584740I1363J-1466D01*
G01X1145187D01*
G02Y1580736I0J-2002D01*
G01X1145186D01*
G02X1143823Y1581272I0J2002D01*
G37*
G36*
G01X1153823D02*
G03X1153551I-136J-147D01*
G02X1152188Y1580736I-1363J1466D01*
G01X1152187D01*
G02Y1584740I0J2002D01*
G01X1152188D01*
G02X1153551Y1584204I0J-2002D01*
G03X1153823I136J147D01*
G02X1155186Y1584740I1363J-1466D01*
G01X1155187D01*
G02Y1580736I0J-2002D01*
G01X1155186D01*
G02X1153823Y1581272I0J2002D01*
G37*
G36*
G01X1163231D02*
G03X1162959I-136J-147D01*
G02X1161596Y1580736I-1363J1466D01*
G01X1161595D01*
G02Y1584740I0J2002D01*
G01X1161596D01*
G02X1162959Y1584204I0J-2002D01*
G03X1163231I136J147D01*
G02X1164594Y1584740I1363J-1466D01*
G01X1164595D01*
G02Y1580736I0J-2002D01*
G01X1164594D01*
G02X1163231Y1581272I0J2002D01*
G37*
G36*
G01X1173231D02*
G03X1172959I-136J-147D01*
G02X1171596Y1580736I-1363J1466D01*
G01X1171595D01*
G02Y1584740I0J2002D01*
G01X1171596D01*
G02X1172959Y1584204I0J-2002D01*
G03X1173231I136J147D01*
G02X1174594Y1584740I1363J-1466D01*
G01X1174595D01*
G02Y1580736I0J-2002D01*
G01X1174594D01*
G02X1173231Y1581272I0J2002D01*
G37*
G36*
G01X1133823Y1589272D02*
G03X1133551I-136J-147D01*
G02X1132188Y1588736I-1363J1466D01*
G01X1132187D01*
G02Y1592740I0J2002D01*
G01X1132188D01*
G02X1133551Y1592204I0J-2002D01*
G03X1133823I136J147D01*
G02X1135186Y1592740I1363J-1466D01*
G01X1135187D01*
G02Y1588736I0J-2002D01*
G01X1135186D01*
G02X1133823Y1589272I0J2002D01*
G37*
G36*
G01X1143823D02*
G03X1143551I-136J-147D01*
G02X1142188Y1588736I-1363J1466D01*
G01X1142187D01*
G02Y1592740I0J2002D01*
G01X1142188D01*
G02X1143551Y1592204I0J-2002D01*
G03X1143823I136J147D01*
G02X1145186Y1592740I1363J-1466D01*
G01X1145187D01*
G02Y1588736I0J-2002D01*
G01X1145186D01*
G02X1143823Y1589272I0J2002D01*
G37*
G36*
G01X1153823D02*
G03X1153551I-136J-147D01*
G02X1152188Y1588736I-1363J1466D01*
G01X1152187D01*
G02Y1592740I0J2002D01*
G01X1152188D01*
G02X1153551Y1592204I0J-2002D01*
G03X1153823I136J147D01*
G02X1155186Y1592740I1363J-1466D01*
G01X1155187D01*
G02Y1588736I0J-2002D01*
G01X1155186D01*
G02X1153823Y1589272I0J2002D01*
G37*
G36*
G01X1163231D02*
G03X1162959I-136J-147D01*
G02X1161596Y1588736I-1363J1466D01*
G01X1161595D01*
G02Y1592740I0J2002D01*
G01X1161596D01*
G02X1162959Y1592204I0J-2002D01*
G03X1163231I136J147D01*
G02X1164594Y1592740I1363J-1466D01*
G01X1164595D01*
G02Y1588736I0J-2002D01*
G01X1164594D01*
G02X1163231Y1589272I0J2002D01*
G37*
G36*
G01X1173231D02*
G03X1172959I-136J-147D01*
G02X1171596Y1588736I-1363J1466D01*
G01X1171595D01*
G02Y1592740I0J2002D01*
G01X1171596D01*
G02X1172959Y1592204I0J-2002D01*
G03X1173231I136J147D01*
G02X1174594Y1592740I1363J-1466D01*
G01X1174595D01*
G02Y1588736I0J-2002D01*
G01X1174594D01*
G02X1173231Y1589272I0J2002D01*
G37*
G36*
G01X810826Y1715542D02*
X816058Y1720774D01*
G02X816942Y1721140I884J-885D01*
G01X901218D01*
G02X902102Y1720774I0J-1251D01*
G01X909144Y1713732D01*
G02X909510Y1712848I-885J-884D01*
G01Y1667718D01*
X918658Y1658570D01*
X1064888D01*
G02X1065772Y1658204I0J-1251D01*
G01X1085876Y1638100D01*
X1102078D01*
G02X1102962Y1637734I0J-1251D01*
G01X1105274Y1635422D01*
G02X1105640Y1634538I-885J-884D01*
G01Y1606962D01*
G02X1105274Y1606078I-1251J0D01*
G01X1103642Y1604446D01*
G02X1102758Y1604080I-884J885D01*
G01X1081112D01*
X1080194Y1603162D01*
Y1602842D01*
X1081707Y1601328D01*
G02X1082362Y1600268I-1907J-1911D01*
G03X1083025Y1600111I380J126D01*
G01X1083178Y1600264D01*
G02X1084062Y1600630I884J-885D01*
G01X1095052D01*
G02X1095199Y1600621I-3J-1250D01*
G01X1095210Y1600620D01*
X1106448D01*
G02X1107332Y1600254I0J-1251D01*
G01X1108636Y1598950D01*
G02X1109002Y1598066I-885J-884D01*
G01Y1565342D01*
G02X1108636Y1564458I-1251J0D01*
G01X1106544Y1562366D01*
G02X1105660Y1562000I-884J885D01*
G01X1084682D01*
G02X1083798Y1562366I0J1251D01*
G01X1082380Y1563784D01*
G03X1081801Y1563770I-283J-283D01*
G02X1081707Y1563672I-1995J1819D01*
G01X1080842Y1562807D01*
X1080645Y1562602D01*
G02X1080216Y1562313I-898J870D01*
G01X1079671Y1562092D01*
G02X1079201Y1562000I-471J1158D01*
G01X945581D01*
G02X943672Y1562793I2J2700D01*
G01X941807Y1564658D01*
X941602Y1564855D01*
G02X941313Y1565284I870J898D01*
G01X941092Y1565829D01*
G02X941000Y1566299I1158J471D01*
G01Y1599900D01*
X940822Y1600078D01*
X940214D01*
X936892Y1596756D01*
G02X936008Y1596390I-884J885D01*
G01X927766D01*
X923290Y1591914D01*
Y1578352D01*
G02X922924Y1577468I-1251J0D01*
G01X922132Y1576676D01*
G02X921248Y1576310I-884J885D01*
G01X906872D01*
G02X905988Y1576676I0J1251D01*
G01X905196Y1577468D01*
G02X904830Y1578352I885J884D01*
G01Y1591896D01*
X904388Y1592338D01*
G02X904022Y1593222I885J884D01*
G01Y1603382D01*
X896864Y1610540D01*
X889128D01*
X882022Y1603434D01*
Y1593152D01*
G02X881656Y1592268I-1251J0D01*
G01X881310Y1591922D01*
Y1578402D01*
G02X880944Y1577518I-1251J0D01*
G01X880112Y1576686D01*
G02X879228Y1576320I-884J885D01*
G01X864892D01*
G02X864008Y1576686I0J1251D01*
G01X863206Y1577488D01*
G02X862840Y1578372I885J884D01*
G01Y1591966D01*
X862488Y1592318D01*
G02X862122Y1593202I885J884D01*
G01Y1602864D01*
X854886Y1610100D01*
X846166D01*
X839980Y1603914D01*
Y1593162D01*
G02X839614Y1592278I-1251J0D01*
G01X839280Y1591944D01*
Y1578322D01*
G02X838914Y1577438I-1251J0D01*
G01X838162Y1576686D01*
G02X837278Y1576320I-884J885D01*
G01X822872D01*
G02X821988Y1576686I0J1251D01*
G01X821236Y1577438D01*
G02X820870Y1578322I885J884D01*
G01Y1591816D01*
X820488Y1592198D01*
G02X820122Y1593082I885J884D01*
G01Y1603042D01*
X812654Y1610510D01*
X804298D01*
X798022Y1604234D01*
Y1593104D01*
G02X797656Y1592220I-1251J0D01*
G01X797290Y1591854D01*
Y1578352D01*
G02X796924Y1577468I-1251J0D01*
G01X796142Y1576686D01*
G02X795258Y1576320I-884J885D01*
G01X780872D01*
G02X779988Y1576686I0J1251D01*
G01X779236Y1577438D01*
G02X778870Y1578322I885J884D01*
G01Y1591954D01*
X774954Y1595870D01*
X751976D01*
X751087Y1594981D01*
X751101Y1594883D01*
G02X751114Y1594683I-1489J-197D01*
G02X749612Y1593181I-1502J0D01*
G02X749412Y1593194I-3J1502D01*
G01X749314Y1593208D01*
X748022Y1591915D01*
Y1590733D01*
G02X747656Y1589849I-1251J0D01*
G01X746824Y1589017D01*
G02X745940Y1588651I-884J885D01*
G01X745090D01*
Y1578308D01*
G02X744730Y1577431I-1250J1D01*
G01X743935Y1576624D01*
G02X743045Y1576251I-891J877D01*
G01X727872D01*
G02X726622Y1577501I0J1250D01*
G01Y1600869D01*
G02X726988Y1601753I1251J0D01*
G01X727560Y1602325D01*
X727554Y1602415D01*
G02X727550Y1602518I1498J110D01*
G02X727922Y1603507I1501J0D01*
G01Y1606915D01*
X727488Y1607349D01*
G02X727122Y1608233I885J884D01*
G01Y1626632D01*
G02X727488Y1627516I1251J0D01*
G01X758056Y1658084D01*
G02X758940Y1658450I884J-885D01*
G01X776714D01*
X810460Y1692196D01*
Y1714658D01*
G02X810826Y1715542I1251J0D01*
G37*
G36*
G01X1411037Y1711457D02*
G03X1411142Y1712134I-151J370D01*
G02X1421732I5295J6330D01*
G03X1421837Y1711457I256J-307D01*
G02X1430690Y1698267I-5399J-13190D01*
G02X1402184I-14253J0D01*
G02X1411037Y1711457I14252J0D01*
G37*
G36*
G01X435643Y1711458D02*
G03X435748Y1712135I-151J370D01*
G02X446338I5295J6330D01*
G03X446443Y1711458I256J-307D01*
G02X455296Y1698268I-5399J-13190D01*
G02X426790I-14253J0D01*
G02X435643Y1711458I14252J0D01*
G37*
G54D104*
X1137717Y1558020D03*
G54D101*
X1290005Y293768D03*
G54D97*
X1455787Y1421784D03*
X1710550Y691327D03*
X93547Y692260D03*
X479646Y1421784D03*
G54D102*
X1175215Y1532913D03*
X1131715D03*
G54D82*
X1307572Y-26511D03*
X1040152Y-16511D03*
X1015152D03*
X1307572Y13489D03*
X1282572Y23489D03*
X1307572D03*
X1282572Y13489D03*
X1040152Y23489D03*
Y13489D03*
X973180Y-6500D03*
X998180D03*
X1015152Y13489D03*
X1282572Y-16511D03*
X973180Y-26500D03*
X998180D03*
Y-16500D03*
X1015152Y23489D03*
X1307572Y-16511D03*
X973180Y-16500D03*
X1474931Y23489D03*
X1499931D03*
X705760Y-26500D03*
X730760D03*
X705760Y-6500D03*
Y-16500D03*
X730760D03*
Y-6500D03*
X1474931Y13489D03*
X998180Y3500D03*
X973180D03*
X1499931Y13489D03*
X998180Y13500D03*
Y23500D03*
X973180D03*
Y13500D03*
X1499931Y-16511D03*
X1474931D03*
X1324471Y23489D03*
X1349471D03*
X822720Y3500D03*
X847720D03*
X822720Y23500D03*
Y13500D03*
X847720D03*
Y23500D03*
X1324471Y-16511D03*
X1349471D03*
X1324471Y13489D03*
X1349471D03*
X1307572Y-36511D03*
X1282572D03*
Y-26511D03*
X1307572Y-6511D03*
Y3489D03*
X1282572D03*
Y-6511D03*
X1015152Y-36511D03*
Y-26511D03*
X1040152D03*
Y-36511D03*
X1015152Y3489D03*
Y-6511D03*
X1040152D03*
Y3489D03*
X1499931Y-26511D03*
Y-36511D03*
X1474931D03*
Y-26511D03*
X1499931Y-6511D03*
Y3489D03*
X1474931D03*
Y-6511D03*
X1324471Y-36511D03*
Y-26511D03*
X1349471D03*
Y-36511D03*
X1324471Y3489D03*
Y-6511D03*
X1349471D03*
Y3489D03*
G54D89*
X70472Y173228D03*
Y236220D03*
G54D93*
X1565236Y184783D03*
Y264035D03*
G54D94*
X929331Y160413D03*
X922441Y237697D03*
X1534712Y20354D03*
X1787330Y24291D03*
X505185Y41142D03*
X757803Y45079D03*
X312921Y24291D03*
G54D92*
X676508Y224606D03*
G54D91*
Y145866D03*
G54D88*
X1829725Y130315D03*
G54D84*
X791280Y1704890D03*
X1066280D03*
G54D99*
X1405118Y112008D03*
G54D81*
X1341752Y-31511D03*
Y-21511D03*
Y-11511D03*
Y-1511D03*
X1482650Y-31511D03*
Y-21511D03*
Y-11511D03*
Y-1511D03*
X90998Y1517237D03*
X78120Y1517136D03*
X99750Y1563678D03*
X75922Y1560674D03*
X404030Y1593690D03*
X957156Y228863D03*
X899830Y973184D03*
X1380522Y261936D03*
X1388754Y255503D03*
X1380638Y247394D03*
X1386630Y240351D03*
X397406Y1634842D03*
X1031950Y385471D03*
X736710Y605542D03*
X527310Y96447D03*
X414406Y1626692D03*
X460910Y1627472D03*
X64410Y1600802D03*
X1340420Y540122D03*
X704770Y204921D03*
X896060Y482922D03*
X716698Y210721D03*
X704770Y216732D03*
X895340Y499582D03*
X907470Y213680D03*
X902350Y220768D03*
X953970Y206575D03*
X716698Y198887D03*
X704770Y193110D03*
Y181299D03*
X947496Y227835D03*
X705800Y169488D03*
X947496Y213697D03*
X907470Y227854D03*
X941050Y530552D03*
X968286Y482241D03*
X716698Y175387D03*
X902350Y206594D03*
X944032Y435931D03*
X716698Y187387D03*
X944250Y196189D03*
X954420Y512952D03*
Y498852D03*
G54D100*
X1247638Y269488D03*
G54D96*
X1550708Y991220D03*
X525275Y1171319D03*
X1332204D03*
X1326240Y811122D03*
X1501417Y1171319D03*
X1507381Y811122D03*
X1282913Y991220D03*
X306771D03*
X574566D03*
X350098Y811122D03*
X531240D03*
X356062Y1171319D03*
G54D80*
X723041Y-11500D03*
Y-21500D03*
X840001Y8500D03*
Y18500D03*
X980899Y-21500D03*
Y-11500D03*
Y8500D03*
Y18500D03*
X1032433Y-31511D03*
Y-21511D03*
Y-11511D03*
Y-1511D03*
X1290291Y-31511D03*
Y-21511D03*
Y-11511D03*
Y-1511D03*
X62813Y414300D03*
X47619Y417205D03*
X1386273Y270370D03*
X615573Y178034D03*
X628195Y174214D03*
X1282645Y253971D03*
X941059Y426211D03*
X901829Y514430D03*
X889439Y491299D03*
X1407029Y154432D03*
X922879Y530276D03*
X946727Y506252D03*
G54D95*
X1819208Y1420330D03*
X38346D03*
G54D83*
X19685Y-29134D03*
X1837795D03*
X1808192Y1569255D03*
X41870Y1511291D03*
X1812980Y502472D03*
X49280Y337402D03*
X441043Y1672205D03*
X1416437Y1672204D03*
X2081889Y1803261D03*
Y-29134D03*
G54D90*
X1057658Y204724D03*
X805690D03*
G54D98*
X763602Y605413D03*
X1739744D03*
X1094075Y605378D03*
X117933D03*
G54D103*
X841240Y1420330D03*
X1016240D03*
G54D87*
X1680327Y277236D03*
X1153555Y277208D03*
X704185Y277236D03*
X177413Y277208D03*
G54D85*
X177311Y1657953D03*
G54D86*
X1680232D03*
%LPC*%
G75*
G36*
G01X817460Y1718640D02*
X900700D01*
X907010Y1712330D01*
Y1667200D01*
G03X907376Y1666316I1251J0D01*
G01X917256Y1656436D01*
G03X918140Y1656070I884J885D01*
G01X1064370D01*
X1084474Y1635966D01*
G03X1085358Y1635600I884J885D01*
G01X1101560D01*
X1103140Y1634020D01*
Y1607480D01*
X1102240Y1606580D01*
X943698D01*
G03X942814Y1606214I0J-1251D01*
G01X935490Y1598890D01*
X927248D01*
G03X926364Y1598524I0J-1251D01*
G01X921156Y1593316D01*
G03X920790Y1592432I885J-884D01*
G01Y1578870D01*
X920730Y1578810D01*
X907390D01*
X907330Y1578870D01*
Y1592414D01*
G03X906964Y1593298I-1251J0D01*
G01X906522Y1593740D01*
Y1603900D01*
G03X906156Y1604784I-1251J0D01*
G01X898266Y1612674D01*
G03X897382Y1613040I-884J-885D01*
G01X888610D01*
G03X887726Y1612674I0J-1251D01*
G01X879888Y1604836D01*
G03X879522Y1603952I885J-884D01*
G01Y1593670D01*
X879176Y1593324D01*
G03X878810Y1592440I885J-884D01*
G01Y1578920D01*
X878710Y1578820D01*
X865410D01*
X865340Y1578890D01*
Y1592484D01*
G03X864974Y1593368I-1251J0D01*
G01X864622Y1593720D01*
Y1603382D01*
G03X864256Y1604266I-1251J0D01*
G01X856288Y1612234D01*
G03X855404Y1612600I-884J-885D01*
G01X845648D01*
G03X844764Y1612234I0J-1251D01*
G01X837846Y1605316D01*
G03X837480Y1604432I885J-884D01*
G01Y1593680D01*
X837146Y1593346D01*
G03X836780Y1592462I885J-884D01*
G01Y1578840D01*
X836760Y1578820D01*
X823390D01*
X823370Y1578840D01*
Y1592334D01*
G03X823004Y1593218I-1251J0D01*
G01X822622Y1593600D01*
Y1603560D01*
G03X822256Y1604444I-1251J0D01*
G01X814056Y1612644D01*
G03X813172Y1613010I-884J-885D01*
G01X803780D01*
G03X802896Y1612644I0J-1251D01*
G01X795888Y1605636D01*
G03X795522Y1604752I885J-884D01*
G01Y1593622D01*
X795156Y1593256D01*
G03X794790Y1592372I885J-884D01*
G01Y1578870D01*
X794740Y1578820D01*
X781390D01*
X781370Y1578840D01*
Y1592472D01*
G03X781004Y1593356I-1251J0D01*
G01X776356Y1598004D01*
G03X775472Y1598370I-884J-885D01*
G01X751458D01*
G03X750574Y1598004I0J-1251D01*
G01X745888Y1593317D01*
G03X745522Y1592433I885J-884D01*
G01Y1591251D01*
X745422Y1591151D01*
X744540D01*
G03X743656Y1590785I0J-1251D01*
G01X742956Y1590085D01*
G03X742590Y1589201I885J-884D01*
G01Y1578820D01*
X742522Y1578751D01*
X729122D01*
Y1600351D01*
X730056Y1601285D01*
G03X730360Y1601779I-884J885D01*
G03X730554Y1602518I-1308J738D01*
G03X730438Y1603098I-1502J1D01*
G01X730422Y1603135D01*
Y1607433D01*
G03X730056Y1608317I-1251J0D01*
G01X729622Y1608751D01*
Y1626114D01*
X759458Y1655950D01*
X777232D01*
G03X778116Y1656316I0J1251D01*
G01X812594Y1690794D01*
G03X812960Y1691678I-885J884D01*
G01Y1714140D01*
X817460Y1718640D01*
G37*
G36*
G01X1077918Y1601500D02*
G02X1078058Y1601442I-1J-200D01*
G01X1079940Y1599560D01*
G03X1080000Y1599504I882J885D01*
G01Y1565496D01*
G03X1079940Y1565440I822J-941D01*
G01X1079067Y1564567D01*
G03X1079004Y1564500I879J-889D01*
G01X945496D01*
G03X945440Y1564560I-941J-822D01*
G01X943567Y1566433D01*
X943566Y1566434D01*
G03X943500Y1566496I-888J-880D01*
G01Y1600504D01*
G03X943560Y1600560I-822J941D01*
G01X944440Y1601440D01*
G03X944496Y1601500I-885J882D01*
G01X1077918D01*
G37*
G36*
G01X1105930Y1598120D02*
X1106502Y1597548D01*
Y1565860D01*
X1105142Y1564500D01*
X1085200D01*
X1084200Y1565500D01*
Y1597750D01*
X1084580Y1598130D01*
X1094904D01*
X1094915Y1598129D01*
G03X1095062Y1598120I150J1241D01*
G01X1105930D01*
G37*
%LPD*%
G75*
G54D15*
X16925Y203366D03*
X17061Y196368D03*
X24720Y216362D03*
Y232362D03*
Y224362D03*
Y240362D03*
X16420Y420662D03*
X26500Y672862D03*
Y675862D03*
X27300Y764200D03*
X27520Y1245162D03*
X33500Y200862D03*
X33670Y192862D03*
Y208362D03*
X30795Y213358D03*
X33670Y232362D03*
X42500Y224409D03*
X30795Y227366D03*
X33670Y240362D03*
X40000Y298707D03*
X36000Y295952D03*
X40000Y293392D03*
X33105Y304972D03*
X35740Y363337D03*
X39320Y392269D03*
X40940Y387302D03*
X43020Y382942D03*
X41933Y395652D03*
X45960Y428806D03*
X38220Y589862D03*
Y592862D03*
X33020Y595232D03*
X32720Y598402D03*
X34790Y666595D03*
X31390D03*
X38470Y688122D03*
Y683122D03*
Y680622D03*
Y685622D03*
Y693122D03*
Y690622D03*
Y695622D03*
X34899Y711400D03*
X45700Y724100D03*
X45800Y726874D03*
X43841Y1248688D03*
X44833Y1656759D03*
X48269Y1672771D03*
X62020Y295952D03*
X62731Y305426D03*
X59322Y360702D03*
X51114Y360862D03*
X53406Y402862D03*
X49360Y428806D03*
X61171D03*
X47619Y418655D03*
X47618Y415613D03*
X48400Y586000D03*
X57595Y603476D03*
X59500Y738700D03*
X56777Y1314165D03*
X56799Y1520094D03*
Y1536094D03*
Y1540094D03*
Y1560094D03*
X59833Y1604359D03*
X54333Y1613359D03*
X50333D03*
X54478Y1663669D03*
X54535Y1658447D03*
X57833Y1671809D03*
X53333Y1671862D03*
X65000Y1681900D03*
X58325Y1679275D03*
X78269Y26474D03*
X74869D03*
X65937Y28403D03*
Y48720D03*
X77165Y278798D03*
Y295798D03*
Y286262D03*
Y303262D03*
X63429Y360702D03*
X67681D03*
X77220Y379022D03*
Y381522D03*
X68020Y395222D03*
X75516Y420319D03*
Y424319D03*
X64571Y428806D03*
X63540Y438802D03*
X72610Y441262D03*
Y444762D03*
X72981Y466385D03*
X77000Y485362D03*
X74550Y487812D03*
X80300Y641862D03*
X80241Y659011D03*
X80123Y664031D03*
X80135Y667933D03*
X74559Y667814D03*
X78080Y701832D03*
X63930Y739300D03*
X73759Y754726D03*
X68315Y765664D03*
X73759Y759246D03*
X72485Y1304152D03*
X75485D03*
X78485D03*
X72485Y1307152D03*
X75485D03*
X69485Y1304152D03*
Y1307152D03*
X65600Y1318588D03*
X65240Y1326068D03*
X75485Y1316152D03*
X72485Y1313152D03*
Y1310152D03*
X75485Y1313152D03*
Y1310152D03*
X69485D03*
X69809Y1333918D03*
Y1331418D03*
Y1336418D03*
X72809Y1333918D03*
Y1331418D03*
Y1336418D03*
X75809Y1333918D03*
Y1331418D03*
Y1336418D03*
X72909Y1339938D03*
X79009Y1340238D03*
X75909Y1339938D03*
X73027Y1347925D03*
X73059Y1345138D03*
X72987Y1342535D03*
X75909Y1342438D03*
X79009Y1342738D03*
Y1345238D03*
X78977Y1348025D03*
X75859Y1348138D03*
Y1345138D03*
X76369Y1507456D03*
X76680Y1530482D03*
X72774Y1546519D03*
X75922Y1558974D03*
Y1562374D03*
X77618Y1572504D03*
X74218D03*
X77040Y1601102D03*
X65120Y1609909D03*
X65520Y1615972D03*
X74100Y1613300D03*
X77833Y1678902D03*
X73833Y1674252D03*
X69833Y1678582D03*
X85374Y19538D03*
X81974D03*
X92442Y26474D03*
X89042D03*
X87620Y285321D03*
X87845Y278798D03*
Y295798D03*
X87820Y302821D03*
X87520Y395865D03*
Y391391D03*
Y382219D03*
X85826Y428319D03*
X84410Y438519D03*
X83320Y445212D03*
X94439Y450081D03*
X81505Y447377D03*
X79400Y482862D03*
X91027Y643276D03*
X89859Y628246D03*
X86459D03*
X82961Y657111D03*
X95725Y654540D03*
X95860Y659622D03*
X83165Y652564D03*
X91078Y649584D03*
X83208Y646436D03*
X83250Y665428D03*
X84470Y668702D03*
X86433Y688160D03*
X81285Y689804D03*
X84035Y697604D03*
X93547Y692260D03*
X83004Y705141D03*
X97295Y699786D03*
X85095Y722164D03*
X95849Y716358D03*
X91610Y721414D03*
X82357Y737803D03*
X84623Y741249D03*
X81966Y759246D03*
X85877Y759275D03*
X93485Y1304152D03*
X87485D03*
X90485D03*
X93485Y1307152D03*
X84485Y1304152D03*
X81485D03*
X93485Y1318152D03*
Y1315652D03*
Y1310152D03*
Y1313152D03*
X94209Y1337738D03*
X81809Y1340238D03*
X84809D03*
X87809D03*
X90809D03*
X94209D03*
X84809Y1345238D03*
X81809Y1342738D03*
X84809D03*
X81809Y1348238D03*
Y1345238D03*
X84809Y1348238D03*
X87809D03*
Y1345238D03*
Y1342738D03*
X94209D03*
Y1348238D03*
Y1345238D03*
X90809Y1348238D03*
Y1345238D03*
Y1342738D03*
X88520Y1484482D03*
Y1491482D03*
Y1487982D03*
Y1494982D03*
X89264Y1507611D03*
X92664D03*
X79769Y1507456D03*
X87500Y1567069D03*
X91500D03*
X90713Y1581852D03*
Y1597867D03*
X81008Y1589872D03*
X90788Y1615821D03*
Y1601867D03*
X81900Y1613300D03*
X85800D03*
X90698Y1630362D03*
X90788Y1619821D03*
X90698Y1642362D03*
X90407Y1656672D03*
X88333Y1661334D03*
X81833Y1674526D03*
X86245Y1694362D03*
X96420Y1693803D03*
X86030Y1683092D03*
X99547Y19538D03*
X110320D03*
X96147D03*
X106615Y26474D03*
X103215D03*
X113490Y216596D03*
X113400Y232128D03*
X110937Y285495D03*
Y302854D03*
X107200Y393562D03*
X107301Y388071D03*
X107419Y487807D03*
X104875Y490980D03*
X102384Y505374D03*
X112480Y507792D03*
X110689Y498271D03*
X110464Y505374D03*
X101983Y518100D03*
X99880Y526300D03*
X110060Y515279D03*
X99773Y515606D03*
X105587Y520727D03*
X106110Y633732D03*
X107489Y630917D03*
X110374Y630879D03*
X102269Y634466D03*
X107045Y661917D03*
X99021Y663732D03*
X103397Y667272D03*
X102120Y688650D03*
X102060Y692100D03*
X102420Y697262D03*
X96626Y736187D03*
X110527Y758869D03*
X108465Y1304292D03*
Y1307292D03*
X105475Y1304222D03*
Y1307222D03*
X102485Y1304152D03*
X99485D03*
X96485D03*
X102485Y1307152D03*
X99485D03*
X96485D03*
X108465Y1318292D03*
Y1310292D03*
Y1313292D03*
Y1315792D03*
X105475Y1318222D03*
Y1310222D03*
Y1313222D03*
Y1315722D03*
X99485Y1318152D03*
X96485D03*
Y1315652D03*
Y1310152D03*
Y1313152D03*
X99485Y1310152D03*
Y1313152D03*
Y1315652D03*
X102485Y1318152D03*
Y1310152D03*
Y1313152D03*
Y1315652D03*
X96809Y1340238D03*
Y1345238D03*
Y1348238D03*
Y1342738D03*
X112270Y1518907D03*
X99274Y1529169D03*
X96570Y1546187D03*
X99750Y1565378D03*
Y1561978D03*
X103902Y1584337D03*
X102251Y1576504D03*
X105651D03*
X104318Y1589352D03*
X100620Y1596367D03*
X101500Y1604400D03*
X100020Y1615821D03*
X98738Y1605867D03*
X104400Y1632385D03*
X104430Y1628012D03*
X104318Y1637862D03*
X99600Y1668332D03*
X99645Y1663217D03*
X99980Y1687921D03*
Y1698921D03*
X113720Y19538D03*
X127894D03*
X124494D03*
X120789Y26474D03*
X117389D03*
X115850Y186362D03*
X122000Y207362D03*
X116920Y207462D03*
X118920Y278875D03*
X119220Y306236D03*
X119920Y379362D03*
X119457Y392071D03*
Y388071D03*
X125070Y486736D03*
X125013Y491829D03*
X124124Y495883D03*
X116171Y485041D03*
X112483Y510637D03*
X116411Y497707D03*
X118652Y528860D03*
X129762Y531942D03*
X115793Y528188D03*
X112393D03*
X111920Y632922D03*
X114540Y633032D03*
X117750Y633232D03*
X120440Y633347D03*
X121400Y638062D03*
X125890Y644163D03*
X122329Y654660D03*
X122280Y651934D03*
X124431Y649570D03*
X122575Y671930D03*
X118019Y661371D03*
X124737Y735726D03*
X118737D03*
X121737D03*
Y738726D03*
X118737D03*
X124737D03*
X123220Y1324662D03*
X120220D03*
X112749Y1532594D03*
Y1528594D03*
Y1552594D03*
Y1556594D03*
X117707Y1553759D03*
X125033Y1589352D03*
X116798D03*
X123230Y1597350D03*
X119500Y1622380D03*
X124795Y1681846D03*
X128195Y1674362D03*
X114645Y1698862D03*
X117220Y1683437D03*
X127195Y1696362D03*
Y1700362D03*
Y1704362D03*
X125082Y1727092D03*
X123394Y1723472D03*
X117426Y1726622D03*
X125720Y1719262D03*
X141520Y181462D03*
X139720Y179162D03*
X143470Y184012D03*
X133590Y212382D03*
X129394Y278875D03*
X129375Y274800D03*
X129394Y306236D03*
X135220Y397071D03*
X132490Y420062D03*
X138042Y480238D03*
X132833D03*
X136982Y497090D03*
X131737Y496295D03*
X135006Y487753D03*
X131295Y487822D03*
X141325Y503806D03*
X141462Y507600D03*
X141329Y510487D03*
X141220Y498810D03*
X138878Y512550D03*
X138408Y507366D03*
X139153Y516453D03*
X133160Y532002D03*
X132600Y537072D03*
Y540472D03*
X133467Y634531D03*
X131740Y640103D03*
X131600Y646861D03*
X131330Y665740D03*
X142960Y690807D03*
X140460D03*
X142754Y698811D03*
X140254D03*
X142778Y706835D03*
X140278D03*
X140326Y721660D03*
X142826D03*
X140142Y1392545D03*
Y1396275D03*
X129627Y1556360D03*
X129586Y1553759D03*
X129813Y1604367D03*
X130533Y1622321D03*
X129533Y1637862D03*
X137420Y1708362D03*
X144520Y1717562D03*
X141642Y1717592D03*
X134557Y1722778D03*
X137852Y1726572D03*
X160360Y19538D03*
X156655Y26474D03*
X153255D03*
X147924Y28258D03*
X148784Y48720D03*
X145720Y186462D03*
Y202862D03*
Y206362D03*
X156670Y344542D03*
X159170D03*
X154220Y375682D03*
X158110Y376172D03*
X160090Y391170D03*
Y397470D03*
X152826Y439397D03*
Y434362D03*
X156306Y449045D03*
X153360Y449112D03*
X149557Y494353D03*
X150113Y488487D03*
X161267Y503143D03*
X149472Y506810D03*
X160000Y510052D03*
X152470Y495383D03*
X151378Y526924D03*
X149512Y514810D03*
X150800Y512021D03*
X153737Y514893D03*
X149504Y519881D03*
X154647Y521783D03*
X150877Y757969D03*
X151277Y1339183D03*
X153877D03*
X156477D03*
X156417Y1336343D03*
X151217Y1336393D03*
X153817D03*
X156417Y1333843D03*
X151217Y1333893D03*
X153817D03*
X151277Y1346883D03*
X153877D03*
X151277Y1349383D03*
X153877D03*
X156477Y1346883D03*
Y1349383D03*
Y1344383D03*
X151277D03*
X153877D03*
X156477Y1341883D03*
X151277D03*
X153877D03*
X147307Y1404745D03*
X149568Y1395145D03*
Y1397695D03*
X152684Y1403451D03*
X157490Y1421454D03*
X154990D03*
X159858Y1409361D03*
X155858Y1406669D03*
Y1409390D03*
X157530Y1432124D03*
X155030D03*
X157530Y1424124D03*
X155030D03*
X157530Y1429124D03*
X155030Y1426624D03*
Y1429124D03*
X157530Y1426624D03*
Y1435124D03*
X155030D03*
X157530Y1437754D03*
X155030D03*
X146390Y1504240D03*
X145538Y1517374D03*
X148938D03*
X153600Y1505600D03*
X147067Y1545985D03*
X157441Y1581932D03*
X146312Y1569525D03*
X149712D03*
X152026Y1614138D03*
X158335Y1614452D03*
X155180Y1619872D03*
X156070Y1695702D03*
X145745Y1712362D03*
X161310Y1708022D03*
X148145Y1701862D03*
X155145Y1713517D03*
X163760Y19538D03*
X174533D03*
X170828Y26474D03*
X167428D03*
X164830Y344542D03*
X161670D03*
X173275Y393497D03*
X164000Y415362D03*
X163926Y425383D03*
X164000Y420362D03*
X172507Y417205D03*
X163926Y430883D03*
Y443319D03*
Y439397D03*
Y435383D03*
X178546Y453806D03*
X172632Y454095D03*
X165176Y500782D03*
X176393Y575189D03*
X173793D03*
X176393Y572689D03*
X173793D03*
X171293D03*
Y575189D03*
X173793Y577790D03*
X171293D03*
X176393D03*
X176651Y596883D03*
Y594163D03*
X173878Y597027D03*
Y594307D03*
X176651Y599603D03*
X173878Y599747D03*
X161126Y721660D03*
X161078Y706835D03*
X163626Y721660D03*
X163578Y706835D03*
X170877Y1333783D03*
Y1336383D03*
X176077Y1333783D03*
X173477D03*
X176077Y1336383D03*
X173477D03*
X170907Y1339233D03*
X176107D03*
X173507D03*
X170877Y1341883D03*
X176077D03*
X173477D03*
Y1349383D03*
Y1346883D03*
Y1344383D03*
X176077D03*
Y1346883D03*
Y1349383D03*
X170877D03*
Y1346883D03*
Y1344383D03*
X176358Y1403669D03*
X176258Y1400669D03*
X173892Y1402749D03*
Y1405649D03*
X170922Y1399255D03*
X166262D03*
X173252Y1400005D03*
X168592D03*
X160490Y1421454D03*
X164000Y1408862D03*
X162257Y1406594D03*
X160530Y1432124D03*
Y1424124D03*
Y1429124D03*
Y1426624D03*
Y1435124D03*
Y1437754D03*
X165500Y1440362D03*
X173727Y1452134D03*
Y1448734D03*
X170570Y1509250D03*
X164710Y1518014D03*
X168110D03*
X173331Y1579399D03*
X167266Y1569968D03*
X170666D03*
X172099Y1588141D03*
X164920Y1712017D03*
X163060Y1717017D03*
X178226Y1726517D03*
X172962Y1721234D03*
X169777Y1726517D03*
X178142Y1720652D03*
X177933Y19538D03*
X186120Y24162D03*
X188620D03*
X190880Y383012D03*
Y387162D03*
Y391082D03*
X178375Y396571D03*
X181845Y401071D03*
X187371Y425383D03*
X187532Y421387D03*
X187371Y430883D03*
Y443383D03*
X180740Y437562D03*
X184550Y435712D03*
X187371Y440742D03*
X194440Y433895D03*
Y439565D03*
X187371Y447172D03*
X177871D03*
X181994Y453932D03*
X180640Y447172D03*
X185211Y453942D03*
X185191Y502439D03*
X186793Y575189D03*
X184193D03*
X186793Y572689D03*
X184193D03*
X181593Y575189D03*
X178993D03*
X181593Y572689D03*
X178993D03*
X189293Y575189D03*
X186793Y577790D03*
X184193D03*
X189293D03*
X181593D03*
X178993D03*
X181651Y596883D03*
X179151D03*
X186796Y594195D03*
Y596915D03*
X184151Y596883D03*
X179151Y594163D03*
X181651D03*
X184151D03*
X181651Y599603D03*
X179151D03*
X186796Y599635D03*
X184151Y599603D03*
X186720Y737862D03*
X180720D03*
X183720D03*
Y734862D03*
X180720D03*
X186720D03*
X185835Y757057D03*
X188978Y756855D03*
X191602Y756839D03*
X189377Y1333783D03*
X191977D03*
X189377Y1336383D03*
X191977D03*
X191947Y1339263D03*
X189347D03*
X189377Y1349383D03*
X191977D03*
X189377Y1346883D03*
X191977D03*
Y1344383D03*
X189377D03*
X191977Y1341883D03*
X189377D03*
X187711Y1395170D03*
Y1397670D03*
X190827Y1403451D03*
X180977Y1396173D03*
X178458Y1399269D03*
Y1402169D03*
Y1405069D03*
X188211Y1406691D03*
X186165Y1422589D03*
X183135Y1419784D03*
X180510Y1420258D03*
X177510D03*
X186135Y1419784D03*
X183165Y1422589D03*
X177510Y1423278D03*
X180510D03*
X183075Y1430424D03*
Y1425424D03*
Y1427924D03*
X186075Y1430424D03*
Y1425424D03*
Y1427924D03*
X183075Y1432924D03*
X186075D03*
X192600Y1557360D03*
X185895Y1557875D03*
X189600Y1566300D03*
X187400Y1568132D03*
X187542Y1729092D03*
X193293Y1722197D03*
X188794Y1725092D03*
X207894Y19538D03*
X204494D03*
X200789Y26474D03*
X197389D03*
X195050Y412055D03*
X199149Y425755D03*
Y420255D03*
Y414755D03*
X204699Y423242D03*
Y428742D03*
X195050Y417465D03*
X199149Y436755D03*
Y442255D03*
Y431255D03*
Y453255D03*
Y447755D03*
X197650Y455712D03*
X199149Y468255D03*
X208200Y493510D03*
X202338Y568746D03*
X201392Y574271D03*
X198336D03*
X204610Y571097D03*
X199164Y582481D03*
X200654Y578271D03*
X201622Y581009D03*
X208056Y591665D03*
X208806Y589335D03*
X208056Y587005D03*
X208806Y584675D03*
X202262Y592305D03*
X205162D03*
X202338Y602746D03*
X201392Y608271D03*
X198336D03*
X203892Y594471D03*
X202492Y596571D03*
X208292D03*
X206892Y594371D03*
X205392Y596571D03*
X204610Y605097D03*
X199164Y616481D03*
X200654Y612271D03*
X201622Y615009D03*
X208806Y618675D03*
X208056Y621005D03*
X208806Y623335D03*
X202338Y636746D03*
X208056Y625665D03*
X203892Y628471D03*
X202492Y630571D03*
X202262Y626305D03*
X208292Y630571D03*
X206892Y628371D03*
X205162Y626305D03*
X205392Y630571D03*
X204610Y639097D03*
X201392Y642271D03*
X199164Y650481D03*
X200654Y646271D03*
X201622Y649009D03*
X198336Y642271D03*
X208056Y655005D03*
X208806Y657335D03*
Y652675D03*
X207620Y671262D03*
X198420Y672662D03*
X198495Y669487D03*
X208056Y659665D03*
X205392Y664571D03*
X205162Y660305D03*
X206892Y662371D03*
X202262Y660305D03*
X202492Y664571D03*
X203892Y662471D03*
X208292Y664571D03*
X196049Y678195D03*
X194196Y687061D03*
X200018Y677492D03*
X193332Y678195D03*
X207129Y690027D03*
X203199Y690006D03*
X197086Y686326D03*
X203179Y693626D03*
X207140Y693636D03*
X195735Y696469D03*
X198235Y698969D03*
Y696469D03*
X200735Y698969D03*
Y696469D03*
X207140Y738462D03*
X205220Y736562D03*
X201220Y736662D03*
X203660Y731802D03*
X195602Y756839D03*
X203602Y756855D03*
X208977Y1336383D03*
Y1333783D03*
X194577D03*
Y1336383D03*
X209007Y1339263D03*
X194547D03*
X208977Y1341883D03*
X194577Y1349383D03*
Y1346883D03*
Y1344383D03*
X208977D03*
Y1346883D03*
Y1349383D03*
X194577Y1341883D03*
X206735Y1400005D03*
X209065Y1399255D03*
X204405D03*
X198001Y1409361D03*
X193941Y1407029D03*
X200797Y1409605D03*
X200492Y1406686D03*
X193941Y1409750D03*
X195966Y1542863D03*
X203120Y1624782D03*
X208115Y1624217D03*
X195590Y1714517D03*
X196010Y1709017D03*
X208295Y1703362D03*
X199050Y1726431D03*
X204600Y1733022D03*
X222067Y19538D03*
X218667D03*
X214962Y26474D03*
X211562D03*
X225407Y321831D03*
X209530Y426192D03*
X217770Y428262D03*
X224210Y431501D03*
X224305Y422977D03*
X219995Y426267D03*
X224210Y436619D03*
X218140Y440735D03*
X218010Y432735D03*
X223664Y443125D03*
X220000Y448735D03*
X212891Y566632D03*
X210391Y567981D03*
X212891Y601981D03*
X210391D03*
Y635981D03*
X212891D03*
X210320Y671262D03*
X224900Y713293D03*
X209720Y731862D03*
X220033Y756844D03*
X211602Y756855D03*
X216842Y756865D03*
X214177Y1336383D03*
X211577D03*
X214177Y1333783D03*
X211577D03*
X214207Y1339263D03*
X211607D03*
X214177Y1341883D03*
X211577D03*
X214177Y1349383D03*
Y1346883D03*
Y1344383D03*
X211577D03*
Y1346883D03*
Y1349383D03*
X211395Y1400005D03*
X214201Y1404169D03*
X212035Y1402899D03*
X214101Y1401169D03*
X216554Y1399264D03*
Y1402164D03*
Y1405064D03*
X212035Y1405799D03*
X219587Y1435402D03*
X217469Y1454725D03*
X219587Y1443402D03*
Y1439402D03*
X220869Y1454725D03*
X209820Y1631142D03*
X210593Y1714017D03*
X212120Y1703062D03*
X214120Y1713462D03*
X233339Y17662D03*
X235701Y21582D03*
X241310Y20322D03*
X229135Y26474D03*
X225735D03*
X238063Y26232D03*
X235701Y39570D03*
X229131Y50646D03*
X225731D03*
X239820Y54362D03*
X239720Y71862D03*
X239010Y78542D03*
X238297Y129703D03*
X234902Y174047D03*
X226800Y359464D03*
X230359Y461683D03*
X227430Y719772D03*
X238940Y716652D03*
X230864Y1254295D03*
X246510Y20362D03*
X242220Y39362D03*
X246220D03*
X250220D03*
X254050Y39422D03*
X246360Y26852D03*
X248820Y48962D03*
X252320D03*
X255820D03*
X257520Y51562D03*
X254020D03*
X250520D03*
X249885Y69623D03*
X245220Y67862D03*
X248097Y92143D03*
X247897Y100543D03*
X244822Y115543D03*
Y111543D03*
X253910Y115722D03*
X253878Y111771D03*
X243892Y140912D03*
X259933Y141122D03*
X257256Y156727D03*
X245490Y159702D03*
X252000Y395400D03*
X255810Y405582D03*
X252500Y415862D03*
X258066Y426735D03*
X256695Y461117D03*
X257750Y450842D03*
X254713Y518465D03*
X245700Y513262D03*
X250100Y521783D03*
X256885Y574805D03*
X254385D03*
X256855Y571995D03*
X251885Y574805D03*
X249800Y563262D03*
X254355Y589235D03*
X256855D03*
X251855D03*
X256855Y605995D03*
X251885Y608805D03*
X257643Y594220D03*
X255043D03*
Y596820D03*
X257643D03*
X256885Y608805D03*
X254385D03*
X256855Y603495D03*
X251855Y623265D03*
X254355D03*
X256855D03*
Y639995D03*
Y637495D03*
X257643Y628220D03*
X255043D03*
Y630820D03*
X257643D03*
X256885Y642805D03*
X254385D03*
X251855Y657265D03*
X251885Y642805D03*
X254355Y657265D03*
X256855D03*
X257643Y662220D03*
X255043D03*
Y664820D03*
X257643D03*
X253819Y675567D03*
X253849Y678077D03*
X256419Y675567D03*
X256449Y678077D03*
X251219Y675567D03*
X251249Y678077D03*
X248649D03*
X248989Y698827D03*
X249019Y693767D03*
X251589Y698827D03*
X251649Y696277D03*
X254189Y698827D03*
X251619Y693767D03*
X256849Y696277D03*
X256789Y698827D03*
X256819Y693767D03*
X254249Y696277D03*
X254219Y693767D03*
X248300Y703862D03*
X242460Y716652D03*
X253057Y755345D03*
X245487Y755435D03*
X259510Y757822D03*
X251187Y1255025D03*
X263240Y38122D03*
X266990Y41832D03*
X275120Y28562D03*
X275900Y48872D03*
X259320Y48962D03*
X261020Y51562D03*
X263520D03*
X261820Y48962D03*
X264740Y49182D03*
X266497Y69536D03*
Y72036D03*
X264720Y56362D03*
Y60362D03*
Y64362D03*
X266597Y77526D03*
Y80026D03*
X263320Y87662D03*
X261420Y100662D03*
X264920D03*
X268420D03*
X262920Y97962D03*
X266420D03*
X269920D03*
X273620Y96662D03*
X263550Y120922D03*
X269191Y121092D03*
X275797Y120245D03*
X265910Y125492D03*
X266975Y140107D03*
X260600Y151062D03*
X272800Y140162D03*
X264578Y151203D03*
X260100Y159562D03*
X265500Y227862D03*
X263000D03*
X260500Y227362D03*
Y224862D03*
X270240Y245332D03*
X271821Y251962D03*
X267759D03*
X259224Y419532D03*
X263430Y422235D03*
X259869Y431039D03*
X262963Y443735D03*
X272500Y447735D03*
X263040Y448752D03*
X272500Y452862D03*
X264055Y574505D03*
X264025Y571995D03*
X261555Y574505D03*
X261525Y571995D03*
X264055Y566935D03*
X263995Y569485D03*
X261495D03*
X261555Y566935D03*
X266555Y574505D03*
X266525Y571995D03*
X266495Y569485D03*
X266555Y566935D03*
X269055Y574505D03*
X269025Y571995D03*
X268995Y569485D03*
X269055Y566935D03*
X261465Y592115D03*
X261525Y589565D03*
X264025D03*
X263965Y592115D03*
X266525Y589565D03*
X266465Y592115D03*
X269025Y589565D03*
X268965Y592115D03*
X264025Y605995D03*
X261525D03*
X264055Y608505D03*
X261555D03*
X261435Y597175D03*
X261495Y594625D03*
X263995D03*
X263935Y597175D03*
X266525Y605995D03*
X266555Y608505D03*
X266435Y597175D03*
X266495Y594625D03*
X261525Y603495D03*
X264025D03*
X266525D03*
X269025Y605995D03*
X269055Y608505D03*
X268935Y597175D03*
X268995Y594625D03*
X269025Y603495D03*
X261495Y621055D03*
X263995D03*
X261525Y623565D03*
X264025D03*
X263995Y611055D03*
X261495D03*
X266495Y621055D03*
X266525Y623565D03*
X266495Y611055D03*
X268995Y621055D03*
X269025Y623565D03*
X268995Y611055D03*
X261525Y639995D03*
X264025D03*
X261525Y637495D03*
X266525Y639995D03*
X269025D03*
X264025Y637495D03*
X266525D03*
X269025D03*
X263965Y626115D03*
X261465D03*
X266465D03*
X268965D03*
X261495Y655055D03*
X263995D03*
X261525Y657565D03*
X264025D03*
X263995Y645055D03*
X264055Y642505D03*
X261495Y645055D03*
X261555Y642505D03*
X266495Y655055D03*
X266525Y657565D03*
X266495Y645055D03*
X266555Y642505D03*
X268995Y655055D03*
X269025Y657565D03*
X268995Y645055D03*
X269055Y642505D03*
X261465Y660115D03*
X263965D03*
X266465D03*
X268965D03*
X259049Y678077D03*
X259019Y675567D03*
X259419Y693767D03*
X259389Y698827D03*
X259449Y696277D03*
X269600Y715792D03*
X274247Y727165D03*
X268331Y738029D03*
X273046Y735662D03*
X270100Y727262D03*
X264000Y726262D03*
X266700Y730962D03*
X271570Y746422D03*
X265997Y747535D03*
X272208Y768516D03*
X271057Y765525D03*
Y762425D03*
X287000Y20862D03*
X284233Y26474D03*
X280833D03*
X290799Y28362D03*
X284230Y50646D03*
X280830D03*
X289400Y54222D03*
X285357Y105003D03*
X288557D03*
X280857Y107303D03*
X285857Y115603D03*
X282857D03*
X280857Y109903D03*
X275797Y129592D03*
X287000Y139862D03*
X283053Y139728D03*
X276825Y140462D03*
X290685Y165447D03*
X286481Y251962D03*
X281077D03*
X276491D03*
X289274Y290662D03*
X284515D03*
X276500Y444862D03*
X274850Y442562D03*
X279500Y455362D03*
X277578Y509039D03*
X284482Y566022D03*
X286582Y637809D03*
Y634283D03*
X284287Y716015D03*
X277046Y725709D03*
Y735442D03*
X284358Y732562D03*
X283350Y728483D03*
X289137Y735275D03*
X279507Y727025D03*
X285046Y737964D03*
X281046Y737938D03*
X275210Y738102D03*
X287607Y754962D03*
X277046Y746702D03*
X281046D03*
X285046D03*
X299500Y22862D03*
X295520Y12762D03*
X302610Y26362D03*
X292060Y24472D03*
X295520Y26362D03*
X300248Y28362D03*
X304927Y24654D03*
X304972Y28362D03*
X302720Y38182D03*
X292590Y53982D03*
X293161Y50522D03*
X306570Y50222D03*
X290720Y40017D03*
X294720D03*
X295524Y52092D03*
X301310Y52482D03*
X298550Y51602D03*
X303715Y50857D03*
X292942Y71499D03*
X305747Y64013D03*
Y61113D03*
X305247Y71567D03*
X301600Y82457D03*
X302310Y75673D03*
X295357Y88903D03*
X307820Y95724D03*
X301183Y107103D03*
Y110003D03*
Y112803D03*
X296478Y149203D03*
X296800Y139762D03*
X306000Y165662D03*
X295685Y165447D03*
X296478Y158703D03*
X306730Y173842D03*
X304651Y251962D03*
X291759D03*
X306736Y290662D03*
X302765D03*
X298184D03*
X293763D03*
X298587Y508074D03*
X300520Y552262D03*
X307987Y577658D03*
X293805Y569397D03*
Y565997D03*
X298000Y587890D03*
X308417Y585158D03*
X308447Y592255D03*
X306144Y602225D03*
X305612Y622530D03*
Y625030D03*
Y627530D03*
X296405Y630732D03*
Y634132D03*
X295962Y679374D03*
X294679Y688446D03*
Y685046D03*
X291600Y705162D03*
X298273Y715400D03*
X297087Y721249D03*
X304602Y727968D03*
X293027Y755985D03*
X303647Y1307981D03*
X303723Y1353316D03*
Y1355853D03*
X304051Y1365453D03*
X306667Y1361597D03*
X302805Y1379941D03*
Y1376541D03*
X296170Y1622852D03*
X310400Y50362D03*
X314657Y71803D03*
Y68903D03*
X323040Y73122D03*
X323117Y81168D03*
Y76938D03*
X322875Y84318D03*
X316364Y89212D03*
X310459Y75892D03*
X320430Y78002D03*
X313357Y89503D03*
X313457Y96803D03*
X311057Y107103D03*
Y110003D03*
Y112803D03*
X308175Y144202D03*
X308500Y165662D03*
X311200Y165562D03*
X309230Y173842D03*
X309756Y177449D03*
Y181449D03*
X310970Y195362D03*
X308790Y197622D03*
X320270Y200462D03*
X319370Y214492D03*
X316370D03*
X319370Y217492D03*
X316370D03*
X323314Y210645D03*
X306910Y228162D03*
X309910D03*
X306910Y225162D03*
X309910D03*
X322658Y229254D03*
X319718Y223750D03*
X317981Y237724D03*
X320940Y238372D03*
X317129Y251962D03*
X316463Y290662D03*
X316444Y559125D03*
X317860Y572322D03*
X319520Y577658D03*
X312007Y588675D03*
X319520Y582658D03*
X316127Y592785D03*
X318560Y587632D03*
X321276Y599298D03*
X317386Y623207D03*
X308605Y629525D03*
Y627025D03*
X319557Y736225D03*
X317967Y746985D03*
Y771875D03*
X320578Y1290197D03*
X323028Y1297967D03*
X320428D03*
Y1295467D03*
X323028D03*
Y1292967D03*
X320428D03*
X320245Y1357401D03*
X313841Y1365553D03*
X309841Y1364815D03*
X318051Y1367043D03*
X316579Y1364585D03*
X309841Y1367871D03*
X322575Y1358151D03*
X332500Y150738D03*
X326216Y138787D03*
X326900Y162287D03*
X323420Y207549D03*
X326168Y207580D03*
X334485Y216809D03*
X337000Y216862D03*
X335575Y214170D03*
X328588Y209677D03*
X334500Y219362D03*
X337000D03*
X328939Y229139D03*
X335385Y235309D03*
X335412Y222176D03*
X329648Y252202D03*
X341295Y290239D03*
X329002Y290662D03*
X330674Y365702D03*
X328167Y379073D03*
X336270Y402992D03*
X329050Y607402D03*
X331339Y709313D03*
X328120Y710862D03*
X335677Y715215D03*
X327107Y732665D03*
X335467Y725335D03*
X338097Y736235D03*
X335126Y728323D03*
X327096Y736005D03*
X336446Y746486D03*
X338667Y772452D03*
X341527Y778362D03*
X339148Y1269717D03*
X339088Y1272287D03*
X339028Y1274887D03*
X325688Y1290167D03*
X325718Y1287587D03*
X328078Y1288747D03*
X323178Y1290197D03*
X323208Y1287617D03*
X328168Y1280967D03*
X325748Y1284987D03*
X328108Y1286147D03*
X328138Y1283567D03*
X328018Y1291317D03*
X339035Y1280218D03*
X339040Y1277594D03*
X328065Y1299248D03*
X325538Y1297937D03*
Y1292937D03*
Y1295437D03*
X328058Y1293917D03*
X328070Y1296624D03*
X335679Y1330518D03*
X334973Y1333353D03*
X338795Y1338799D03*
X336179Y1342753D03*
X324905Y1357401D03*
X327235Y1358151D03*
X332475Y1357945D03*
X327875Y1363945D03*
Y1361045D03*
X330041Y1362315D03*
X329941Y1359315D03*
X332475Y1363345D03*
Y1360445D03*
X340440Y120552D03*
X343450Y131167D03*
X342700Y139662D03*
X355189Y144267D03*
X351100Y150412D03*
X348100Y185162D03*
X345600Y188162D03*
X356295Y219362D03*
X353145D03*
X342000Y252612D03*
X354672Y252693D03*
X354145Y290591D03*
X345411Y364702D03*
Y376923D03*
X343354Y391643D03*
X347340Y407462D03*
X348880Y703442D03*
X354100Y720743D03*
X352879Y728657D03*
X348037Y728735D03*
X348730Y735098D03*
Y731698D03*
X344264Y1272455D03*
X341754Y1272485D03*
X344252Y1269948D03*
X341742Y1269978D03*
X344258Y1267117D03*
X341748Y1267147D03*
X341754Y1274985D03*
X344264Y1274955D03*
X355036Y1272433D03*
Y1269933D03*
X355378Y1262027D03*
X355318Y1264597D03*
X355258Y1267197D03*
X355036Y1274933D03*
X341605Y1280248D03*
X344115Y1280218D03*
X344264Y1277455D03*
X341754Y1277485D03*
X355048Y1277440D03*
X355025Y1280248D03*
X352373Y1334603D03*
X354703Y1335353D03*
X345969Y1342755D03*
X341969Y1342017D03*
X350179Y1344245D03*
X348707Y1341787D03*
X341969Y1345073D03*
X354850Y1371908D03*
X351850D03*
X349260Y1373418D03*
X351850Y1375408D03*
X354850D03*
X351850Y1378408D03*
X354850D03*
X351850Y1381408D03*
X354850D03*
X349260Y1376918D03*
Y1379918D03*
X349636Y1399601D03*
X352713Y1399336D03*
X355513Y1402306D03*
X352513D03*
X349513D03*
X355325Y1405386D03*
X349463Y1405286D03*
X352463D03*
X355325Y1408386D03*
X346426Y1414401D03*
X352401Y1414432D03*
X355325Y1414386D03*
Y1417386D03*
X352401Y1411432D03*
X355325Y1411386D03*
X352401Y1408432D03*
X349123Y1411376D03*
X349323Y1408406D03*
X349073Y1414356D03*
X346256Y1417301D03*
X352231Y1417332D03*
X348903Y1417256D03*
X363625Y127662D03*
X361800Y122522D03*
X366060Y133912D03*
X363525Y158702D03*
X361190Y210762D03*
X357303Y213159D03*
X371551Y224862D03*
X367306Y252811D03*
X366498Y290264D03*
X357660Y318850D03*
X364014Y366391D03*
Y378649D03*
X364179Y392037D03*
X370200Y409582D03*
X373720Y431362D03*
X365720Y440562D03*
X365771Y449480D03*
X359669Y686744D03*
X359639Y690114D03*
X360470Y705965D03*
X363101Y697348D03*
Y693948D03*
X360990Y726862D03*
X358902Y736225D03*
X355946Y728800D03*
X359790Y729835D03*
X358902Y739755D03*
Y743035D03*
Y754945D03*
Y746405D03*
Y773352D03*
X371578Y1248967D03*
X371458Y1254137D03*
X371330Y1256687D03*
X371518Y1251537D03*
X371278Y1259257D03*
X360198Y1269777D03*
X357546Y1272403D03*
Y1269903D03*
X360138Y1272347D03*
X357828Y1264567D03*
X357888Y1261997D03*
X360378Y1264627D03*
X360438Y1262057D03*
X357768Y1267167D03*
X360318Y1267227D03*
X357546Y1274903D03*
X360128Y1274957D03*
X371218Y1261857D03*
X371225Y1267188D03*
X371230Y1264564D03*
X357558Y1277410D03*
X357535Y1280218D03*
X360120Y1277654D03*
X367694Y1317092D03*
X367807Y1319592D03*
X368391Y1328161D03*
X370923Y1325373D03*
X357033Y1334603D03*
X359363Y1335353D03*
X362147Y1336553D03*
X360003Y1338247D03*
X364269Y1338017D03*
X364073Y1334903D03*
X360003Y1341147D03*
X362147Y1339653D03*
X364347Y1340853D03*
X364647Y1371990D03*
X361647D03*
X358647D03*
X367647D03*
X370552Y1372073D03*
X364647Y1375490D03*
X361647D03*
X358647D03*
Y1378490D03*
X370552Y1375573D03*
X367647Y1375490D03*
X355713Y1399336D03*
X361703Y1399386D03*
X364703D03*
X367703D03*
X370703D03*
X358703Y1402386D03*
X361703D03*
X364703D03*
X367703D03*
X370703D03*
X358713Y1399336D03*
X358573Y1405336D03*
X361573D03*
X364573D03*
X367573D03*
X370573D03*
X358703Y1414606D03*
X361703D03*
X364703D03*
X361703Y1417386D03*
X358703D03*
X364703D03*
X367703D03*
Y1414606D03*
X358217Y1411405D03*
X370517Y1414615D03*
X370717Y1417405D03*
X357917Y1408205D03*
X367948Y1531529D03*
X371850Y1534062D03*
X368600Y1543200D03*
X367140Y1645390D03*
X366700Y1649000D03*
X370500Y1654362D03*
X370635Y1675820D03*
X369300Y1680400D03*
Y1682900D03*
X380930Y122022D03*
X383160Y124322D03*
X383060Y128491D03*
X372530Y122972D03*
X373200Y126052D03*
X379295Y131002D03*
X379860Y252162D03*
X379112Y290386D03*
X385720Y320902D03*
X376500Y366391D03*
Y378649D03*
X377136Y390307D03*
X390220Y392062D03*
X383060Y403542D03*
X379220Y436362D03*
X376220D03*
X382220D03*
X389920Y461362D03*
X379220Y470962D03*
X387500Y495362D03*
X389020Y522862D03*
X371970Y683892D03*
X381010Y734732D03*
X376638Y1248997D03*
X374088Y1248937D03*
X374028Y1251507D03*
X373823Y1256896D03*
X376333Y1256866D03*
X376518Y1254167D03*
X376578Y1251567D03*
X373968Y1254107D03*
X373835Y1259403D03*
X376345Y1259373D03*
X387478Y1248967D03*
X387358Y1254137D03*
X387117Y1256851D03*
X387418Y1251537D03*
X387117Y1259351D03*
X373835Y1261903D03*
Y1264403D03*
X376345Y1261873D03*
Y1264373D03*
X376285Y1267218D03*
X373735Y1267158D03*
X387117Y1261851D03*
X387129Y1264358D03*
X387125Y1267188D03*
X384501Y1321177D03*
X386831Y1321927D03*
X378097Y1329329D03*
X374097Y1328591D03*
X382307Y1330819D03*
X380835Y1328361D03*
X374097Y1331647D03*
X373552Y1372073D03*
X377025Y1371990D03*
X380025D03*
X373532Y1378598D03*
X373552Y1375573D03*
X380025Y1378490D03*
X377025D03*
X380025Y1375490D03*
X377025D03*
Y1381490D03*
X380025D03*
X376825Y1399386D03*
X379825D03*
X373703D03*
X379825Y1402386D03*
X376825D03*
X373703D03*
X376825Y1405386D03*
X379825D03*
X373573Y1405336D03*
X374027Y1411365D03*
X373703Y1414606D03*
X376825Y1414386D03*
X379825D03*
X376825Y1417386D03*
Y1411386D03*
X379825D03*
X373703Y1417386D03*
X376825Y1408386D03*
X379825D03*
X374307Y1408135D03*
X382489Y1428478D03*
X385667Y1433425D03*
X386827Y1429525D03*
X377830Y1534342D03*
X374900Y1534102D03*
X381120D03*
X377720Y1539862D03*
X374720D03*
X374800Y1546400D03*
X385100Y1539700D03*
X381800Y1539600D03*
X381000Y1546500D03*
X384000D03*
X378000Y1546400D03*
X387930Y1585155D03*
X384600Y1595100D03*
X382220Y1591870D03*
X374391Y1648476D03*
X385123Y1639732D03*
X378547D03*
X380170Y1660002D03*
X372640Y1662112D03*
X380077Y1654049D03*
X372009Y1682584D03*
X375430Y1676462D03*
X376610Y1688252D03*
X396380Y62742D03*
X402100Y62632D03*
X399240Y62722D03*
X404910Y62562D03*
X388735Y117322D03*
X395980Y148272D03*
X388965Y215067D03*
X388720Y218362D03*
X394720Y206362D03*
X402700Y234167D03*
X392616Y252162D03*
X396294Y281585D03*
X392083Y290954D03*
X404215Y291140D03*
X398720Y321202D03*
X398661Y323761D03*
X390876Y365640D03*
X390843Y378439D03*
X403875Y365640D03*
X404120Y378439D03*
X404291Y391433D03*
X391149Y404304D03*
X403720Y405552D03*
X388720Y430862D03*
X403220Y436362D03*
X395520Y448362D03*
X400080Y472652D03*
X402500Y495362D03*
X394500Y522862D03*
X400589Y575236D03*
X398796Y1161570D03*
Y1153070D03*
Y1170070D03*
X403738Y1249027D03*
X403618Y1254197D03*
X403498Y1256747D03*
X403678Y1251597D03*
X392538Y1248997D03*
X389928Y1251507D03*
X389988Y1248937D03*
X389868Y1254107D03*
X392298Y1256717D03*
X392418Y1254167D03*
X389627Y1256821D03*
X392478Y1251567D03*
X392238Y1259287D03*
X389627Y1259321D03*
X403438Y1259317D03*
X392220Y1264594D03*
X392228Y1261897D03*
X389627Y1261821D03*
X389639Y1264328D03*
X389635Y1267158D03*
X392185Y1267218D03*
X403385Y1267248D03*
X403378Y1261917D03*
X403390Y1264624D03*
X399935Y1317092D03*
Y1319592D03*
X389161Y1321177D03*
X391491Y1321927D03*
X392131Y1324821D03*
X396397Y1324591D03*
X394197Y1323091D03*
X396397Y1321691D03*
X400073Y1327653D03*
X403051Y1325373D03*
X394297Y1326091D03*
X392131Y1327721D03*
X396397Y1327491D03*
X400888Y1395508D03*
X392947Y1397827D03*
X390934Y1404085D03*
X401079Y1399208D03*
X400924Y1408227D03*
X400926Y1404707D03*
X392517Y1419015D03*
X400991Y1417264D03*
X390934Y1407605D03*
X390914Y1412991D03*
X403125Y1425008D03*
X390687Y1431713D03*
X390777Y1435152D03*
X394067Y1435323D03*
X401244Y1440773D03*
X396822Y1439340D03*
X396946Y1537632D03*
X396768Y1541810D03*
X404920Y1539362D03*
X396946Y1556810D03*
X391330Y1585155D03*
X404030Y1595390D03*
Y1591990D03*
X394360Y1616380D03*
X392550Y1618650D03*
X397406Y1633142D03*
X402590Y1618952D03*
X401740Y1648082D03*
X404240D03*
X404320Y1645452D03*
X401820D03*
X391563Y1640244D03*
X397406Y1636542D03*
X397400Y1641000D03*
X390180Y1668212D03*
X396824Y1673662D03*
X407970Y59612D03*
X407790Y62652D03*
X415800Y62665D03*
Y67465D03*
X419901Y117491D03*
X408284Y163662D03*
X420865Y215067D03*
X410996Y218834D03*
X420752Y239562D03*
X405139Y239908D03*
X417765Y252162D03*
X404985D03*
X417218Y291274D03*
X419920Y338162D03*
X416220Y364062D03*
X418704Y379201D03*
X416762Y367353D03*
X418540Y392163D03*
X416514Y407028D03*
X412720Y439362D03*
X417880Y461942D03*
X418520Y473562D03*
X419460Y1161570D03*
Y1153370D03*
Y1169597D03*
X406248Y1248997D03*
X408798Y1249057D03*
X408511Y1256866D03*
X406001Y1256896D03*
X406128Y1254167D03*
X408678Y1254227D03*
X406188Y1251567D03*
X419638Y1248967D03*
X419295Y1256851D03*
X419518Y1254137D03*
X419578Y1251537D03*
X419295Y1259351D03*
X408738Y1251627D03*
X408523Y1259373D03*
X406013Y1259403D03*
X419295Y1261851D03*
X419307Y1264358D03*
X419285Y1267188D03*
X408523Y1264373D03*
X406013Y1264403D03*
Y1261903D03*
X408523Y1261873D03*
X405895Y1267218D03*
X408445Y1267278D03*
X416629Y1321177D03*
X418959Y1321927D03*
X410225Y1329329D03*
X406225Y1328591D03*
X414435Y1330819D03*
X412963Y1328361D03*
X406225Y1331647D03*
X418320Y1383862D03*
X422320D03*
X414333Y1385292D03*
X410933Y1384648D03*
X414909Y1395658D03*
X408915Y1402606D03*
X411150Y1408163D03*
X410912Y1418177D03*
X408968Y1410427D03*
X411162Y1414126D03*
X416926Y1426471D03*
X412416Y1431645D03*
X419861Y1429718D03*
X419302Y1434700D03*
X422708Y1437560D03*
X410074Y1424993D03*
X416999Y1441908D03*
X413599D03*
X407625Y1552572D03*
X419820Y1555862D03*
X409140Y1566892D03*
X405000Y1566670D03*
X412600Y1601000D03*
X408600Y1607400D03*
X419780Y1602802D03*
X414406Y1624992D03*
Y1628392D03*
X405990Y1618952D03*
X416020Y1620862D03*
X412456Y1649838D03*
X417960Y1650072D03*
X410700Y1655310D03*
X409857Y1682767D03*
X421320Y1671699D03*
X410249Y1673082D03*
X427120Y59862D03*
X428500Y65016D03*
Y70016D03*
X435340Y122196D03*
X428889Y121515D03*
X428883Y131015D03*
X429780Y149373D03*
Y153477D03*
Y157466D03*
Y161466D03*
X433695Y209862D03*
X421200Y232562D03*
X423145Y227862D03*
X426490Y244262D03*
X429702Y290763D03*
X425720Y319492D03*
X432380Y346522D03*
X422420Y338162D03*
X431781Y379201D03*
X434006Y365203D03*
X433596Y391163D03*
X431920Y405288D03*
X428720Y439362D03*
X437720Y435362D03*
X431570Y435512D03*
X437520Y476337D03*
X431220Y496362D03*
X434343Y504233D03*
Y509733D03*
Y498733D03*
X431220Y507143D03*
Y512623D03*
Y501643D03*
X434343Y515233D03*
Y526233D03*
Y520733D03*
X431220Y518133D03*
Y523362D03*
X434620Y535762D03*
X434343Y542733D03*
X434320Y540153D03*
X434343Y547769D03*
Y552769D03*
X421960Y1161570D03*
Y1153370D03*
Y1169597D03*
X422148Y1248937D03*
X424698Y1248997D03*
X422088Y1251507D03*
X421805Y1256821D03*
X422028Y1254107D03*
X424458Y1256717D03*
X424578Y1254167D03*
X424638Y1251567D03*
X421805Y1259321D03*
X424398Y1259287D03*
X436068Y1248967D03*
X435828Y1256687D03*
X435948Y1254137D03*
X436008Y1251537D03*
X435768Y1259257D03*
X421805Y1261821D03*
X421817Y1264328D03*
X421795Y1267158D03*
X424345Y1267218D03*
X424380Y1264594D03*
X424388Y1261897D03*
X435715Y1267188D03*
X435720Y1264564D03*
X435708Y1261857D03*
X432063Y1317092D03*
Y1319592D03*
X421289Y1321177D03*
X423619Y1321927D03*
X428525Y1321691D03*
X426325Y1323091D03*
X424259Y1324821D03*
X428525Y1324591D03*
X432628Y1327845D03*
X435179Y1325373D03*
X424259Y1327721D03*
X426425Y1326091D03*
X428525Y1327491D03*
X426320Y1383862D03*
X430320D03*
X439030Y1383692D03*
X436780Y1387387D03*
X436467Y1391687D03*
X438458Y1402169D03*
X438645Y1426890D03*
X437299Y1436774D03*
X433539Y1430613D03*
X425030Y1434292D03*
X433897Y1434670D03*
X427546Y1443411D03*
X433954Y1439029D03*
X424146Y1443411D03*
X435396Y1551810D03*
X424820Y1552605D03*
X431620Y1541362D03*
X434430Y1567562D03*
X424570Y1579466D03*
X433350Y1579509D03*
X424800Y1616600D03*
X432200Y1607060D03*
X423180Y1602802D03*
X432500Y1613822D03*
X430015Y1626608D03*
X433670Y1639562D03*
X426728Y1636495D03*
X451418Y78782D03*
X446640Y104552D03*
X446746Y152662D03*
X453028Y154864D03*
X452500Y213362D03*
Y222362D03*
X452071Y254862D03*
X442265Y290939D03*
X439120Y314562D03*
X442220Y323362D03*
X448220Y323582D03*
Y319862D03*
X446000Y339362D03*
X455000Y340362D03*
X450500Y358862D03*
X443770Y371042D03*
X451062Y397262D03*
X447490Y409052D03*
X443300Y410962D03*
X447750Y414112D03*
X453020Y414262D03*
X449420Y424162D03*
X451520Y475837D03*
X442520Y476337D03*
X453680Y515072D03*
X451320Y533562D03*
X448276Y1161570D03*
X445776D03*
X443276D03*
X445776Y1153370D03*
X448276D03*
X443276D03*
X448276Y1170069D03*
X445776D03*
X443276D03*
X441128Y1248997D03*
X438578Y1248937D03*
X438518Y1251507D03*
X440858Y1256866D03*
X438348Y1256896D03*
X441008Y1254167D03*
X438458Y1254107D03*
X441068Y1251567D03*
X440870Y1259373D03*
X438360Y1259403D03*
X451642Y1256851D03*
X451878Y1254107D03*
X451642Y1259351D03*
X451938Y1251507D03*
X451998Y1248937D03*
X438360Y1261903D03*
X440870Y1261873D03*
Y1264373D03*
X438360Y1264403D03*
X438225Y1267158D03*
X440775Y1267218D03*
X451642Y1261851D03*
X451654Y1264358D03*
X451645Y1267158D03*
X448757Y1321177D03*
X451087Y1321927D03*
X442353Y1329329D03*
X438353Y1328591D03*
X446563Y1330819D03*
X445091Y1328361D03*
X438353Y1331647D03*
X443842Y1389106D03*
X448020Y1391862D03*
X443424Y1397869D03*
X439391Y1398266D03*
X441369Y1394260D03*
X451048Y1404914D03*
X447110Y1403812D03*
X448114Y1396812D03*
X445339Y1415731D03*
X446230Y1407722D03*
X445230Y1411719D03*
X445723Y1419730D03*
X443850Y1423404D03*
X451080Y1433740D03*
X440164Y1433982D03*
X445294Y1430415D03*
X443715Y1436052D03*
X452520Y1564862D03*
X448328Y1582476D03*
X446020Y1570412D03*
X452020Y1580412D03*
X448740Y1574862D03*
X444458Y1602654D03*
X437383Y1602629D03*
X454661Y1609235D03*
X442974Y1615615D03*
X448181Y1614401D03*
X443800Y1610712D03*
X449940Y1647412D03*
X447090Y1647472D03*
X444940Y1641842D03*
X438340Y1652266D03*
X441740D03*
X462620Y120948D03*
X462320Y115948D03*
X453346Y149864D03*
X461900Y215244D03*
X466300Y217803D03*
X461900Y222921D03*
X466300Y225480D03*
X468323Y254562D03*
X465236Y296973D03*
X461736Y301098D03*
Y306098D03*
X463198Y311587D03*
X465000Y340362D03*
X456660Y359172D03*
X460800Y358962D03*
X467211Y371902D03*
X459220Y393762D03*
X463500Y383562D03*
X455720Y404762D03*
X458600Y414262D03*
X465421Y428078D03*
X456520Y476337D03*
X461520D03*
X453727Y518036D03*
X457456Y522516D03*
X470880Y572692D03*
X467130Y600122D03*
X456818Y1256687D03*
X454388Y1254077D03*
X454152Y1256821D03*
X456998Y1251537D03*
X456758Y1259257D03*
X454152Y1259321D03*
X468258Y1249107D03*
X468018Y1256827D03*
X468138Y1254277D03*
X468198Y1251677D03*
X467958Y1259397D03*
X457058Y1248967D03*
X454508Y1248907D03*
X454448Y1251477D03*
X456938Y1254137D03*
X456705Y1267188D03*
X454155Y1267128D03*
X456748Y1261867D03*
X456740Y1264564D03*
X454152Y1261821D03*
X454164Y1264328D03*
X467905Y1267328D03*
X467910Y1264704D03*
X467898Y1261997D03*
X464191Y1317092D03*
Y1319592D03*
X453417Y1321177D03*
X455747Y1321927D03*
X458453Y1323091D03*
X460653Y1321691D03*
Y1324591D03*
X456387Y1324821D03*
X464191Y1327793D03*
X467307Y1325373D03*
X458553Y1326091D03*
X460653Y1327491D03*
X456387Y1327721D03*
X459550Y1401348D03*
X465947Y1398355D03*
X459321Y1393009D03*
Y1396409D03*
X458441Y1414893D03*
X468880Y1418400D03*
X456619Y1431189D03*
X463140Y1451562D03*
X463207Y1547543D03*
X453595Y1551470D03*
X459520Y1546962D03*
X466905Y1567847D03*
X467400Y1556700D03*
X460020Y1580412D03*
X457220Y1584020D03*
X466520Y1574862D03*
X457220Y1603562D03*
X460200Y1589900D03*
X456510Y1614472D03*
X469488Y1607362D03*
X460910Y1629172D03*
Y1625772D03*
X455681Y1622492D03*
X458978Y1634481D03*
X463344Y1637622D03*
X469580Y1640272D03*
X468040Y1651657D03*
X466460Y1672332D03*
X466180Y1678392D03*
X481880Y147069D03*
X481246Y161364D03*
X476220Y158772D03*
X470900Y234787D03*
X486800Y259162D03*
X478500Y258862D03*
X474736Y302098D03*
X478995Y293787D03*
X479736Y303598D03*
Y308598D03*
X486720Y360862D03*
X482720D03*
X475508Y359266D03*
X476585Y370727D03*
X472720Y391362D03*
X485020Y414162D03*
X471920Y416687D03*
X474169Y476196D03*
X479169D03*
X474044Y503725D03*
X478510Y602942D03*
X472960Y602152D03*
X482780Y607012D03*
X473698Y1161570D03*
X471198D03*
X473698Y1153370D03*
X471198D03*
X473698Y1170070D03*
X471198D03*
X473318Y1249137D03*
X470768Y1249077D03*
X473035Y1256866D03*
X470525Y1256896D03*
X473198Y1254307D03*
X470648Y1254247D03*
X473258Y1251707D03*
X470708Y1251647D03*
X473047Y1259373D03*
X470537Y1259403D03*
X484098Y1248997D03*
X483819Y1256851D03*
X483978Y1254167D03*
X484038Y1251567D03*
X483819Y1259351D03*
X472965Y1267358D03*
X470415Y1267298D03*
X470537Y1261903D03*
X473047Y1261873D03*
Y1264373D03*
X470537Y1264403D03*
X483819Y1261851D03*
X483831Y1264358D03*
X483745Y1267218D03*
X480885Y1321177D03*
X485545D03*
X483215Y1321927D03*
X474481Y1329329D03*
X470481Y1328591D03*
X478691Y1330819D03*
X477219Y1328361D03*
X470481Y1331647D03*
X483560Y1401712D03*
X474983Y1400385D03*
X485141Y1405430D03*
X481997Y1409955D03*
X470987Y1409965D03*
X484921Y1413246D03*
X470890Y1435838D03*
X478449Y1448158D03*
X482633Y1449091D03*
Y1446091D03*
X470111Y1548269D03*
X483348Y1548062D03*
X475110Y1548112D03*
X477968Y1548122D03*
X480848Y1548120D03*
X486210Y1547960D03*
X482400Y1558320D03*
X472220Y1626732D03*
X472210Y1622735D03*
X477905Y1663242D03*
Y1659242D03*
X475150Y1654302D03*
X477835Y1677462D03*
X488748Y72264D03*
X499580Y78442D03*
X489730Y76132D03*
X498330Y96112D03*
X498730Y128592D03*
X498700Y212685D03*
Y220362D03*
X503100Y215244D03*
X500925Y231262D03*
X503100Y222921D03*
X496028Y258590D03*
X499096Y252462D03*
X489091Y293787D03*
X498636Y296273D03*
X495136Y300398D03*
Y305398D03*
X486861D03*
X495036Y310398D03*
X486710Y313582D03*
X492150Y336810D03*
X498720Y360862D03*
X490720D03*
Y368862D03*
X489520Y411862D03*
X494020Y414262D03*
X492970Y409252D03*
X502070Y427937D03*
X488169Y475696D03*
X493169Y476196D03*
X498169D03*
X486500Y556212D03*
X491043Y550447D03*
X486608Y1248967D03*
X489158Y1249027D03*
X486329Y1256821D03*
X486488Y1254137D03*
X488918Y1256747D03*
X489038Y1254197D03*
X486548Y1251537D03*
X489098Y1251597D03*
X486329Y1259321D03*
X488858Y1259317D03*
X500228Y1259237D03*
X486329Y1261821D03*
X486341Y1264328D03*
X488840Y1264624D03*
X488848Y1261927D03*
X488805Y1267248D03*
X486255Y1267188D03*
X500138Y1269637D03*
X500150Y1272344D03*
X500198Y1267037D03*
Y1264467D03*
X500168Y1261807D03*
X500150Y1275224D03*
Y1278104D03*
X487875Y1321927D03*
X492878Y1322618D03*
X490678Y1324018D03*
X496319Y1330493D03*
Y1333043D03*
X499435Y1338799D03*
X488539Y1325772D03*
X492878Y1325518D03*
X488539Y1328672D03*
X490778Y1327018D03*
X492878Y1328418D03*
X496319Y1341264D03*
X491089Y1446091D03*
Y1449091D03*
X499489D03*
Y1446091D03*
X489230Y1643592D03*
X516236Y92948D03*
X513586Y92799D03*
X510600Y92782D03*
X517290Y104252D03*
X513700Y117862D03*
X510900Y111962D03*
X503270Y128592D03*
X507320D03*
X515690Y147852D03*
X519010Y147912D03*
X518186Y139821D03*
X519236Y202404D03*
X518670Y219192D03*
X512500Y209862D03*
Y223362D03*
X508500Y232862D03*
X508000Y241862D03*
X508502Y298813D03*
X503040Y287928D03*
X508500Y303362D03*
X508136Y309398D03*
X502239Y315404D03*
X507160Y332452D03*
X510720Y360862D03*
X514720D03*
X502720D03*
X506720Y368862D03*
X509720Y390362D03*
X513720D03*
X505720Y398362D03*
X502260Y397742D03*
X511320Y437962D03*
X513444Y457522D03*
X516970Y592942D03*
X504135Y615612D03*
X505398Y1259377D03*
X502858Y1259257D03*
X502718Y1271417D03*
X505218Y1271447D03*
X505290Y1267254D03*
X505338Y1261947D03*
X505278Y1264547D03*
X502750Y1267134D03*
X502798Y1261827D03*
X502738Y1264427D03*
X502718Y1274114D03*
X505218Y1274144D03*
X515898Y1271447D03*
X515950Y1274144D03*
X505220Y1280054D03*
X502718Y1276994D03*
X505218Y1277024D03*
X502680Y1280054D03*
X515960D03*
X515950Y1277024D03*
X513013Y1334603D03*
X517673D03*
X515343Y1335353D03*
X506609Y1342755D03*
X502609Y1342017D03*
X510819Y1344245D03*
X509347Y1341787D03*
X502609Y1345073D03*
X509246Y1420002D03*
X505777Y1425579D03*
X507964Y1448979D03*
Y1445979D03*
X529720Y30792D03*
Y43054D03*
X534720Y42922D03*
X533915Y59822D03*
X523978Y59074D03*
X529078Y59282D03*
X527520Y69633D03*
X528590Y72922D03*
X518450Y101602D03*
X527310Y98147D03*
Y94747D03*
X527160Y129243D03*
X523220Y170362D03*
X534765Y161067D03*
X526920Y161362D03*
X529507Y202448D03*
X522337Y202404D03*
X531298Y284280D03*
X536420Y309422D03*
X523682Y307541D03*
Y304541D03*
X526980Y322582D03*
X521820Y336762D03*
X531720Y360862D03*
X527720D03*
X523670Y368892D03*
X525720Y390362D03*
X529720D03*
X521720Y398362D03*
X532650Y446396D03*
Y442376D03*
X521885Y452442D03*
X532650Y450330D03*
Y454270D03*
X533410Y475932D03*
X525820Y473662D03*
X524425Y489112D03*
Y495112D03*
X519520Y484027D03*
X522805Y482155D03*
X531258Y505473D03*
X521561Y505969D03*
Y500469D03*
Y511469D03*
X524220Y505862D03*
Y500362D03*
Y511362D03*
X521561Y516969D03*
Y522469D03*
X536000Y520362D03*
X524220Y516862D03*
X524720Y525293D03*
Y519743D03*
X521561Y527969D03*
Y539819D03*
X524920D03*
X524820Y545319D03*
X523699Y571545D03*
X528500Y566722D03*
X523890Y592387D03*
X531472Y579750D03*
X521118Y1273097D03*
X518488Y1271477D03*
X521058Y1275667D03*
X518490Y1274144D03*
X521058Y1278277D03*
X521020Y1280974D03*
X518500Y1280054D03*
X518490Y1277024D03*
X530398Y1288557D03*
X530548Y1283377D03*
X530428Y1285947D03*
X530410Y1291254D03*
X532558Y1289967D03*
X532618Y1287367D03*
X532678Y1284797D03*
X530450Y1297014D03*
Y1294134D03*
X532570Y1295554D03*
Y1298434D03*
Y1292674D03*
X525008Y1336287D03*
X520643Y1338247D03*
X522809Y1339517D03*
X522783Y1334882D03*
X520643Y1341147D03*
X520003Y1335353D03*
X528447Y1353316D03*
Y1355816D03*
X524892Y1341462D03*
X522818Y1342930D03*
X528929Y1364212D03*
X531563Y1361597D03*
X539720Y30792D03*
X534720D03*
X542050Y47452D03*
X539720Y42862D03*
X550971Y42902D03*
X544720Y42892D03*
X548609Y48082D03*
X537315Y59822D03*
X541002Y71436D03*
X544402D03*
X548070Y79372D03*
X542460Y99172D03*
X539475Y118772D03*
X547395Y147302D03*
X543083Y146338D03*
X540460Y200392D03*
X544390Y236512D03*
X550390Y231742D03*
X548390Y236512D03*
X546390Y231742D03*
X542050Y231722D03*
X539639Y271972D03*
X539830Y274912D03*
X537720Y278212D03*
X547420Y306862D03*
X544920D03*
X549220Y339687D03*
X535720Y360862D03*
X546758Y360502D03*
X547810Y414472D03*
X549670Y419892D03*
X542870Y438320D03*
X548464Y456534D03*
X548780Y475932D03*
X548550Y480382D03*
X546210Y519642D03*
X541820Y575130D03*
X541722Y568054D03*
X537730Y577440D03*
X547020Y590332D03*
X550320Y583362D03*
X536626Y590500D03*
X537560Y598102D03*
X537648Y1290037D03*
X535058Y1290007D03*
X535148Y1287397D03*
X543660Y1302934D03*
X541100D03*
X538560D03*
X535110Y1292704D03*
Y1295584D03*
Y1298464D03*
X537650Y1292704D03*
X540210D03*
X537650Y1298464D03*
Y1295584D03*
X540210Y1298464D03*
Y1295584D03*
X536020Y1302904D03*
X545141Y1357401D03*
X549801D03*
X538737Y1365553D03*
X534737Y1364815D03*
X542947Y1367043D03*
X541475Y1364585D03*
X534737Y1367871D03*
X547471Y1358151D03*
X563482Y40826D03*
X554720Y32862D03*
X565184Y47982D03*
X558058Y46352D03*
X554983Y45312D03*
X553650Y48842D03*
X551470Y79372D03*
X567865Y92656D03*
X559000Y102862D03*
X561000Y98862D03*
X552395Y134340D03*
X566500Y125097D03*
X551231Y122671D03*
X564890Y142173D03*
X555220Y164787D03*
X555545Y156462D03*
X555195Y184862D03*
Y171862D03*
X554872Y196635D03*
X559400Y201162D03*
X557248Y198909D03*
X564600Y202662D03*
X552489Y212022D03*
X553402Y231292D03*
X552089Y253202D03*
Y257202D03*
X562461Y272161D03*
X561324Y301149D03*
X566730Y300992D03*
X555520Y309827D03*
X563790Y331846D03*
X561290D03*
X558790D03*
X562200Y419412D03*
X559300Y414112D03*
X559730Y434772D03*
X557829Y454479D03*
X558220Y459362D03*
X563281Y543113D03*
X563700Y538477D03*
X560640Y540613D03*
X566140Y554972D03*
Y551472D03*
X559927Y548457D03*
X556820Y570462D03*
X557430Y583572D03*
X566510Y1352217D03*
X554837Y1359315D03*
X557037Y1363715D03*
Y1357915D03*
Y1360815D03*
X554937Y1362315D03*
X552771Y1361045D03*
Y1363945D03*
X552131Y1358151D03*
X555057Y1449395D03*
X572500Y32862D03*
X568500D03*
X581500Y41862D03*
X573190Y42912D03*
X567507Y45869D03*
X575330Y47672D03*
X570208Y47982D03*
X579930Y72052D03*
X577300Y66682D03*
X577880Y75442D03*
X570150Y102862D03*
X579080Y119402D03*
X573360Y140532D03*
X573115Y161232D03*
X569470Y171702D03*
X581120Y155062D03*
X568245Y167112D03*
X579481Y198378D03*
X579170Y190092D03*
X579481Y194378D03*
Y206378D03*
X578450Y218562D03*
X579245Y221362D03*
X567730Y225362D03*
X578390D03*
X567730Y221362D03*
X581755Y236978D03*
X575359Y265132D03*
X582510Y296657D03*
X577676Y300268D03*
X577480Y303822D03*
X582510Y304052D03*
Y311571D03*
X570440Y331930D03*
X567630Y331958D03*
X574800Y322462D03*
X571830Y348772D03*
X572360Y351962D03*
X571720Y381862D03*
X575050Y383602D03*
X577720Y381862D03*
X574491Y376549D03*
X580370Y383670D03*
X581090Y426970D03*
X571930Y421232D03*
X571110Y442656D03*
X569490Y437600D03*
X571110Y446706D03*
X567320Y454962D03*
Y459962D03*
Y457462D03*
X577220Y449462D03*
X578920Y466462D03*
X583045Y488212D03*
X583220Y493212D03*
X568840Y501046D03*
X584173Y498422D03*
X568520Y504162D03*
Y506662D03*
X577470Y505592D03*
X578925Y516846D03*
X571627Y548124D03*
X569050Y578292D03*
X572057Y577242D03*
X571555Y1352487D03*
X570645Y1361358D03*
X576220Y1423862D03*
X571620Y1424492D03*
X584950Y54842D03*
X586260Y52222D03*
X599800Y43152D03*
X597955Y48047D03*
X593369Y45682D03*
X586600Y60602D03*
X590680Y83591D03*
X592307Y94262D03*
X597287D03*
X594720Y97220D03*
X588245Y132142D03*
X598410Y124102D03*
X598390Y126802D03*
X589690Y161732D03*
X592220Y173862D03*
X596795Y179287D03*
X590281Y180698D03*
X599720Y184887D03*
X593220D03*
X584795Y233362D03*
X591310Y219582D03*
X592220Y249362D03*
X595415Y246515D03*
X591727Y285862D03*
X593763Y293999D03*
X588850Y291622D03*
X599620Y314762D03*
X595520Y314862D03*
X583820Y314662D03*
X590820Y330962D03*
X590720Y327862D03*
Y324582D03*
X590470Y319192D03*
X593120Y342782D03*
X583685Y363271D03*
X586185D03*
X586070Y352302D03*
X591839Y426112D03*
X595380Y416660D03*
X591720Y433937D03*
X595520Y439762D03*
X597220Y458688D03*
X599080Y448062D03*
X584100Y477952D03*
X592520Y467662D03*
X590210Y484132D03*
X599645Y479862D03*
X598661Y486922D03*
X587100Y493842D03*
X592400Y479162D03*
X591070Y504900D03*
X594090Y501957D03*
X587100Y496342D03*
X591425Y522337D03*
X591500Y516862D03*
X596880Y534812D03*
X592340Y744624D03*
X598693Y742072D03*
X611810Y34400D03*
X612822Y43232D03*
X606880Y44682D03*
X614400Y46012D03*
X603063Y48023D03*
X606020Y84562D03*
X615220Y76862D03*
X615170Y73812D03*
X601220Y73862D03*
Y76862D03*
X603720Y98362D03*
X608620Y94162D03*
X617585Y97257D03*
X613020Y94162D03*
X617409D03*
X603880Y93902D03*
X600220Y96862D03*
X614384Y119342D03*
X606040Y153432D03*
X606190Y144002D03*
X602580Y151052D03*
X603019Y146399D03*
X615573Y179484D03*
X615572Y176442D03*
X611381Y200378D03*
Y209878D03*
X614200Y265792D03*
X605350Y293092D03*
X605870Y298172D03*
X605560Y303372D03*
X607590Y314732D03*
X609040Y317282D03*
X615635Y317637D03*
X614130Y328762D03*
X605305Y331162D03*
X615180Y336812D03*
X605898Y372984D03*
X609690Y402812D03*
X605220Y416362D03*
X610720Y436362D03*
X600800Y430900D03*
X614220Y436362D03*
X610720Y442862D03*
X614220D03*
Y447862D03*
X602910Y461862D03*
X610720Y457862D03*
X614220D03*
X610720Y452862D03*
X604360Y452120D03*
X614220Y467862D03*
Y472862D03*
Y477862D03*
X605469Y467562D03*
X610720Y462862D03*
X614220D03*
X601220Y486922D03*
X600645Y504362D03*
X606200Y510862D03*
X611870Y512560D03*
X606220Y517762D03*
X607328Y537481D03*
X610797Y537528D03*
X607720Y550862D03*
X610720D03*
X613220Y654662D03*
X603276Y741375D03*
X600460Y744912D03*
X613047Y741492D03*
X602768Y758385D03*
X616675Y31777D03*
X624633Y49193D03*
X629820Y42562D03*
Y45062D03*
X619562Y49193D03*
X624140Y46672D03*
X622271Y44782D03*
X629000Y67362D03*
X628590Y58622D03*
X622271Y57952D03*
X623300Y95762D03*
X620540Y100112D03*
X632300Y104472D03*
X626699Y119182D03*
X630951D03*
X631290Y153702D03*
X615970Y161522D03*
X628195Y175914D03*
X628194Y172872D03*
X628730Y216472D03*
X631730D03*
X628730Y220472D03*
Y224472D03*
X631730Y220472D03*
Y224472D03*
X622730Y230362D03*
X630795Y236862D03*
X618470Y265732D03*
X629564Y253127D03*
X621060Y271066D03*
X633150Y301457D03*
X627950Y298897D03*
X627600Y309134D03*
X632143Y306575D03*
X630220Y314362D03*
X623365Y316742D03*
X631146Y317768D03*
X619474Y331162D03*
X619100Y374638D03*
X621720Y373362D03*
X622490Y402162D03*
X628500Y402362D03*
X624220Y411362D03*
X629220D03*
X623220Y426362D03*
X625500Y421362D03*
X629220D03*
Y426362D03*
X628900Y431050D03*
X625620Y447862D03*
X625900Y431050D03*
X625620Y442862D03*
X629220D03*
X622220D03*
X617220Y436362D03*
X622220Y452862D03*
Y447862D03*
X629220Y457862D03*
X626400Y462812D03*
X625620Y457862D03*
X622220D03*
X629220Y452862D03*
X625620D03*
X629220Y447862D03*
X626390Y467882D03*
X626210Y478002D03*
X626310Y472902D03*
X629220Y462862D03*
X622220D03*
X622520Y467862D03*
X629220Y487310D03*
X622860D03*
X626720Y482880D03*
X623670Y507862D03*
X629480Y508862D03*
X633000Y508700D03*
X629920Y516652D03*
X623000Y546900D03*
X629220Y643462D03*
X626720D03*
X617252Y739354D03*
X623497Y748235D03*
X626017Y745083D03*
X620870Y762072D03*
X617940Y763552D03*
X630417Y757135D03*
X628970Y1670880D03*
X637220Y31462D03*
X643880Y42142D03*
X647447Y46322D03*
X641200Y46762D03*
X638500Y57362D03*
X635000D03*
X637000Y68142D03*
X634500Y73422D03*
X645330Y77132D03*
Y72972D03*
X640220Y85542D03*
X634690D03*
X647220Y96929D03*
X639901Y103462D03*
X640000Y108542D03*
X639970Y113892D03*
X640130Y166362D03*
X643170Y171362D03*
X649870Y181942D03*
X645263Y235689D03*
X640295Y234237D03*
X645109Y249202D03*
Y260202D03*
X643800Y294327D03*
Y298297D03*
Y306547D03*
Y302247D03*
X645990Y314482D03*
X643800Y310962D03*
X633350Y314362D03*
X647100Y357372D03*
X636075Y389862D03*
X649075Y389937D03*
X632620Y389862D03*
X645925Y389937D03*
X638700Y400962D03*
X647700Y399162D03*
X643500Y400962D03*
X643940Y411482D03*
X637220Y411362D03*
X644220Y426362D03*
X640720Y418862D03*
X644220Y421362D03*
X637220Y416362D03*
Y426362D03*
X637195Y421362D03*
X647420Y434162D03*
X640720Y431362D03*
X644000Y438862D03*
X644220Y431362D03*
X638250Y439250D03*
X637220Y431362D03*
X644220Y452862D03*
X640820Y457902D03*
X637220Y452862D03*
X640720D03*
X640920Y447862D03*
X644220D03*
X637195Y457862D03*
X637220Y467862D03*
Y472862D03*
Y477862D03*
X644220D03*
Y462862D03*
X641235Y477377D03*
X640798Y472934D03*
X637220Y462862D03*
X640820Y467862D03*
X640620Y483422D03*
X642580Y508172D03*
X645220Y504362D03*
X646815Y517974D03*
X648296Y528255D03*
X637020Y522362D03*
X642630Y517870D03*
X640130D03*
X633147Y758595D03*
X647725Y1643719D03*
X643725Y1643467D03*
X648225Y1658482D03*
X642725Y1658562D03*
X635410Y1664220D03*
X637540Y1669480D03*
X636702Y1677610D03*
X645725Y1691182D03*
X640725Y1691452D03*
X650725Y1690682D03*
X646225Y1708169D03*
X642225Y1708457D03*
X648220Y1716912D03*
X636160Y1710662D03*
X639745Y1722362D03*
Y1718362D03*
X648220Y1722921D03*
X651943Y33535D03*
X663543Y43328D03*
X656950Y59012D03*
X651680Y73812D03*
X656500Y69662D03*
X661587D03*
X661600Y75562D03*
X657165Y79131D03*
X656426Y75431D03*
X652320Y123362D03*
X662498Y124960D03*
X650790Y149871D03*
Y140699D03*
X662880Y149912D03*
Y146912D03*
X651730Y177212D03*
X662560Y214152D03*
X662780Y210362D03*
Y205362D03*
Y207862D03*
X659880Y210762D03*
Y205762D03*
Y208262D03*
X650705Y270947D03*
X662891Y357442D03*
X662680Y354362D03*
X651520Y378662D03*
X658720Y399862D03*
X652000Y402362D03*
X653100Y407862D03*
X655820Y452662D03*
X655800Y461432D03*
X652195Y457862D03*
X655820Y467662D03*
X663000Y489500D03*
X663014Y493860D03*
X655220Y486862D03*
X661865Y505334D03*
X663720Y523806D03*
X665990Y517131D03*
X661220Y526862D03*
X650794Y515039D03*
X652577Y1000775D03*
X653690Y1392362D03*
X653761Y1396300D03*
X663187Y1395170D03*
Y1397720D03*
X666303Y1403476D03*
X663687Y1407279D03*
X654540Y1427605D03*
Y1424205D03*
X661100Y1451012D03*
X662660Y1548120D03*
X663410Y1553982D03*
X664590Y1631620D03*
X663097Y1642667D03*
X651725Y1643397D03*
X656725Y1660769D03*
X663118Y1655557D03*
X663043Y1651557D03*
X663145Y1672862D03*
Y1668862D03*
X653420Y1698662D03*
X663645Y1722862D03*
X680200Y39062D03*
X677560Y40572D03*
X672250Y40812D03*
X666943Y43328D03*
X682290Y46822D03*
X670612Y47264D03*
X674012D03*
X674035Y74522D03*
X678050Y58157D03*
X673987Y87662D03*
X677820Y89462D03*
X680578Y75992D03*
X674540Y80652D03*
X670800Y85932D03*
X667940Y80142D03*
X671320Y91192D03*
X677790Y104880D03*
X673720Y110362D03*
X674145Y113487D03*
X677978Y119668D03*
Y115668D03*
X675560Y117120D03*
X668300Y132400D03*
X665650Y147692D03*
X673713Y237725D03*
X674731Y359924D03*
X680600Y364282D03*
X683100Y369550D03*
X673220Y388362D03*
X675295Y399862D03*
X670720D03*
X668695Y408362D03*
Y404262D03*
X665870Y433942D03*
X675220Y508862D03*
X680220Y495887D03*
X670220Y503837D03*
X680220Y508862D03*
X675220Y521862D03*
X670720D03*
Y516862D03*
X680220Y530362D03*
X673340Y530922D03*
X673617Y744735D03*
X669700Y746626D03*
X677887Y742121D03*
X669778Y759929D03*
X670037Y1336396D03*
X664987D03*
X667487D03*
X664987Y1338896D03*
X667487D03*
X670037D03*
Y1333896D03*
X664987D03*
X667487D03*
X664987Y1348896D03*
X667487D03*
X664987Y1346396D03*
X667487D03*
X664987Y1343896D03*
Y1341396D03*
X667487D03*
Y1343896D03*
X670037Y1341396D03*
Y1343896D03*
Y1346396D03*
Y1348896D03*
X679881Y1399280D03*
X673477Y1409386D03*
X669477Y1406694D03*
X677619Y1408887D03*
X675876Y1406619D03*
X669477Y1409415D03*
X674149Y1434149D03*
X671149D03*
X668649D03*
X674149Y1426149D03*
Y1431149D03*
Y1428649D03*
X671149Y1426149D03*
X668649D03*
X671149Y1431149D03*
X668649Y1428649D03*
Y1431149D03*
X671149Y1428649D03*
X677319Y1428359D03*
Y1433359D03*
Y1430859D03*
X682160Y1548040D03*
X665410Y1548180D03*
X679207Y1560482D03*
X678877Y1566798D03*
X678621Y1571072D03*
X678610Y1582154D03*
X666560Y1581000D03*
X678619Y1579070D03*
X666600Y1584900D03*
X678900Y1595400D03*
X678771Y1585945D03*
X666700Y1595500D03*
X678900Y1589800D03*
X666700Y1591900D03*
X678900Y1592600D03*
X666700Y1588500D03*
X679640Y1617520D03*
Y1614000D03*
X679270Y1604040D03*
X675710Y1620320D03*
X673420Y1650057D03*
X671290Y1646320D03*
X668695Y1662235D03*
X671610Y1673792D03*
X671620Y1668303D03*
X677940Y1670110D03*
X678490Y1695660D03*
X674195Y1712362D03*
X675120Y1716242D03*
X674195Y1728362D03*
X672270Y1721612D03*
X687120Y39632D03*
X692289Y40633D03*
X689940Y38952D03*
X696800Y42108D03*
X696838Y47940D03*
X683440Y42832D03*
X687344Y46940D03*
X692389Y46439D03*
X694751Y70212D03*
X690027Y70142D03*
X685780Y70022D03*
X699475Y69982D03*
X685968Y58157D03*
X694400D03*
X681980D03*
X690510Y59132D03*
X696700Y72462D03*
X692389Y72692D03*
X687664Y73202D03*
X696370Y78512D03*
X696727Y81552D03*
Y84052D03*
X681053Y104668D03*
X695720Y102162D03*
X694220Y104862D03*
X688019Y109845D03*
X687030Y113090D03*
X687034Y115896D03*
X697615Y123697D03*
X687238Y171071D03*
X685600Y364282D03*
X690600D03*
X695600D03*
X683500Y381200D03*
X685210Y388852D03*
X694920Y388797D03*
X687500Y399402D03*
X692330Y388751D03*
X685220Y391652D03*
X692402Y391250D03*
X695220Y399862D03*
X685270Y408362D03*
Y404262D03*
X692400Y404682D03*
X683320Y490662D03*
X685220Y495887D03*
X690580Y482992D03*
X694510Y482942D03*
X686120Y481862D03*
X695220Y495887D03*
X690220D03*
X695220Y508862D03*
X685220D03*
X690220Y506362D03*
X685220Y503837D03*
X690220Y508882D03*
X690330Y503530D03*
X695257Y503847D03*
X695220Y516852D03*
X685220D03*
X690220Y519662D03*
X695220D03*
X689720Y530862D03*
X695220Y530662D03*
X683457Y745175D03*
X696810Y1300162D03*
X692280Y1302532D03*
X684555Y1338896D03*
X689605Y1336396D03*
Y1338896D03*
X687105Y1336396D03*
X684555D03*
X687105Y1338896D03*
X689605Y1333896D03*
X687105D03*
X684555D03*
X689605Y1348896D03*
X687105D03*
X689605Y1346396D03*
X687105D03*
X684555Y1341396D03*
Y1343896D03*
Y1346396D03*
Y1348896D03*
X689605Y1341396D03*
Y1343896D03*
X687105Y1341396D03*
Y1343896D03*
X684541Y1399280D03*
X682211Y1400030D03*
X686871D03*
X691777Y1405594D03*
Y1399794D03*
X689577Y1401194D03*
X687511Y1402924D03*
X691777Y1402694D03*
X689677Y1404194D03*
X687511Y1405824D03*
X694596Y1396198D03*
X694129Y1420283D03*
X696754Y1419809D03*
X691129Y1420283D03*
X681899Y1434049D03*
Y1426049D03*
Y1431049D03*
Y1428549D03*
X694129Y1423303D03*
X691129D03*
X696694Y1427949D03*
Y1425449D03*
Y1430449D03*
X696784Y1422614D03*
X683930Y1552562D03*
Y1555062D03*
Y1557562D03*
X692100Y1567190D03*
X692026Y1580490D03*
X697197Y1640667D03*
X697122Y1636667D03*
X689200Y1648843D03*
X686220Y1640667D03*
X697595Y1666862D03*
X687045Y1673362D03*
X706370Y46782D03*
X701838Y42202D03*
Y47940D03*
X703900Y72112D03*
X701400D03*
X713000Y69662D03*
X697720Y58162D03*
X710200Y69662D03*
X706867Y58197D03*
X703100Y58157D03*
X712500Y79862D03*
X710486Y77695D03*
X700500Y74862D03*
X698710Y86035D03*
X705390Y85792D03*
X703000Y84862D03*
X706720Y100462D03*
X699220Y102162D03*
X702720D03*
X701220Y104862D03*
X697720D03*
X712733Y117488D03*
Y114588D03*
X712290Y106722D03*
X712340Y128093D03*
X700600Y125309D03*
X707008Y125804D03*
X705800Y167788D03*
Y171188D03*
X704770Y182999D03*
Y179599D03*
Y194810D03*
Y191410D03*
Y218432D03*
Y206621D03*
Y215032D03*
Y203221D03*
X700600Y364282D03*
X705600D03*
X710600D03*
X709000Y354000D03*
X715600Y363900D03*
X705700Y361400D03*
X709400Y378200D03*
X713220Y378362D03*
X711200Y396500D03*
X707220Y399362D03*
X709160Y386730D03*
X713220Y388362D03*
X707400Y396200D03*
X713220Y399862D03*
X705195Y408362D03*
Y404262D03*
X705780Y411022D03*
X712770Y406822D03*
X705720Y488862D03*
X703220Y490362D03*
X705720Y484862D03*
X711220Y503842D03*
X705220D03*
Y508862D03*
X711220Y508882D03*
X710720Y521362D03*
X705220D03*
X701757Y521324D03*
X705220Y530362D03*
X710940Y591172D03*
X698602Y580536D03*
X705240Y594020D03*
X702740D03*
X712060Y638542D03*
X708680Y638812D03*
X708310Y646032D03*
X704320Y645262D03*
X704000Y740862D03*
X700500Y745862D03*
X703545Y745907D03*
X711720Y1286162D03*
X707720Y1290162D03*
X705720Y1286662D03*
X704795Y1294559D03*
X707320Y1301162D03*
X708137Y1336396D03*
Y1338896D03*
X703087Y1336396D03*
X705587D03*
Y1338896D03*
X703087D03*
X708137Y1333896D03*
X705587D03*
X703087D03*
Y1346396D03*
X705587D03*
X703087Y1348896D03*
X705587D03*
X708137Y1341396D03*
Y1343896D03*
X705587Y1341396D03*
X703087D03*
Y1343896D03*
X705587D03*
X708137Y1348896D03*
Y1346396D03*
X701330Y1395195D03*
Y1397695D03*
X704446Y1403476D03*
X701830Y1407326D03*
X711620Y1409386D03*
X707620Y1406694D03*
Y1409660D03*
X699754Y1419809D03*
X699694Y1427949D03*
Y1425449D03*
Y1430449D03*
X699784Y1422614D03*
X712222Y1570703D03*
X702112Y1571683D03*
Y1575683D03*
Y1579683D03*
X711102Y1575683D03*
X714162Y1574333D03*
X713052Y1579683D03*
X712582Y1584843D03*
X704497Y1598927D03*
X702112Y1587683D03*
Y1591683D03*
X713102Y1601307D03*
X715775Y1599024D03*
X714380Y1589960D03*
X702112Y1595683D03*
X712512Y1596338D03*
X711350Y1590720D03*
X711780Y1614590D03*
X704370Y1604580D03*
X706103Y1617107D03*
X708857Y1613462D03*
X710570Y1629890D03*
X708830Y1623115D03*
X705516Y1620296D03*
X710540Y1636070D03*
X708999Y1646762D03*
X703719Y1646768D03*
X697595Y1662862D03*
X700460Y1660918D03*
X709678Y1658485D03*
X697730Y1677460D03*
X704759Y1677001D03*
X724620Y40062D03*
X728720Y43562D03*
X719820Y45862D03*
X717320Y44062D03*
X729293Y58062D03*
X724644Y58362D03*
X719949Y58862D03*
X715990Y69662D03*
X725740Y69580D03*
X721990Y69762D03*
X718900Y69662D03*
X727700Y60562D03*
X728591Y71960D03*
X722415Y77862D03*
X718425Y77882D03*
X728090Y75132D03*
X719100Y85262D03*
X727518Y90984D03*
X715933Y117488D03*
Y114588D03*
X729933Y108388D03*
X728733Y132088D03*
Y129288D03*
X720433Y135088D03*
X717433D03*
X728733Y126388D03*
X719933Y124488D03*
X723133D03*
X715940Y157362D03*
X718213Y159241D03*
X720633Y160788D03*
X716698Y185687D03*
Y173687D03*
Y177087D03*
Y197187D03*
Y200587D03*
Y189087D03*
Y209021D03*
Y212421D03*
X717020Y220862D03*
X719720Y220142D03*
X722500Y365500D03*
X724897Y353887D03*
X721989Y351234D03*
X727000Y365500D03*
X731400D03*
X722500Y374100D03*
X727000D03*
X731400Y375000D03*
X718720Y381892D03*
X728220Y388362D03*
X723195Y408362D03*
Y404262D03*
X725220Y399862D03*
X723220Y508882D03*
X717220D03*
X729220D03*
Y503842D03*
X723220D03*
X717220D03*
X714000Y496132D03*
X723120Y525362D03*
X728220Y521362D03*
X717220D03*
X717296Y525407D03*
X723220Y516852D03*
X729220D03*
X717220D03*
X729212Y531700D03*
X729328Y583076D03*
X729295Y586113D03*
X725207Y579371D03*
X722707D03*
X715860Y585540D03*
X714320Y597462D03*
X723450Y597072D03*
X720240Y598292D03*
X715420Y639162D03*
X719190Y646642D03*
X717720Y643262D03*
X715220D03*
X723340Y642922D03*
X714087Y745865D03*
X720697Y765862D03*
X723460Y1245632D03*
X714720Y1286162D03*
X723054Y1333896D03*
X725604D03*
X728104D03*
X725604Y1338896D03*
X723054Y1336396D03*
X725604D03*
X728104Y1338896D03*
Y1336396D03*
X723054Y1338896D03*
X725604Y1346396D03*
X728104D03*
X725604Y1348896D03*
X728104D03*
X725604Y1343896D03*
Y1341396D03*
X728104Y1343896D03*
Y1341396D03*
X723054Y1348896D03*
Y1346396D03*
Y1343896D03*
Y1341396D03*
X725654Y1405824D03*
Y1402924D03*
X727720Y1401194D03*
X727820Y1404194D03*
X718024Y1399280D03*
X722684D03*
X720354Y1400030D03*
X725014D03*
X715762Y1408887D03*
X714019Y1406619D03*
X717300Y1547370D03*
X715792Y1567461D03*
X720370Y1566910D03*
X723520Y1561604D03*
X724712Y1566820D03*
X716612Y1584635D03*
X717152Y1570093D03*
X728977Y1574453D03*
X717402Y1574433D03*
X724465Y1580092D03*
X722465Y1582092D03*
X726465D03*
X723942Y1574123D03*
X724465Y1590950D03*
X722465Y1588950D03*
X726465D03*
X729052Y1602518D03*
X726092Y1598483D03*
X720987Y1599568D03*
X723542Y1612702D03*
X721488Y1610945D03*
X725910Y1611900D03*
X716688Y1610055D03*
X719168Y1612016D03*
X718195Y1647300D03*
X714203Y1642926D03*
X729150Y1641690D03*
X726810Y1652430D03*
X714071Y1663842D03*
X722630Y1655740D03*
X724500Y1680400D03*
X718758Y1673800D03*
X745900Y40362D03*
X733314Y40862D03*
X740100Y41162D03*
X746100Y46262D03*
X736620Y45262D03*
X745474Y57932D03*
X733642Y58062D03*
X741377Y57932D03*
X737595D03*
X732793Y71436D03*
X736193D03*
X742620Y71762D03*
X735880Y60662D03*
X740819Y82362D03*
X736720Y101662D03*
X745035Y94632D03*
X735770Y94988D03*
X739823Y91052D03*
X741308Y108742D03*
X738600Y136600D03*
X736060Y145532D03*
X740220Y145362D03*
X745725Y167537D03*
X732720Y231362D03*
X734220Y238362D03*
X744247Y312598D03*
X741800Y363200D03*
X742090Y356082D03*
X735600Y351400D03*
X735800Y365500D03*
X732700Y351500D03*
X740200Y375100D03*
X736220Y380787D03*
X742720Y380262D03*
X735800Y375000D03*
X738220Y388362D03*
X742160Y396452D03*
X738220Y383862D03*
X745720Y399862D03*
X735220Y410842D03*
X735745Y408362D03*
Y404262D03*
X733720Y399862D03*
X743980Y443482D03*
X740740Y473822D03*
X741420Y494162D03*
X747600Y506592D03*
X735220Y508862D03*
X745220Y503842D03*
X735220D03*
X735430Y516862D03*
X745220Y522362D03*
Y516852D03*
X730220Y523362D03*
X740840Y521982D03*
X735173Y521362D03*
X736480Y531722D03*
X738980D03*
X733922Y531712D03*
X733117Y580071D03*
Y582571D03*
X733134Y585672D03*
X736710Y603842D03*
Y607242D03*
X735620Y613862D03*
X730690Y655532D03*
X744538Y746524D03*
X737609Y744282D03*
X730889Y746834D03*
X740820Y741762D03*
X729920Y1405594D03*
X732226Y1396212D03*
X729920Y1399794D03*
Y1402694D03*
X733336Y1568341D03*
Y1565341D03*
Y1559341D03*
Y1562341D03*
X730336Y1559341D03*
Y1562341D03*
X745336D03*
Y1559341D03*
Y1565341D03*
Y1568341D03*
X742336Y1562341D03*
Y1559341D03*
Y1565341D03*
Y1568341D03*
X739336Y1562341D03*
Y1559341D03*
Y1565341D03*
Y1568341D03*
X736336D03*
Y1565341D03*
Y1559341D03*
Y1562341D03*
X733336Y1574341D03*
Y1571341D03*
X745336Y1574341D03*
Y1571341D03*
X742336Y1574341D03*
Y1571341D03*
X739336Y1574341D03*
Y1571341D03*
X736336D03*
Y1574341D03*
X735300Y1648760D03*
X737080Y1655820D03*
X735080Y1662980D03*
X740840Y1655590D03*
X732705Y1669450D03*
X754620Y51602D03*
X758620D03*
X749477Y57932D03*
X755700Y59942D03*
Y62442D03*
X758200Y59942D03*
Y62442D03*
X760700Y59942D03*
Y62442D03*
X747487Y71429D03*
X757693Y100653D03*
Y96423D03*
X750700Y106642D03*
X754800Y97082D03*
X750033Y92888D03*
Y89988D03*
X757340Y92562D03*
X748033Y116288D03*
X747230Y108572D03*
X760390Y111810D03*
X751220Y137864D03*
X747200Y251500D03*
X757150Y280592D03*
X758720Y283262D03*
X759920Y280562D03*
X758412Y298790D03*
X755305Y298847D03*
X748820Y284562D03*
X758390Y295450D03*
X748498Y309640D03*
X759637Y311585D03*
X757936Y303908D03*
X760670Y317432D03*
X747554Y384962D03*
X757430Y408212D03*
X760469Y442647D03*
X750290Y462162D03*
X757365Y459862D03*
X752500Y495762D03*
X757238Y483862D03*
X756642Y496522D03*
Y501744D03*
X751220Y522362D03*
Y516852D03*
X759790Y525522D03*
X755940Y516862D03*
X756650Y526072D03*
X761710Y517651D03*
X757020Y530462D03*
X759820D03*
X754220D03*
X762345Y1284542D03*
Y1287542D03*
Y1290542D03*
X762205Y1293272D03*
X757720Y1375462D03*
Y1384062D03*
X758020Y1397862D03*
X758420Y1406862D03*
X758120Y1414762D03*
X755420Y1426262D03*
Y1422862D03*
X748336Y1562341D03*
Y1559341D03*
Y1565341D03*
Y1568341D03*
X751336D03*
Y1565341D03*
Y1559341D03*
Y1562341D03*
X748336Y1574341D03*
Y1571341D03*
X760112Y1579183D03*
X749612Y1579023D03*
X749652Y1586407D03*
X760152Y1583183D03*
X749612Y1583023D03*
X760112Y1592183D03*
Y1587183D03*
X749662Y1590733D03*
X749612Y1594683D03*
X758360Y1589661D03*
X761716Y1661194D03*
X751620Y1674312D03*
X759859Y1686090D03*
X759359Y1729520D03*
X752875Y1726670D03*
X774059Y68912D03*
X773420Y143462D03*
X772328Y153728D03*
X771426Y158026D03*
X766320Y264892D03*
X763320D03*
X771630Y258102D03*
X762420Y280562D03*
X777420Y277962D03*
X769789Y296231D03*
X777467Y296315D03*
X769860Y302462D03*
X771377Y314139D03*
X771490Y354942D03*
X768490D03*
X777420Y354962D03*
X774490Y354942D03*
X765000Y354862D03*
X771960Y375162D03*
X767960Y369662D03*
X776000D03*
X764000D03*
X766195Y393212D03*
X773245Y398212D03*
X766195Y403212D03*
Y413212D03*
X773245Y403212D03*
Y408212D03*
X768910Y403260D03*
X771050Y416940D03*
X766195Y423212D03*
Y428212D03*
X768701Y418662D03*
X774982Y446908D03*
X772365Y454862D03*
X768720Y459862D03*
X765315Y454862D03*
Y459862D03*
X772365D03*
X765360Y475412D03*
X765335Y469552D03*
X772364Y475062D03*
X772365Y469862D03*
X765315Y479862D03*
X772365Y488862D03*
X776170Y493422D03*
X766510Y493452D03*
X765386Y483572D03*
X773530Y507062D03*
X765810Y506342D03*
X769745Y502600D03*
X775378Y502502D03*
X765521Y525364D03*
X769220Y530362D03*
X765720D03*
X777020D03*
X772020Y746562D03*
X774384Y744088D03*
X762562Y746444D03*
X769921Y742095D03*
X767421D03*
X764921D03*
X769337Y760775D03*
X762617Y758885D03*
X765345Y1284542D03*
X768335Y1284612D03*
X765345Y1287542D03*
Y1290542D03*
X768335Y1287612D03*
Y1290612D03*
X765205Y1293272D03*
X768195Y1293342D03*
X778005Y1294092D03*
X768520Y1384062D03*
Y1375462D03*
X768620Y1397262D03*
X775375Y1403561D03*
X767820Y1414762D03*
X763152Y1581893D03*
Y1577893D03*
Y1573793D03*
X773952Y1580493D03*
X768714Y1571203D03*
X769452Y1584393D03*
X770252Y1587268D03*
X763152Y1590893D03*
Y1594893D03*
X774052Y1590293D03*
X776922Y1590444D03*
X764920Y1695347D03*
X766880Y1689020D03*
X766603Y1721797D03*
X785180Y120947D03*
X792680D03*
X790180D03*
X787680D03*
X783940Y118637D03*
X786440D03*
X788940D03*
X781440D03*
X782553Y150031D03*
Y152531D03*
X779893Y147521D03*
Y150021D03*
X780820Y278262D03*
X785135Y274822D03*
X785200Y271400D03*
X794057Y301569D03*
X794220Y296062D03*
X785220Y284762D03*
X792943Y312642D03*
X784415Y313734D03*
X793896Y309026D03*
X793820Y304962D03*
X779120Y303410D03*
Y308755D03*
X785000Y355000D03*
X779920Y354962D03*
X782420D03*
X790120Y354862D03*
X792620D03*
X787600Y354900D03*
X795520Y393462D03*
X791075Y388000D03*
X781195Y393212D03*
X781320Y398212D03*
X787720Y408362D03*
X781195Y413212D03*
Y423212D03*
X785560Y417902D03*
X788120Y422942D03*
X791040Y422892D03*
X793660Y422842D03*
X785720Y427862D03*
X789230Y414942D03*
X780020Y441437D03*
Y445287D03*
X784730Y432682D03*
X787320Y444862D03*
Y439862D03*
X791582Y435352D03*
X781205Y454402D03*
X780315Y459862D03*
X787320Y454862D03*
Y449862D03*
Y459862D03*
X787360Y469862D03*
X786220Y464862D03*
X796315Y469290D03*
X780315Y464862D03*
X783340Y474802D03*
X782690Y488862D03*
X793220Y493362D03*
X781170Y493422D03*
X785800Y482762D03*
X793875Y483262D03*
X778670Y493422D03*
X783600Y502462D03*
X783450Y522462D03*
X783400Y511902D03*
X789720Y589862D03*
X785220Y581362D03*
X789720Y587362D03*
X791720Y593862D03*
X793720Y595862D03*
X791969Y618384D03*
X794720Y617862D03*
X783507Y761875D03*
X794157Y761295D03*
X782515Y766702D03*
X791140Y761693D03*
X792045Y1284542D03*
Y1290542D03*
Y1287542D03*
X791905Y1293272D03*
X791260Y1388662D03*
X790380Y1432132D03*
X784352Y1568293D03*
Y1565293D03*
Y1559293D03*
Y1562293D03*
X781352Y1568293D03*
Y1565293D03*
Y1559293D03*
Y1562293D03*
X793352D03*
Y1559293D03*
Y1565293D03*
Y1568293D03*
X790352Y1562293D03*
Y1559293D03*
Y1565293D03*
Y1568293D03*
X787352D03*
Y1565293D03*
Y1559293D03*
Y1562293D03*
X784352Y1574293D03*
Y1571293D03*
X781352Y1574293D03*
Y1571293D03*
X793352Y1574293D03*
Y1571293D03*
X790352Y1574293D03*
Y1571293D03*
X787352D03*
Y1574293D03*
X808800Y267900D03*
X810920Y280062D03*
X798204Y279146D03*
X797924Y298358D03*
X806450Y310362D03*
X803620Y302962D03*
X805870Y304812D03*
X799720Y300462D03*
X795920Y312662D03*
X803280Y354982D03*
X800646Y354921D03*
X795220Y354862D03*
X806000Y360600D03*
X798400D03*
X805910Y355012D03*
X797900Y354800D03*
X795520Y398212D03*
X800352Y408389D03*
X803120Y428762D03*
X797720Y428412D03*
X798370Y439932D03*
X802010Y439940D03*
X802790Y433832D03*
X795320Y439862D03*
X805720Y432902D03*
X801750Y444330D03*
X795320Y444862D03*
X810860Y454862D03*
X802810D03*
X795320D03*
Y449862D03*
X802810Y464862D03*
Y449862D03*
X810860Y459862D03*
X802810D03*
X795320D03*
X810860Y449862D03*
X798990Y474862D03*
X802865D03*
X795320Y464862D03*
X810815Y474862D03*
X810860Y464862D03*
X810815Y469862D03*
X807220Y493362D03*
X801940Y485932D03*
X804510Y486122D03*
X809510D03*
X799230Y485922D03*
X812510Y486422D03*
X802790Y495652D03*
X805470Y510522D03*
X807640Y506672D03*
X808100Y509900D03*
X797420Y512503D03*
X805445Y587582D03*
X810720Y586862D03*
X811143Y605265D03*
X807945Y594362D03*
X803220D03*
X797200Y599883D03*
X795720Y614862D03*
X796702Y761195D03*
X810850Y770272D03*
X799577Y760985D03*
X807000Y757562D03*
X798035Y1284612D03*
X795045Y1284542D03*
X798035Y1290612D03*
Y1287612D03*
X795045Y1290542D03*
Y1287542D03*
X797895Y1293342D03*
X794905Y1293272D03*
X806323Y1343076D03*
X812130Y1343022D03*
X809210Y1343062D03*
X804100Y1435010D03*
X800000Y1431100D03*
X799352Y1562293D03*
Y1559293D03*
Y1565293D03*
Y1568293D03*
X796352Y1562293D03*
Y1559293D03*
Y1565293D03*
Y1568293D03*
X799352Y1574293D03*
Y1571293D03*
X796352Y1574293D03*
Y1571293D03*
X804652Y1581793D03*
Y1573793D03*
X812652Y1577793D03*
X801652Y1584539D03*
X812698Y1587047D03*
X804652Y1597793D03*
Y1585993D03*
X799152Y1586507D03*
X804652Y1589793D03*
Y1609793D03*
X827114Y115223D03*
X823114D03*
X814570Y145952D03*
X814531Y139851D03*
X820900Y147112D03*
X815060Y280072D03*
X813490Y273862D03*
X816220Y277162D03*
X813293Y287062D03*
X826300Y311962D03*
X823800D03*
X818000Y378800D03*
X813210Y374292D03*
X815710D03*
X825003Y389012D03*
Y397276D03*
X819220Y397664D03*
X824980Y413260D03*
X819220Y412264D03*
X823600Y421194D03*
X815310Y440100D03*
X816810Y464862D03*
X825100Y468900D03*
X824860Y464862D03*
X816400Y472900D03*
X820720Y493862D03*
X822415Y479600D03*
X821720Y511082D03*
X814305Y499503D03*
X819320Y502347D03*
X821720Y527082D03*
X815650Y516807D03*
X821720Y515082D03*
Y523082D03*
X820220Y586862D03*
X814220Y582530D03*
X823720Y594862D03*
X820470Y595112D03*
X815120Y593582D03*
X820613Y744641D03*
X823589Y746924D03*
X822374Y757039D03*
X814770Y763874D03*
X815789Y1008845D03*
X826090Y1334362D03*
Y1339362D03*
Y1329362D03*
Y1344362D03*
X820920Y1344342D03*
X818420D03*
X823352Y1565293D03*
Y1562293D03*
Y1559293D03*
Y1568293D03*
X826352Y1565293D03*
Y1562293D03*
Y1559293D03*
Y1568293D03*
X823352Y1571293D03*
Y1574293D03*
X826352Y1571293D03*
Y1574293D03*
X815652Y1582570D03*
Y1573793D03*
X813352Y1590893D03*
X812652Y1593793D03*
X815551D03*
X818652Y1590444D03*
X812652Y1605793D03*
Y1601793D03*
X836779Y68008D03*
X828600Y61752D03*
X839898Y87248D03*
X841584Y94181D03*
X837250Y93221D03*
X839360Y114862D03*
X835114Y115223D03*
X845220Y135862D03*
Y129362D03*
X829114Y147123D03*
X828145Y160362D03*
X838220Y163862D03*
X835220D03*
X837320Y175112D03*
X842720Y181360D03*
X837160Y218212D03*
Y213207D03*
X844526Y204968D03*
X838820Y206872D03*
X837500Y229642D03*
X840063Y285022D03*
X839450Y272662D03*
X835400Y268800D03*
X829620Y280345D03*
X829820Y275045D03*
X840850Y278948D03*
X829720Y292762D03*
X839860Y294702D03*
X827620Y302962D03*
X830417Y311865D03*
X836300Y418800D03*
X832400Y427100D03*
X840400Y418900D03*
X831720Y457700D03*
X839640Y449612D03*
X832700Y446800D03*
X830600Y449200D03*
X838220Y459562D03*
X841200Y456500D03*
X832720Y494862D03*
X829720D03*
X838645Y492862D03*
X830870Y480010D03*
X832590Y512888D03*
X829745Y502082D03*
X832370Y525849D03*
X843287Y527817D03*
X841461Y525849D03*
X840990Y529786D03*
X828009Y587913D03*
X831705Y593877D03*
X829230Y582772D03*
X831530Y651932D03*
X830587Y741205D03*
X833120Y743392D03*
X838587Y766825D03*
X841827Y766795D03*
X837127Y758976D03*
X829420Y758422D03*
X841997Y773085D03*
X838020Y1232432D03*
X832090Y1326862D03*
Y1331862D03*
Y1336862D03*
Y1341862D03*
X829352Y1565293D03*
Y1562293D03*
Y1559293D03*
Y1568293D03*
X832352D03*
Y1565293D03*
Y1559293D03*
Y1562293D03*
X835352Y1568293D03*
Y1565293D03*
Y1559293D03*
Y1562293D03*
X838352Y1568293D03*
Y1565293D03*
Y1559293D03*
Y1562293D03*
X841352Y1568293D03*
Y1565293D03*
Y1559293D03*
Y1562293D03*
X829352Y1574293D03*
Y1571293D03*
X832352D03*
Y1574293D03*
X835352Y1571293D03*
Y1574293D03*
X838352Y1571293D03*
Y1574293D03*
X841352Y1571293D03*
Y1574293D03*
X843652Y1584539D03*
X841152Y1586507D03*
X858629Y60293D03*
X850015Y87341D03*
X843855Y87711D03*
X847472Y94754D03*
X847660Y113962D03*
X853100Y113762D03*
X854100Y132972D03*
X854220Y135862D03*
Y129362D03*
X854200Y138562D03*
X848745Y160187D03*
X848709Y156752D03*
X848360Y182872D03*
X845720Y181362D03*
X855858Y212425D03*
X855933Y215375D03*
X860050Y215310D03*
X847580Y232222D03*
X853828Y269043D03*
X850133Y271049D03*
X861865Y273730D03*
X850093Y286625D03*
X855480Y299692D03*
X856243Y286447D03*
X859920Y308852D03*
X859740Y399081D03*
X846040Y399210D03*
X846490Y422131D03*
X850610Y444352D03*
X851606Y447927D03*
X844210Y455902D03*
X846700Y476900D03*
X855200D03*
X857620Y492862D03*
X858600Y511130D03*
X848620Y509752D03*
X853070Y515447D03*
X857195Y522162D03*
X859888Y593970D03*
X859054Y583752D03*
X845523Y582126D03*
X856520Y751262D03*
X859450Y750462D03*
X844957Y763065D03*
X854620Y1242125D03*
X854237Y1250358D03*
X846652Y1581793D03*
Y1573793D03*
X854652Y1577793D03*
X857652Y1582570D03*
Y1573793D03*
X854777Y1586968D03*
X846652Y1597793D03*
X855352Y1590893D03*
X854652Y1593793D03*
X846652Y1585993D03*
X857551Y1593793D03*
X846652Y1589793D03*
X854652Y1605793D03*
Y1601793D03*
X846652Y1609793D03*
X862930Y70072D03*
X866330D03*
X862452Y151590D03*
X867620Y154362D03*
X871145Y163862D03*
X871580Y183370D03*
X875169Y185113D03*
X864859Y187110D03*
X873200Y194262D03*
X871890Y196740D03*
X877971Y196652D03*
X867528Y231788D03*
X875543Y266447D03*
X867700Y268262D03*
X875543Y269347D03*
X863747Y280870D03*
X867237Y273325D03*
X868552Y285537D03*
X874243Y287047D03*
X877322Y296051D03*
X872320Y304936D03*
X869820D03*
X867320D03*
X864820D03*
X860531Y375826D03*
X870700Y386476D03*
Y398620D03*
Y402581D03*
X868113Y409372D03*
X870513Y414276D03*
X862320Y431462D03*
X863415Y445829D03*
X860574Y445404D03*
X861080Y459742D03*
X870360Y493042D03*
X862620Y507162D03*
X868110Y499142D03*
X865290Y499032D03*
X865810Y521862D03*
X866820Y736562D03*
X863925Y737697D03*
X864680Y751582D03*
X874155Y756993D03*
X864700Y778300D03*
X868352Y1568293D03*
Y1565293D03*
Y1559293D03*
Y1562293D03*
X865352Y1568293D03*
Y1565293D03*
Y1559293D03*
Y1562293D03*
X874352D03*
Y1559293D03*
Y1565293D03*
Y1568293D03*
X871352D03*
Y1565293D03*
Y1559293D03*
Y1562293D03*
X868352Y1574293D03*
Y1571293D03*
X865352Y1574293D03*
Y1571293D03*
X874352Y1574293D03*
Y1571293D03*
X871352D03*
Y1574293D03*
X860652Y1590444D03*
X878327Y183169D03*
X876695Y171362D03*
Y176862D03*
X887520Y171362D03*
Y176862D03*
X877724Y200837D03*
X878220Y187449D03*
X888929Y209223D03*
X891620Y209662D03*
X888929Y206723D03*
X891620Y207162D03*
X884003Y278712D03*
X883870Y275802D03*
X883909Y281862D03*
X879587Y270004D03*
X883870Y272652D03*
X887338Y296760D03*
X882520Y327562D03*
X885020D03*
X887520D03*
X890422Y333879D03*
X893440Y336232D03*
X890820Y389362D03*
X890920Y386352D03*
X889453Y458926D03*
X887590Y471552D03*
X889439Y489599D03*
Y492999D03*
X881680Y504742D03*
Y508142D03*
X884512Y523800D03*
X882410Y526132D03*
X888130Y532612D03*
X891530D03*
X887810Y582442D03*
X889000Y737562D03*
X885310Y736442D03*
X886720Y741902D03*
X878192Y879910D03*
X884747Y871745D03*
X879100Y912608D03*
X884619Y916477D03*
X892317Y915872D03*
X880102Y923235D03*
X891560Y1435510D03*
X883352Y1562293D03*
Y1559293D03*
Y1565293D03*
Y1568293D03*
X880352Y1562293D03*
Y1559293D03*
Y1565293D03*
Y1568293D03*
X877352Y1562293D03*
Y1559293D03*
Y1565293D03*
Y1568293D03*
X883352Y1574293D03*
Y1571293D03*
X880352Y1574293D03*
Y1571293D03*
X877352Y1574293D03*
Y1571293D03*
X888652Y1581793D03*
Y1573793D03*
X885652Y1584539D03*
X888652Y1597793D03*
Y1585993D03*
X883152Y1586507D03*
X888652Y1589793D03*
Y1609793D03*
X908620Y188899D03*
X896620Y209662D03*
X894120D03*
Y207162D03*
X896620D03*
X906120Y261252D03*
X894770Y283062D03*
X896540Y341132D03*
X902260Y473153D03*
Y475653D03*
X903124Y470797D03*
X900020Y470672D03*
X896060Y481222D03*
Y484622D03*
X907678Y488177D03*
X895340Y497882D03*
Y501282D03*
X901829Y512730D03*
Y516130D03*
X893450Y516862D03*
X901230Y531612D03*
X904630D03*
X894897Y871745D03*
X894965Y917422D03*
X899830Y971484D03*
Y974884D03*
X907770Y1045242D03*
X894830Y1435970D03*
X907352Y1568293D03*
Y1565293D03*
Y1559293D03*
Y1562293D03*
Y1574293D03*
Y1571293D03*
X896652Y1577793D03*
X899652Y1582570D03*
Y1573793D03*
X896672Y1587073D03*
X897352Y1590893D03*
X896652Y1593793D03*
X899551D03*
X902652Y1590444D03*
X896652Y1605793D03*
Y1601793D03*
X922726Y176302D03*
X922100Y181791D03*
X917386Y184114D03*
X924920Y196199D03*
X923836Y193563D03*
X923897Y445545D03*
X927034Y445594D03*
X912984Y458135D03*
X909584D03*
X924447Y463012D03*
X921047D03*
X909190Y473392D03*
X912288Y472430D03*
X918532Y492445D03*
X927154Y492103D03*
X924623Y492097D03*
X918078Y495177D03*
X921189Y492086D03*
X918212Y497677D03*
X918131Y503330D03*
X921060Y506086D03*
X923783Y506076D03*
X918212Y500777D03*
X909984Y496330D03*
X926173Y512391D03*
X913394Y521662D03*
X916794D03*
X909600Y521162D03*
X922879Y531976D03*
Y528576D03*
X918420Y804062D03*
X909720Y798861D03*
Y794862D03*
X913720Y799362D03*
X914152Y803294D03*
X921757Y962082D03*
X916974Y962108D03*
X923930Y976652D03*
X917980Y974952D03*
X924440Y996852D03*
X914838Y985989D03*
X918720Y1009937D03*
X910352Y1568293D03*
Y1565293D03*
Y1559293D03*
Y1562293D03*
X922352D03*
Y1559293D03*
Y1565293D03*
Y1568293D03*
X919352Y1562293D03*
Y1559293D03*
Y1565293D03*
Y1568293D03*
X916352Y1562293D03*
Y1559293D03*
Y1565293D03*
Y1568293D03*
X913352D03*
Y1565293D03*
Y1559293D03*
Y1562293D03*
X910352Y1574293D03*
Y1571293D03*
X922352Y1574293D03*
Y1571293D03*
X919352Y1574293D03*
Y1571293D03*
X916352Y1574293D03*
Y1571293D03*
X913352D03*
Y1574293D03*
X919488Y1660733D03*
X918020Y1672860D03*
X914500Y1671400D03*
X938160Y173389D03*
X935550Y173329D03*
X940720Y173389D03*
X938160Y176389D03*
X935550Y176329D03*
X940720Y176389D03*
X940424Y184190D03*
X936424D03*
X935770Y191419D03*
X939270D03*
X940410Y188852D03*
X930472Y246093D03*
X938603Y240063D03*
X933122Y246115D03*
X933686Y242922D03*
X935454Y241154D03*
X933217Y380693D03*
Y384693D03*
X941059Y427911D03*
Y424511D03*
X937447Y457862D03*
X934047D03*
X928394Y472201D03*
Y474701D03*
X932373Y495175D03*
X932089Y492691D03*
X929654Y492103D03*
X932218Y499314D03*
X939872Y495813D03*
X932089Y505986D03*
X932289Y502986D03*
X926637Y506069D03*
X929281Y506086D03*
X931720Y524862D03*
X940550Y517400D03*
X940140Y514925D03*
X933773Y530479D03*
X930731D03*
X941050Y532252D03*
Y528852D03*
X938742Y803831D03*
X931573Y816109D03*
X927470Y815112D03*
X935052Y812630D03*
X934260Y808312D03*
X938371Y809311D03*
X930786Y811785D03*
X925220Y817862D03*
X928237Y824844D03*
X926469Y826612D03*
X926823Y962082D03*
X940170Y962842D03*
X939740Y987762D03*
X936998Y985750D03*
X932310Y996812D03*
X927220Y1012362D03*
X931220D03*
X925352Y1562293D03*
Y1559293D03*
Y1565293D03*
Y1568293D03*
Y1574293D03*
Y1571293D03*
X938652Y1581393D03*
X928152Y1584539D03*
X938652Y1593393D03*
Y1585393D03*
X925152Y1586507D03*
X938652Y1589393D03*
X933979Y1661327D03*
X929979Y1661352D03*
X942100Y1671100D03*
X945720Y173389D03*
X943220D03*
X945720Y176389D03*
X943220D03*
X948400Y176499D03*
X949120Y184912D03*
X944250Y194489D03*
Y197889D03*
X957020Y193299D03*
X949550Y192819D03*
X957020Y264862D03*
X953046Y390103D03*
X951181Y391916D03*
X950660Y399472D03*
X956487Y394831D03*
X949920Y404602D03*
X944032Y437631D03*
Y434231D03*
X945447Y463012D03*
X942047D03*
X946727Y507952D03*
Y504552D03*
X954420Y511252D03*
Y500552D03*
Y497152D03*
Y514652D03*
X954390Y527596D03*
X945524Y515483D03*
X944261Y517871D03*
X941740Y512922D03*
X942610Y515350D03*
X945100Y534464D03*
X955123Y533642D03*
X948415Y534313D03*
X956518Y531567D03*
X957220Y582862D03*
X953594Y787477D03*
X954447Y791735D03*
X951043Y796140D03*
X950190Y791382D03*
X944272Y803410D03*
X943366Y798707D03*
X946786Y795287D03*
X947921Y799761D03*
X944170Y962842D03*
X949560Y981392D03*
X951560Y997422D03*
X956980Y1536260D03*
X953980D03*
X950980D03*
X947980D03*
X944980D03*
Y1551260D03*
X947980D03*
X950980D03*
X953980D03*
X956980D03*
X944980Y1548260D03*
X947980D03*
X950980D03*
X953980D03*
X956980D03*
X944980Y1545260D03*
X947980D03*
X950980D03*
X953980D03*
X956980D03*
X944980Y1542260D03*
X947980D03*
X950980D03*
X953980D03*
X956980D03*
Y1539260D03*
X953980D03*
X950980D03*
X947980D03*
X944980D03*
Y1554260D03*
X947980D03*
X950980D03*
X953980D03*
X956980D03*
X956800Y1663725D03*
X956600Y1666875D03*
X962604Y165313D03*
X962458Y162398D03*
X965150Y193412D03*
X966720Y198099D03*
X970720D03*
X961120Y193299D03*
X968384Y242051D03*
X965884D03*
X960020Y264862D03*
X963020D03*
X962570Y282812D03*
X962882Y314512D03*
X967239Y320073D03*
X963854Y320113D03*
X963300Y347962D03*
X962623Y350642D03*
X970730Y377872D03*
X972220Y386251D03*
Y390239D03*
X975670Y392063D03*
X963856Y398302D03*
X965890Y405967D03*
X963720Y439862D03*
X961320Y476242D03*
X968286Y483941D03*
Y480541D03*
X964347Y509462D03*
X970788Y501230D03*
X964347Y501262D03*
X969351Y512416D03*
X957790Y527596D03*
X963930Y533362D03*
X967330D03*
X959351Y533566D03*
X960920Y644762D03*
Y649762D03*
Y654762D03*
X963720Y647262D03*
Y657262D03*
Y652262D03*
X960820Y665062D03*
X960920Y659762D03*
X963720Y662262D03*
X967750Y1376460D03*
X969000Y1536262D03*
X971700D03*
X969000Y1548262D03*
X971700D03*
X969000Y1545262D03*
X971700D03*
X969000Y1551262D03*
X971700D03*
Y1542262D03*
X969000D03*
X971700Y1539262D03*
X969000D03*
X965904Y1554364D03*
X960904D03*
X969000Y1554262D03*
X971700D03*
X965086Y1603984D03*
X962086D03*
X990501Y152397D03*
X986369Y155358D03*
X975690Y157220D03*
X983811Y156694D03*
X985499Y168753D03*
X985431Y181058D03*
X990115Y173039D03*
X987320Y194599D03*
Y198099D03*
Y201599D03*
X977220Y201399D03*
X986020Y191099D03*
X981795Y216623D03*
X978012Y276436D03*
X975512Y282096D03*
X978012D03*
X975512Y279266D03*
X978012D03*
X981470Y268532D03*
X979940Y292262D03*
Y289762D03*
X975512Y294996D03*
X978012D03*
X979940Y284762D03*
Y287262D03*
X988818Y346372D03*
X978000Y362462D03*
X988723Y369650D03*
X991934Y368443D03*
X988908Y373392D03*
X986400Y383123D03*
X983770Y373962D03*
X979766Y377507D03*
X977949Y384205D03*
X980916Y384286D03*
X980856Y392502D03*
X986955Y391939D03*
X983629Y397628D03*
X979559Y399362D03*
X983970Y392562D03*
X991369Y408252D03*
X979240Y425212D03*
X984254Y418379D03*
X987440Y431193D03*
X980720Y512362D03*
X986400Y503200D03*
X986273Y532996D03*
X980535Y532643D03*
X986418Y530019D03*
X975900Y1265062D03*
X987920Y1290662D03*
X985320Y1288762D03*
X992306Y1295049D03*
X979373Y1342724D03*
X974700Y1536262D03*
X980400D03*
X977700D03*
X974700Y1548262D03*
Y1545262D03*
Y1551262D03*
X980400Y1548262D03*
X977700D03*
X980400Y1545262D03*
X977700D03*
X980400Y1551262D03*
X977700D03*
Y1542262D03*
X980400D03*
X974700D03*
X977700Y1539262D03*
X980400D03*
X974700D03*
X984270Y1554364D03*
X974700Y1554262D03*
X980400D03*
X977700D03*
X989270Y1554364D03*
X995000Y150883D03*
X1001500D03*
X995180Y153689D03*
X1006220Y160799D03*
X1002720D03*
X1001101Y165510D03*
X999220Y185299D03*
X1002720D03*
X1006220D03*
X996415Y172579D03*
X1002920Y174799D03*
X990220Y195699D03*
Y199199D03*
X1008120Y198293D03*
X990195Y216823D03*
X990220Y202699D03*
X1000610Y211039D03*
X1005640Y210969D03*
X1001195Y219898D03*
X1005120Y230399D03*
X994743Y289843D03*
X1006232Y343983D03*
X1001440Y359702D03*
X994689Y379348D03*
X1006201Y370004D03*
X999440Y371782D03*
X996922Y367764D03*
X994322Y404090D03*
X1005123Y414662D03*
X997617Y412383D03*
X997394Y415578D03*
X993012Y421570D03*
X997225Y419162D03*
X990840Y431193D03*
X1005720Y498862D03*
X1003220Y512862D03*
X1005520Y510932D03*
X991237Y533043D03*
X1008560Y589682D03*
X1005960Y594682D03*
X1005373Y748826D03*
X995120Y773122D03*
X994942Y777055D03*
X996320Y1280683D03*
Y1284062D03*
X997920Y1278762D03*
X994574Y1297318D03*
X995066Y1536262D03*
X992466D03*
X1001066D03*
X1003766D03*
X998066D03*
X995066Y1551262D03*
X992466D03*
X995066Y1545262D03*
X992466D03*
X995066Y1548262D03*
X992466D03*
X1001066Y1551262D03*
X1003766D03*
X1001066Y1545262D03*
X1003766D03*
X1001066Y1548262D03*
X1003766D03*
X998066Y1551262D03*
Y1545262D03*
Y1548262D03*
Y1542262D03*
X1003766D03*
X1001066D03*
X992466D03*
X995066D03*
X998066Y1539262D03*
X1003766D03*
X1001066D03*
X992466D03*
X995066D03*
X1007636Y1554364D03*
X995066Y1554262D03*
X992466D03*
X1001066D03*
X1003766D03*
X998066D03*
X996698Y1604000D03*
X993698D03*
X1008129Y150948D03*
X1009720Y160799D03*
X1013220D03*
X1012791Y157596D03*
X1012000Y185299D03*
X1014900D03*
X1017800D03*
X1017200Y175699D03*
X1014300D03*
X1019900Y175799D03*
X1020645Y190499D03*
X1011320Y202169D03*
X1019355Y218423D03*
X1019802Y214099D03*
X1010005Y208424D03*
X1011720Y229699D03*
X1019355Y222423D03*
X1019530Y226423D03*
X1007820Y229999D03*
X1021118Y294290D03*
X1020720Y310937D03*
X1015520Y302862D03*
X1009800Y343800D03*
X1021695Y364518D03*
X1006710Y372931D03*
X1015096Y373758D03*
X1017163Y367963D03*
X1009883Y367955D03*
X1010420Y416062D03*
X1015420Y410862D03*
X1009009Y419948D03*
X1021239Y416974D03*
X1016261Y432888D03*
X1012861D03*
X1024200Y510362D03*
X1018092Y520212D03*
X1020392Y521826D03*
X1016360Y594682D03*
X1016220Y590862D03*
X1019000Y601042D03*
X1021654Y606302D03*
X1011160Y594682D03*
X1007873Y748826D03*
X1007600Y1298250D03*
X1007610Y1295040D03*
X1021612Y1536262D03*
X1016012D03*
X1018612D03*
Y1551262D03*
X1016012D03*
X1018612Y1545262D03*
X1016012D03*
X1018612Y1548262D03*
X1016012D03*
X1021612Y1551262D03*
Y1545262D03*
Y1548262D03*
X1018612Y1542262D03*
X1016012D03*
X1021612D03*
Y1539262D03*
X1016012D03*
X1018612D03*
Y1554262D03*
X1016012D03*
X1021612D03*
X1012636Y1554364D03*
X1026620Y125662D03*
X1034229Y128953D03*
X1032894Y155185D03*
X1022800Y175799D03*
X1037618Y261200D03*
X1031702Y264130D03*
X1025862Y291727D03*
X1032317Y291284D03*
X1036278Y303993D03*
Y307393D03*
X1033285Y353627D03*
X1029395Y375844D03*
X1025004Y374662D03*
X1031950Y383771D03*
Y387171D03*
X1031153Y390152D03*
X1026820Y394362D03*
X1038320Y407062D03*
Y404462D03*
X1026548Y400571D03*
X1035920Y420062D03*
Y417462D03*
X1026370Y503562D03*
X1032155Y509737D03*
X1025530Y519627D03*
X1033040Y519852D03*
X1038130Y518417D03*
X1040720Y591862D03*
X1024154Y601152D03*
X1029630Y601252D03*
X1026654Y596152D03*
X1035760Y592952D03*
X1033260Y601272D03*
X1038260D03*
X1033817Y735612D03*
X1036954Y734669D03*
X1030660Y735082D03*
X1027212Y1536262D03*
X1024612D03*
Y1551262D03*
X1027212D03*
X1024612Y1545262D03*
X1027212D03*
X1024612Y1548262D03*
X1027212D03*
X1024612Y1542262D03*
X1027212D03*
Y1539262D03*
X1024612D03*
X1031002Y1554364D03*
X1024612Y1554262D03*
X1027212D03*
X1036002Y1554364D03*
X1028298Y1604000D03*
X1025298D03*
X1040970Y128332D03*
X1043720Y363462D03*
X1054820Y370162D03*
X1044120Y366362D03*
X1040120Y393962D03*
X1042720D03*
X1041420Y443962D03*
X1043920D03*
X1050470Y447062D03*
X1041444Y506504D03*
X1053690Y520760D03*
X1045720Y591672D03*
X1043260Y601272D03*
X1045760Y596272D03*
X1048260Y601272D03*
X1051680Y614772D03*
X1053745Y742341D03*
X1053354Y1286714D03*
Y1291714D03*
X1039510Y1296655D03*
X1049510D03*
X1044510D03*
X1039510Y1293155D03*
X1049510D03*
X1044510D03*
X1053354Y1296714D03*
X1041798Y1536262D03*
X1047798D03*
X1050498D03*
X1044798D03*
X1039298D03*
X1041798Y1551262D03*
X1039298D03*
X1041798Y1545262D03*
X1039298D03*
X1041798Y1548262D03*
X1039298D03*
X1047798Y1551262D03*
X1050498D03*
X1047798Y1545262D03*
X1050498D03*
X1047798Y1548262D03*
X1050498D03*
X1044798Y1551262D03*
Y1545262D03*
Y1548262D03*
X1039298Y1542262D03*
X1044798D03*
X1050498D03*
X1047798D03*
X1041798D03*
X1044798Y1539262D03*
X1050498D03*
X1047798D03*
X1039298D03*
X1041798D03*
X1054368Y1554364D03*
X1041798Y1554262D03*
X1039298D03*
X1047798D03*
X1050498D03*
X1044798D03*
X1056898Y1604000D03*
X1067220Y145362D03*
Y142862D03*
Y148362D03*
X1059943Y435314D03*
X1062120Y477462D03*
X1056190Y520760D03*
X1058220Y585862D03*
X1061470D03*
X1056220Y605052D03*
X1055205Y744853D03*
X1063354Y1286714D03*
X1058354D03*
X1063354Y1291714D03*
X1058354D03*
X1063354Y1296714D03*
X1058290Y1296302D03*
X1071179Y1294669D03*
X1066462Y1520088D03*
X1065164Y1536262D03*
X1062464D03*
X1071164D03*
X1068164D03*
X1065164Y1551262D03*
X1062464D03*
X1065164Y1545262D03*
X1062464D03*
X1065164Y1548262D03*
X1062464D03*
X1071164Y1551262D03*
Y1545262D03*
Y1548262D03*
X1068164Y1551262D03*
Y1545262D03*
Y1548262D03*
Y1542262D03*
X1071164D03*
X1062464D03*
X1065164D03*
X1068164Y1539262D03*
X1071164D03*
X1062464D03*
X1065164D03*
Y1554262D03*
X1062464D03*
X1071164D03*
X1068164D03*
X1059368Y1554364D03*
X1059898Y1604000D03*
X1071920Y53862D03*
X1079114Y75775D03*
X1080168Y90721D03*
X1081282Y180937D03*
X1086756Y187540D03*
X1077973Y246362D03*
X1083973D03*
X1080973D03*
X1077883Y260842D03*
X1076823Y265438D03*
X1083823D03*
X1083883Y260842D03*
X1080883D03*
X1080323Y265438D03*
X1082853Y269492D03*
X1079853D03*
X1075400Y273762D03*
X1078400D03*
X1081400D03*
X1084400D03*
X1087400D03*
X1076018Y289400D03*
X1079018D03*
X1082018D03*
X1085018D03*
X1084130Y298342D03*
X1086630D03*
X1076353Y363966D03*
X1078853D03*
X1087330Y369061D03*
Y374131D03*
Y379251D03*
X1075462Y386723D03*
X1078151Y413911D03*
X1078120Y411262D03*
X1084245Y435437D03*
X1078545Y435637D03*
X1081045D03*
X1087280Y435437D03*
X1076598Y477087D03*
X1081930Y477132D03*
X1079320Y473892D03*
X1076820D03*
X1073589Y506461D03*
X1082220Y522362D03*
X1085720Y522422D03*
X1073250Y582332D03*
X1084637Y744635D03*
X1083714Y1285144D03*
Y1288144D03*
Y1291144D03*
X1077634Y1294869D03*
X1074387Y1294652D03*
X1074010Y1510650D03*
X1073864Y1536262D03*
X1085830D03*
X1073864Y1551262D03*
Y1545262D03*
Y1548262D03*
X1085830Y1551262D03*
Y1545262D03*
Y1548262D03*
Y1542262D03*
X1073864D03*
X1085830Y1539262D03*
X1073864D03*
X1077734Y1554364D03*
X1073864Y1554262D03*
X1085830D03*
X1082734Y1554364D03*
X1084000Y1647110D03*
X1094644Y67992D03*
X1090279Y126524D03*
X1105580Y132822D03*
X1100630Y130376D03*
X1099030Y245140D03*
X1088018Y289400D03*
X1089130Y298342D03*
X1091630D03*
X1094130D03*
X1089660Y408560D03*
X1095820Y420762D03*
X1090245Y435437D03*
X1093497Y744655D03*
X1089714Y1285144D03*
X1105480Y1517982D03*
X1088530Y1536262D03*
X1091530D03*
X1088530Y1551262D03*
Y1545262D03*
Y1548262D03*
X1094530Y1551262D03*
X1097230D03*
X1094530Y1545262D03*
X1097230D03*
X1094530Y1548262D03*
X1097230D03*
X1091530Y1551262D03*
Y1545262D03*
Y1548262D03*
Y1542262D03*
X1097230D03*
X1094530D03*
X1088530D03*
X1091530Y1539262D03*
X1094530D03*
X1088530D03*
X1101600Y1554364D03*
X1104750Y1549346D03*
X1088530Y1554262D03*
X1094530D03*
X1097230D03*
X1091530D03*
X1095436Y1603944D03*
X1092436D03*
X1088790Y1641830D03*
X1094225Y1671710D03*
X1091880Y1673720D03*
X1110977Y55505D03*
X1110754Y60028D03*
X1113594Y69862D03*
X1109020Y80592D03*
X1118309Y111687D03*
X1115860Y113883D03*
X1118486Y208942D03*
X1111918Y234718D03*
X1109088Y234668D03*
X1111918Y237718D03*
Y240718D03*
X1109088Y237668D03*
Y240668D03*
X1120190Y255652D03*
X1117820Y456132D03*
X1113207Y744455D03*
X1115853Y1426342D03*
Y1435532D03*
X1114400Y1518237D03*
X1110725Y1518046D03*
X1113725Y1530935D03*
X1115802Y1615010D03*
X1117407Y1628495D03*
X1113990Y1631370D03*
X1113325Y1627975D03*
X1117182Y1625460D03*
X1106480Y1641275D03*
X1113110Y1666460D03*
X1108320Y1680200D03*
X1112130Y1711600D03*
X1112252Y1706170D03*
X1112200Y1709000D03*
X1114150Y1715726D03*
X1110663Y1719189D03*
X1119200Y1730300D03*
Y1727200D03*
X1114300Y1722700D03*
X1119300Y1724100D03*
X1132547Y64864D03*
X1129997Y69864D03*
X1122278Y107549D03*
X1120420Y109829D03*
X1124858Y197309D03*
X1128485Y198159D03*
X1133041Y194137D03*
X1124360Y259712D03*
X1125409Y305797D03*
X1122059Y305673D03*
X1124985Y302578D03*
X1127402Y456174D03*
X1136051Y503324D03*
X1124120Y643762D03*
X1136720Y641362D03*
X1133720Y642862D03*
X1129420Y644062D03*
X1122980Y741312D03*
X1127972Y747250D03*
X1135750Y1255672D03*
X1127179Y1372700D03*
X1124679D03*
Y1370200D03*
X1127179D03*
X1129729Y1372700D03*
Y1370200D03*
Y1375200D03*
X1127179D03*
X1124679D03*
X1129729Y1377700D03*
Y1380200D03*
Y1385200D03*
Y1382700D03*
X1127179D03*
X1124679D03*
X1127179Y1380200D03*
Y1377700D03*
X1124679D03*
Y1380200D03*
Y1385200D03*
X1127179D03*
X1122879Y1431474D03*
Y1434024D03*
X1125995Y1439780D03*
X1123379Y1443583D03*
X1133169Y1445690D03*
X1129169Y1442998D03*
X1135568Y1442923D03*
X1129169Y1445719D03*
X1130841Y1462953D03*
X1128341Y1465453D03*
Y1462953D03*
X1130841Y1465453D03*
X1133841Y1462953D03*
Y1465453D03*
X1128341Y1468453D03*
X1130841D03*
X1133841D03*
X1128341Y1460453D03*
X1130841D03*
X1133841D03*
Y1471453D03*
X1130841D03*
X1128341D03*
X1132187Y1582738D03*
X1135187D03*
X1132187Y1590738D03*
X1135187D03*
X1124862Y1615010D03*
X1140242Y101135D03*
X1152720Y180862D03*
X1148795Y213731D03*
X1141957Y227277D03*
X1144457D03*
X1139457D03*
X1146670Y230110D03*
X1147700Y362731D03*
X1137315Y379592D03*
X1147700Y368041D03*
X1138551Y503324D03*
X1144720Y501362D03*
Y498662D03*
X1142967Y592097D03*
X1138500Y586362D03*
X1142127Y586452D03*
X1140697Y608762D03*
X1150140Y610362D03*
X1144810Y613762D03*
X1142674Y1287608D03*
X1144247Y1372700D03*
Y1370200D03*
X1146797Y1372700D03*
X1149297D03*
X1146797Y1370200D03*
X1149297D03*
X1144247Y1375200D03*
X1146797D03*
X1149297D03*
X1144247Y1377700D03*
Y1380200D03*
Y1385200D03*
Y1382700D03*
X1146797D03*
X1149297D03*
X1146797Y1380200D03*
Y1377700D03*
X1149297Y1380200D03*
Y1377700D03*
Y1385200D03*
X1146797D03*
X1146563Y1436334D03*
X1141903D03*
X1144233Y1435584D03*
X1139573D03*
X1149469Y1437098D03*
X1151669Y1435698D03*
Y1438598D03*
X1137311Y1445191D03*
X1147203Y1441968D03*
X1149569Y1440098D03*
X1151669Y1441498D03*
X1147203Y1439068D03*
X1141591Y1462853D03*
Y1465353D03*
Y1468353D03*
Y1471353D03*
Y1460353D03*
X1150821Y1459607D03*
Y1456587D03*
X1138430Y1524150D03*
X1151497Y1524187D03*
X1153465Y1550301D03*
X1149528D03*
X1145410Y1540640D03*
X1143060Y1538380D03*
X1141654Y1550301D03*
X1137717Y1558020D03*
X1141690Y1552920D03*
X1152187Y1574738D03*
X1142187D03*
X1145187D03*
X1142187Y1582738D03*
X1145187D03*
X1152187D03*
X1141525Y1597630D03*
X1152187Y1590738D03*
X1142187D03*
X1145187D03*
X1140750Y1604330D03*
X1150380Y1602590D03*
X1146960Y1618960D03*
X1152257Y1628910D03*
X1155703Y73679D03*
X1165440Y176450D03*
X1168710Y176590D03*
X1159460Y194090D03*
X1160630Y213870D03*
X1159753Y361281D03*
X1159460Y366025D03*
X1156790Y363231D03*
X1161690Y374110D03*
X1164320Y451062D03*
X1156100Y456342D03*
X1167190Y526922D03*
X1158300Y585862D03*
X1170740Y602132D03*
X1155962Y746193D03*
X1156609Y1286685D03*
X1165279Y1372700D03*
X1162779D03*
X1167829D03*
X1162779Y1370200D03*
X1165279D03*
X1167829D03*
X1162779Y1375200D03*
X1165279D03*
X1167829D03*
Y1377700D03*
Y1380200D03*
Y1385200D03*
Y1382700D03*
X1165279D03*
X1162779D03*
X1165279Y1380200D03*
X1162779D03*
Y1377700D03*
X1165279D03*
X1162779Y1385200D03*
X1165279D03*
X1161022Y1431499D03*
Y1433999D03*
X1164138Y1439780D03*
X1154288Y1432502D03*
X1161522Y1443630D03*
X1167312Y1442998D03*
Y1445964D03*
X1159386Y1464253D03*
Y1466753D03*
X1156386Y1464253D03*
Y1466753D03*
X1159386Y1469253D03*
X1156386D03*
X1153821Y1459607D03*
Y1456587D03*
X1159386Y1461753D03*
X1159476Y1458918D03*
X1156386Y1461753D03*
X1156476Y1458918D03*
X1159446Y1456113D03*
X1156446D03*
X1167245Y1524187D03*
X1159371D03*
X1163308D03*
X1155433D03*
X1165276Y1550301D03*
X1169213D03*
X1157402D03*
X1161339D03*
X1161595Y1574738D03*
X1164595D03*
X1155187D03*
X1161595Y1582738D03*
X1164595D03*
X1155187D03*
X1163079Y1601479D03*
X1161595Y1590738D03*
X1164595D03*
X1155187D03*
X1169460Y1606630D03*
Y1616630D03*
Y1611630D03*
X1158030Y1619250D03*
X1164830Y1628830D03*
X1163970Y1620600D03*
X1169325Y1642600D03*
X1158325D03*
X1162383Y1652505D03*
X1164830Y1654632D03*
X1159930D03*
X1161076Y1680624D03*
X1157700Y1681100D03*
X1174120Y57111D03*
X1175926Y69151D03*
X1180676Y106858D03*
X1187413Y143132D03*
X1181420Y157962D03*
X1181700Y186962D03*
X1173314Y176452D03*
X1170595Y170056D03*
X1181476Y172247D03*
X1184510Y188962D03*
X1173100Y186962D03*
X1172925Y202174D03*
X1181369Y199234D03*
X1183460Y205342D03*
X1181470Y208802D03*
X1172835Y218174D03*
X1181500Y211962D03*
Y218462D03*
Y215962D03*
Y222162D03*
X1186653Y302242D03*
X1181450Y306052D03*
X1174120Y355362D03*
X1169690Y526922D03*
X1172310Y584562D03*
X1181300Y584762D03*
X1177570Y602052D03*
X1175217Y595762D03*
X1173020Y745972D03*
X1175573Y1286765D03*
X1172573D03*
X1182747Y1372700D03*
X1185297D03*
X1182747Y1370200D03*
X1185297D03*
X1182747Y1375200D03*
X1185297D03*
X1182747Y1380200D03*
Y1377700D03*
Y1385200D03*
Y1382700D03*
X1185297D03*
Y1377700D03*
Y1380200D03*
Y1385200D03*
X1184706Y1436334D03*
X1180046D03*
X1182376Y1435584D03*
X1177716D03*
X1171342Y1445650D03*
X1175454Y1445191D03*
X1173711Y1442923D03*
X1171182Y1524187D03*
X1184330Y1573260D03*
X1184290Y1570080D03*
X1171595Y1574738D03*
X1174595D03*
X1171595Y1582738D03*
X1174595D03*
X1183410Y1594450D03*
X1183440Y1591640D03*
X1171595Y1590738D03*
X1174595D03*
X1178140Y1601100D03*
X1184200Y1599900D03*
X1183320Y1597080D03*
X1169968Y1602370D03*
X1174550Y1615630D03*
X1178250Y1609100D03*
X1184200Y1602700D03*
X1185030Y1624660D03*
X1180325Y1642600D03*
X1173383Y1652505D03*
X1184383D03*
X1181930Y1654632D03*
X1175830D03*
X1170930D03*
X1183076Y1680624D03*
X1172076D03*
X1194478Y56986D03*
X1197520Y56962D03*
X1201158Y57130D03*
X1189393Y60183D03*
X1188700Y100700D03*
X1185400Y104000D03*
X1193532Y132644D03*
X1194800Y143112D03*
X1197414Y161592D03*
X1191020Y170862D03*
X1185420Y153762D03*
X1200720Y184862D03*
X1188300Y189062D03*
X1200720Y187862D03*
X1200963Y212648D03*
X1200830Y206002D03*
X1186340Y204492D03*
X1187300Y217862D03*
X1188500Y205772D03*
X1188600Y225962D03*
X1187013Y238972D03*
X1194840Y236592D03*
X1199720Y252362D03*
X1196720D03*
X1188810Y296088D03*
X1186280Y298972D03*
X1193198Y586172D03*
X1195698D03*
X1198198D03*
X1200698D03*
X1185687Y744475D03*
X1187797Y1372700D03*
Y1370200D03*
Y1375200D03*
Y1382700D03*
Y1377700D03*
Y1380200D03*
Y1385200D03*
X1187412Y1437498D03*
X1189612Y1436098D03*
X1191918Y1432516D03*
X1185346Y1442128D03*
X1187512Y1440498D03*
X1189612Y1441898D03*
X1185346Y1439228D03*
X1189612Y1438998D03*
X1187720Y1517688D03*
X1187830Y1522188D03*
X1198546Y1520188D03*
X1187830Y1526688D03*
X1198546Y1524688D03*
X1187720Y1536362D03*
X1198485Y1534313D03*
X1198436Y1529362D03*
X1187720Y1531862D03*
Y1553692D03*
X1198497Y1539667D03*
X1187720Y1548772D03*
X1198436Y1546492D03*
X1187720Y1544292D03*
X1198436Y1551192D03*
Y1556192D03*
Y1561062D03*
X1187720Y1558682D03*
Y1563182D03*
X1194510Y1563076D03*
X1187600Y1622064D03*
X1201600Y1633790D03*
X1199400Y1627800D03*
X1190895Y1642910D03*
X1186000Y1640000D03*
X1197400Y1654942D03*
X1192500D03*
X1186830Y1654632D03*
X1193646Y1680934D03*
X1201106Y1677873D03*
X1190735Y1688390D03*
X1194793Y1698295D03*
X1201505Y1688435D03*
X1192340Y1700422D03*
X1197240D03*
X1193174Y1726414D03*
X1216176Y56742D03*
X1202860Y120392D03*
X1215763Y114363D03*
X1215800Y111300D03*
X1201700Y110000D03*
X1202920Y117162D03*
X1210910Y129502D03*
X1206114Y132962D03*
X1206434Y129492D03*
X1206694Y139512D03*
X1214415Y153962D03*
X1206664Y158952D03*
X1214091Y164962D03*
X1214534Y157462D03*
X1214054Y186092D03*
X1214693Y174962D03*
X1214134Y180972D03*
X1213720Y200309D03*
Y189362D03*
X1204220D03*
X1213720Y195362D03*
X1215720Y204862D03*
X1203200Y202514D03*
X1219060Y213312D03*
X1206660Y224742D03*
X1213540Y224792D03*
X1207220Y243998D03*
X1210900Y265300D03*
X1204475Y350684D03*
X1205165Y380962D03*
X1218870Y418082D03*
X1214000Y599262D03*
X1208980Y598462D03*
X1207100Y600882D03*
X1211277Y744265D03*
X1206757Y744455D03*
X1210288Y754081D03*
X1202300Y753962D03*
X1207607Y754095D03*
X1215896Y756942D03*
X1206432Y758995D03*
X1202307Y757082D03*
X1205820Y1652910D03*
X1210830Y1676500D03*
X1217210Y1684520D03*
X1212305Y1688700D03*
X1216363Y1698605D03*
X1205563Y1698340D03*
X1207180Y1685680D03*
X1208010Y1700467D03*
X1213910Y1700732D03*
X1203110Y1700467D03*
X1203939Y1726459D03*
X1214834Y1726724D03*
X1228425Y91500D03*
X1222100Y91600D03*
X1225100Y91500D03*
X1225700Y108962D03*
X1232182Y110659D03*
X1224614Y116962D03*
X1219534Y116492D03*
X1223500Y111162D03*
X1226400Y125200D03*
X1226093Y134262D03*
X1229500Y125100D03*
X1223100Y130700D03*
X1234093Y144962D03*
X1226093Y140962D03*
X1222593D03*
X1222920Y144909D03*
Y148909D03*
X1222593Y168962D03*
X1222890Y157002D03*
X1226093Y156962D03*
X1222594Y154242D03*
X1226093Y168162D03*
X1225874Y163462D03*
X1222720Y163362D03*
X1226093Y177962D03*
X1222724Y176102D03*
X1226093Y172962D03*
X1223134Y190802D03*
X1225574Y188662D03*
X1228520Y202162D03*
X1229720Y197302D03*
X1226093Y193462D03*
X1225320Y200162D03*
X1233282Y201875D03*
X1223180Y210552D03*
X1233780Y214572D03*
X1231720Y217862D03*
Y209862D03*
X1219220Y243862D03*
Y247148D03*
X1230720Y380362D03*
X1221220D03*
X1232720Y377862D03*
X1224300Y380400D03*
X1223650Y520672D03*
X1230650D03*
X1227150D03*
X1219060Y757272D03*
X1223327Y757615D03*
X1228320Y758598D03*
X1218810Y1700732D03*
X1236620Y58862D03*
X1241010Y110782D03*
X1250010Y117121D03*
X1244200Y112862D03*
X1249362Y111600D03*
X1241035Y114399D03*
X1234746Y136040D03*
X1240728Y136198D03*
X1240904Y151592D03*
X1238604Y150062D03*
X1241100Y145842D03*
X1244120Y167462D03*
X1246272Y164889D03*
X1243100Y160181D03*
X1243184Y182422D03*
X1239874Y182322D03*
X1236410Y201462D03*
X1236220Y189362D03*
X1236593Y197462D03*
X1236584Y205762D03*
X1245486Y203000D03*
X1245593Y211762D03*
X1236620Y221562D03*
X1244720Y230362D03*
X1245514Y224302D03*
X1245593Y219662D03*
X1239045Y224062D03*
X1246878Y248615D03*
X1240500Y248332D03*
Y244332D03*
X1236720Y257362D03*
X1243589Y379595D03*
X1236720Y377862D03*
X1234720Y380362D03*
X1248150Y520672D03*
X1244650D03*
X1241150D03*
X1237650D03*
X1234150D03*
X1242260Y757602D03*
X1261227Y52061D03*
X1258727D03*
X1263454Y83060D03*
X1266464Y83090D03*
X1264098Y88787D03*
X1262320Y96012D03*
X1258539Y100900D03*
X1252520Y92022D03*
X1258539Y109263D03*
X1260641Y114399D03*
X1264220Y110462D03*
X1250424Y108943D03*
X1257581Y114579D03*
X1256093Y149462D03*
X1264663Y158946D03*
X1254994Y157382D03*
X1265010Y162222D03*
X1261899Y174648D03*
X1253624Y201362D03*
X1267315Y220701D03*
X1264874Y217462D03*
X1256504D03*
X1255613Y209568D03*
X1265207Y208442D03*
X1259703Y209808D03*
X1253440Y230552D03*
X1253860Y235622D03*
X1256070Y229512D03*
X1264584Y226592D03*
X1256593Y221462D03*
Y233972D03*
Y225972D03*
X1253950Y246692D03*
X1266715Y244692D03*
X1254370Y241302D03*
X1265065Y249982D03*
X1256494Y243177D03*
X1256574Y238662D03*
X1266518Y237042D03*
X1256584Y248002D03*
X1256454Y252122D03*
X1264854Y253996D03*
Y256496D03*
X1258883Y280558D03*
X1258250Y292986D03*
X1263150Y294726D03*
X1255150Y306211D03*
X1256220Y434362D03*
X1261220Y454362D03*
X1253220Y451362D03*
X1267220D03*
X1260220Y477362D03*
X1255920Y511362D03*
X1251650Y520672D03*
X1255150D03*
X1258667Y751405D03*
X1255520Y747362D03*
X1263486Y739949D03*
X1257672Y1351008D03*
X1276820Y58142D03*
X1282360Y58132D03*
X1279580D03*
X1279390Y87697D03*
X1275820Y87962D03*
X1270329Y101011D03*
X1266722Y101005D03*
X1278456Y96187D03*
X1279415Y90847D03*
X1281704Y95402D03*
X1282824Y108872D03*
X1271284Y108971D03*
X1282764Y135398D03*
X1277820Y140682D03*
X1281093Y144516D03*
X1271954Y159143D03*
X1271593Y165962D03*
X1278093Y184462D03*
X1278993Y193262D03*
X1273093Y200038D03*
X1278183Y201262D03*
X1275493Y193962D03*
X1267289Y192167D03*
X1269904Y192692D03*
X1272893Y191262D03*
X1271315Y220701D03*
X1267773Y208373D03*
X1273093Y213962D03*
X1275727Y209597D03*
X1267618Y225382D03*
X1277661Y225685D03*
X1267593Y229462D03*
X1278783Y221386D03*
X1282176Y221436D03*
X1282654Y226309D03*
X1278320Y239292D03*
X1279493Y248662D03*
X1282645Y255671D03*
Y252271D03*
X1277771Y255173D03*
X1273754Y256504D03*
X1276800Y276562D03*
X1269960Y294536D03*
X1271150Y305792D03*
X1272530Y429362D03*
X1284220D03*
X1280270Y434362D03*
X1272220D03*
X1278380Y463362D03*
X1276220Y477362D03*
X1283220D03*
X1269220D03*
X1274420Y463362D03*
X1275576Y730879D03*
X1266727Y752955D03*
X1279788Y1304042D03*
X1279812Y1353552D03*
X1279334Y1356089D03*
X1275856Y1358098D03*
X1271990Y1358079D03*
X1276891Y1362891D03*
X1282928Y1361833D03*
X1269012Y1371693D03*
Y1368293D03*
X1285201Y58121D03*
X1293454Y81232D03*
X1289210D03*
X1298640Y93062D03*
X1292880Y93162D03*
X1292899Y98519D03*
X1294354Y103166D03*
X1291704Y109427D03*
X1288093Y125962D03*
X1291478Y137745D03*
X1286150Y131092D03*
X1297605Y145824D03*
X1285710Y249182D03*
X1290293Y247562D03*
X1288637Y240448D03*
X1292630Y240462D03*
X1291071Y275543D03*
Y278543D03*
X1290005Y293768D03*
Y290268D03*
X1294500Y299692D03*
X1291100D03*
X1291500Y312862D03*
Y315362D03*
X1291420Y320662D03*
Y318162D03*
X1295540Y440902D03*
X1301310Y440862D03*
X1291220Y463362D03*
X1294440Y477267D03*
X1296630Y463462D03*
X1300220Y477362D03*
X1284220Y463362D03*
X1289936Y732539D03*
X1290520Y746562D03*
X1292572Y785575D03*
X1297298Y790982D03*
X1296719Y1290197D03*
X1299169Y1295467D03*
Y1297967D03*
X1296569D03*
Y1295467D03*
Y1292967D03*
X1299169D03*
X1296581Y1300474D03*
X1299181D03*
X1296576Y1303298D03*
X1299176D03*
X1290102Y1365789D03*
X1286102Y1365051D03*
X1294312Y1367279D03*
X1292840Y1364821D03*
X1286102Y1368107D03*
X1298836Y1358387D03*
X1296506Y1357637D03*
X1301820Y58672D03*
X1311424Y68652D03*
X1308174D03*
X1311960Y58152D03*
X1311260Y83032D03*
X1310857Y78542D03*
X1307120Y78562D03*
X1310906Y97807D03*
X1314406Y97756D03*
X1308274Y104162D03*
X1314059Y93877D03*
X1307244Y118452D03*
X1306836Y108242D03*
X1302080Y117032D03*
X1302060Y113852D03*
X1300990Y121812D03*
X1315156Y130656D03*
X1314920Y135361D03*
X1313117Y250605D03*
X1314685Y248651D03*
X1307431Y256099D03*
X1309283Y254162D03*
X1311275Y252297D03*
X1305552Y257974D03*
X1308736Y284948D03*
X1312136D03*
X1307042Y292636D03*
X1303642D03*
X1307442Y306998D03*
X1304042D03*
X1307677Y322996D03*
X1311077D03*
X1317100Y553900D03*
X1308600Y653500D03*
X1303576Y659671D03*
X1311420Y738262D03*
X1305187Y735630D03*
X1315020Y739862D03*
X1307469Y787772D03*
X1301034Y784165D03*
X1304260Y788265D03*
X1309930Y789852D03*
X1306701Y794779D03*
X1305117Y797125D03*
X1309210Y792802D03*
X1315169Y1274887D03*
X1315289Y1269717D03*
X1315229Y1272287D03*
X1304149Y1291317D03*
X1301889Y1284987D03*
X1301829Y1290167D03*
X1301859Y1287587D03*
X1304299Y1280967D03*
X1304269Y1283567D03*
X1304239Y1286147D03*
X1304209Y1288747D03*
X1315176Y1280218D03*
X1315181Y1277594D03*
X1299319Y1290197D03*
X1299349Y1287617D03*
X1301686Y1303268D03*
X1304196Y1299248D03*
X1304189Y1293917D03*
X1304201Y1296624D03*
X1301679Y1292937D03*
Y1295437D03*
Y1297937D03*
X1301691Y1300444D03*
X1311820Y1330518D03*
Y1333018D03*
X1314936Y1338799D03*
X1312650Y1342572D03*
X1308616Y1363345D03*
Y1360445D03*
X1306082Y1359315D03*
X1306182Y1362315D03*
X1304016Y1363945D03*
Y1361045D03*
X1308616Y1357945D03*
X1303496Y1358387D03*
X1301166Y1357637D03*
X1316459Y58697D03*
X1322248Y68487D03*
X1321279Y58767D03*
X1317831Y68652D03*
X1322415Y75480D03*
X1322906Y94212D03*
X1319968Y98266D03*
X1329891Y99455D03*
X1329646Y104954D03*
X1322906Y109733D03*
X1323912Y245111D03*
X1320387Y258901D03*
X1325769Y259001D03*
X1325414Y293556D03*
X1328814D03*
X1319903Y299176D03*
X1323303D03*
X1319618Y318073D03*
X1325080Y323902D03*
X1316218Y318073D03*
X1328480Y323902D03*
X1330101Y540049D03*
X1328530Y747702D03*
X1325210Y744322D03*
X1331519Y1262027D03*
X1331459Y1264597D03*
X1331399Y1267197D03*
X1317889Y1267147D03*
X1320399Y1267117D03*
X1317883Y1269978D03*
X1317895Y1272485D03*
X1320393Y1269948D03*
X1320405Y1272455D03*
X1331177Y1269933D03*
Y1272433D03*
X1317895Y1274985D03*
X1320405Y1274955D03*
X1331177Y1274933D03*
X1331166Y1280248D03*
X1317746D03*
X1320256Y1280218D03*
X1317895Y1277485D03*
X1320405Y1277455D03*
X1331189Y1277440D03*
X1328514Y1334603D03*
X1330844Y1335353D03*
X1322110Y1342755D03*
X1318110Y1342017D03*
X1326320Y1344245D03*
X1324848Y1341787D03*
X1318110Y1345073D03*
X1331288Y1372440D03*
X1327491Y1372358D03*
X1324491Y1372658D03*
X1327491Y1375858D03*
X1331288Y1375940D03*
X1324491Y1375858D03*
X1327491Y1381478D03*
Y1378478D03*
X1331288Y1378560D03*
X1324491Y1381478D03*
Y1378478D03*
X1331304Y1401986D03*
Y1404986D03*
X1327926D03*
X1322228Y1419890D03*
X1322186Y1411326D03*
Y1414326D03*
Y1417326D03*
X1322270Y1422454D03*
X1325084Y1420066D03*
X1325042Y1408502D03*
Y1411502D03*
Y1417502D03*
Y1414502D03*
X1331344Y1414456D03*
X1330804Y1411536D03*
Y1408536D03*
X1331386Y1420020D03*
X1328008D03*
X1331344Y1417456D03*
X1327966Y1408456D03*
Y1411456D03*
Y1417456D03*
Y1414456D03*
X1331428Y1422584D03*
X1328050D03*
X1322312Y1425018D03*
X1325126Y1422630D03*
X1325168Y1425194D03*
X1328092Y1425148D03*
X1331470D03*
X1333190Y58825D03*
X1347640Y101950D03*
X1345583Y91307D03*
X1336549Y105970D03*
X1344631Y127244D03*
X1332497Y133931D03*
X1343034Y141698D03*
X1336761Y293404D03*
X1340161D03*
X1335145Y332616D03*
X1341431Y322693D03*
X1331745Y332616D03*
X1338031Y322693D03*
X1345424Y328981D03*
X1344720Y423162D03*
X1337220D03*
X1342220D03*
X1339720D03*
X1333143Y540049D03*
X1340420Y538422D03*
Y541822D03*
X1347419Y1259257D03*
X1347379Y1256687D03*
X1336269Y1274957D03*
X1333969Y1264567D03*
X1334029Y1261997D03*
X1333909Y1267167D03*
X1336339Y1269777D03*
X1336279Y1272347D03*
X1347359Y1261857D03*
X1347371Y1264564D03*
X1336519Y1264627D03*
X1336579Y1262057D03*
X1347366Y1267188D03*
X1336459Y1267227D03*
X1333687Y1269903D03*
Y1272403D03*
Y1274903D03*
X1333676Y1280218D03*
X1336261Y1277654D03*
X1333699Y1277410D03*
X1343948Y1317092D03*
Y1319592D03*
X1344532Y1328161D03*
X1347397Y1325320D03*
X1336144Y1341147D03*
X1338288Y1339653D03*
X1340488Y1340853D03*
X1336144Y1338247D03*
X1340214Y1334853D03*
X1340410Y1338017D03*
X1338288Y1336553D03*
X1333174Y1334603D03*
X1335504Y1335353D03*
X1334288Y1372440D03*
X1340288D03*
X1346193Y1372523D03*
X1343193D03*
X1337288Y1372440D03*
Y1375940D03*
X1334288D03*
X1343193Y1376023D03*
X1346193D03*
X1340288Y1375940D03*
X1346304Y1401986D03*
X1343304D03*
X1340304D03*
X1337304D03*
X1334304D03*
Y1404986D03*
X1346304D03*
X1343304D03*
X1340304D03*
X1337304D03*
X1337344Y1414456D03*
X1346344D03*
X1343344D03*
X1340344D03*
X1346534Y1411496D03*
Y1408496D03*
X1334344Y1414456D03*
X1346344Y1417456D03*
X1340344D03*
X1337344D03*
X1334386Y1420020D03*
X1334344Y1417456D03*
X1346386Y1420020D03*
X1343386D03*
X1340386D03*
X1337386D03*
X1343344Y1417456D03*
X1337428Y1422584D03*
X1340428D03*
X1343428D03*
X1334428D03*
X1337328Y1425164D03*
X1340328D03*
X1343328D03*
X1346178Y1425254D03*
X1346278Y1422674D03*
X1334470Y1425148D03*
X1348610Y84712D03*
X1349480Y77072D03*
X1366369Y83820D03*
X1349570Y104147D03*
X1353394Y131812D03*
X1348620Y136162D03*
X1349220Y140362D03*
X1348824Y328981D03*
X1358371Y332275D03*
X1361771D03*
X1355200Y337843D03*
X1351800D03*
X1356220Y581862D03*
X1356047Y680000D03*
X1358907Y681262D03*
X1361727Y680665D03*
X1352474Y1256866D03*
X1349964Y1256896D03*
X1352486Y1259373D03*
X1349976Y1259403D03*
X1363258Y1256851D03*
Y1259351D03*
X1349876Y1267158D03*
X1352426Y1267218D03*
X1363266Y1267188D03*
X1349976Y1261903D03*
X1352486Y1261873D03*
Y1264373D03*
X1349976Y1264403D03*
X1363258Y1261851D03*
X1363270Y1264358D03*
X1360593Y1321872D03*
X1363098Y1320951D03*
X1354238Y1329329D03*
X1350238Y1328591D03*
X1358448Y1330819D03*
X1356976Y1328361D03*
X1350238Y1331647D03*
X1352666Y1378560D03*
X1349666D03*
X1352666Y1381560D03*
X1349666D03*
X1352666Y1375940D03*
X1349666D03*
X1352126Y1401986D03*
X1349426D03*
X1352126Y1404986D03*
X1349426D03*
X1349508Y1420020D03*
X1352166Y1420456D03*
Y1414456D03*
Y1411456D03*
Y1408456D03*
Y1417456D03*
X1349466Y1411456D03*
Y1408456D03*
Y1417456D03*
Y1414456D03*
X1349278Y1422674D03*
X1364860Y1455172D03*
X1362410Y1445272D03*
X1378839Y87626D03*
X1366369Y92450D03*
X1366714Y109506D03*
X1376991Y176430D03*
X1373591D03*
X1375619Y236261D03*
X1375257Y229756D03*
X1373493Y227762D03*
X1370207Y682245D03*
X1374938Y1161569D03*
Y1170069D03*
X1379579Y1259317D03*
X1368379Y1259287D03*
X1379639Y1256747D03*
X1368439Y1256717D03*
X1365768Y1256821D03*
Y1259321D03*
X1365776Y1267158D03*
X1368326Y1267218D03*
X1379519Y1261917D03*
X1379531Y1264624D03*
X1379526Y1267248D03*
X1368361Y1264594D03*
X1368369Y1261897D03*
X1365768Y1261821D03*
X1365780Y1264328D03*
X1376076Y1317092D03*
Y1319592D03*
X1379192Y1325373D03*
X1368272Y1324821D03*
X1372538Y1324591D03*
X1370338Y1323091D03*
X1372538Y1321691D03*
X1365376Y1321938D03*
X1367635Y1320904D03*
X1377214Y1327653D03*
X1368272Y1327721D03*
X1370438Y1326091D03*
X1372538Y1327491D03*
X1377054Y1394028D03*
X1367316Y1399053D03*
Y1403458D03*
X1370577Y1421899D03*
X1367436Y1414778D03*
X1370891Y1410306D03*
X1378417Y1415292D03*
X1367316Y1407458D03*
X1367889Y1419235D03*
X1377075Y1425014D03*
X1365235Y1428637D03*
X1370250Y1433715D03*
X1367620Y1431472D03*
X1367170Y1453142D03*
X1368842Y1449261D03*
X1364800Y1449231D03*
X1368980Y1457122D03*
X1370041Y1460374D03*
X1393250Y93802D03*
X1386684Y145017D03*
X1386404Y149008D03*
X1394182Y171470D03*
X1398182D03*
X1395960Y226422D03*
X1393460D03*
X1386868Y222937D03*
X1384017Y223697D03*
X1386138Y225411D03*
X1384895Y221346D03*
X1381951Y221420D03*
X1381235Y236020D03*
X1390600Y248262D03*
X1392685Y498992D03*
X1387550Y502922D03*
X1387600Y499182D03*
X1391260Y507082D03*
X1396081Y1161569D03*
Y1153369D03*
Y1170069D03*
X1384652Y1256866D03*
X1382142Y1256896D03*
X1384664Y1259373D03*
X1382154Y1259403D03*
X1395436Y1256851D03*
Y1259351D03*
X1384586Y1267278D03*
X1395426Y1267188D03*
X1382036Y1267218D03*
X1382154Y1261903D03*
X1384664Y1261873D03*
Y1264373D03*
X1382154Y1264403D03*
X1395436Y1261851D03*
X1395448Y1264358D03*
X1392770Y1321177D03*
X1395100Y1321927D03*
X1386366Y1329329D03*
X1382366Y1328591D03*
X1390576Y1330819D03*
X1389104Y1328361D03*
X1382366Y1331647D03*
X1396311Y1385712D03*
X1398680Y1380582D03*
X1390474Y1385142D03*
X1387074Y1384272D03*
X1390513Y1395452D03*
X1387066Y1401734D03*
X1387291Y1408163D03*
X1387470Y1418302D03*
X1385109Y1410427D03*
X1390170Y1423942D03*
X1387068Y1413991D03*
X1381066Y1425008D03*
X1393630Y1426562D03*
X1388557Y1431645D03*
X1395907Y1430227D03*
X1395443Y1434700D03*
X1398569Y1437860D03*
X1383429Y1427652D03*
X1392620Y1446708D03*
X1389220D03*
X1382600Y1563480D03*
X1391655Y1570037D03*
X1391055Y1565037D03*
X1384840Y1565640D03*
X1386790Y1563610D03*
X1396600Y1590200D03*
Y1586400D03*
X1393000Y1590300D03*
X1395325Y1606862D03*
X1386200Y1645700D03*
X1386600Y1641400D03*
X1407029Y152732D03*
X1410370Y138742D03*
X1406970D03*
X1407029Y156132D03*
X1401341Y177159D03*
X1404829Y184263D03*
X1404741Y177159D03*
X1408229Y184263D03*
X1407178Y171684D03*
X1403778D03*
X1413900Y225212D03*
X1396900Y228932D03*
X1398831Y1161569D03*
Y1153369D03*
Y1170069D03*
X1411909Y1259257D03*
X1400599Y1256717D03*
X1411969Y1256687D03*
X1397946Y1256821D03*
Y1259321D03*
X1400539Y1259287D03*
X1400521Y1264594D03*
X1400529Y1261897D03*
X1397936Y1267158D03*
X1400486Y1267218D03*
X1411849Y1261857D03*
X1411861Y1264564D03*
X1411856Y1267188D03*
X1397946Y1261821D03*
X1397958Y1264328D03*
X1408204Y1317092D03*
Y1319592D03*
X1411320Y1325373D03*
X1400400Y1324821D03*
X1404666Y1324591D03*
X1402466Y1323091D03*
X1404666Y1321691D03*
X1397430Y1321177D03*
X1399760Y1321927D03*
X1408969Y1327645D03*
X1402566Y1326091D03*
X1400400Y1327721D03*
X1404666Y1327491D03*
X1401655Y1384676D03*
X1406461Y1383862D03*
X1415171Y1383692D03*
X1412961Y1387387D03*
X1412608Y1391687D03*
X1414362Y1402191D03*
X1414786Y1426890D03*
X1413440Y1436774D03*
X1409680Y1430613D03*
X1401371Y1434592D03*
X1410477Y1440117D03*
X1410038Y1434670D03*
X1403687Y1444711D03*
X1400287D03*
X1400220Y1518862D03*
X1409248Y1528862D03*
X1400160Y1543342D03*
X1404433Y1565037D03*
X1400695Y1570037D03*
X1400715Y1565037D03*
X1407440Y1557552D03*
X1404433Y1570037D03*
X1402536Y1576097D03*
X1402680Y1597700D03*
X1401300Y1619917D03*
X1410900Y1624800D03*
X1400000Y1626362D03*
Y1634362D03*
Y1638362D03*
X1410500Y1638862D03*
X1396900Y1642100D03*
X1413950Y184263D03*
X1423110D03*
X1417350D03*
X1426510D03*
X1428336Y232762D03*
X1415340Y231812D03*
X1418630Y220018D03*
X1422030D03*
X1413847Y239528D03*
X1426020Y261501D03*
X1431430Y256383D03*
Y264060D03*
X1426647Y329050D03*
X1417022Y621419D03*
X1424119Y1161520D03*
X1426619D03*
X1424119Y1153369D03*
X1426619D03*
Y1169570D03*
X1424119D03*
X1416999Y1256866D03*
X1414489Y1256896D03*
X1417011Y1259373D03*
X1414501Y1259403D03*
X1427783Y1256851D03*
Y1259351D03*
X1414366Y1267158D03*
X1416916Y1267218D03*
X1427786Y1267158D03*
X1414501Y1261903D03*
X1417011Y1261873D03*
Y1264373D03*
X1414501Y1264403D03*
X1427783Y1261851D03*
X1427795Y1264358D03*
X1424898Y1321177D03*
X1427228Y1321927D03*
X1418494Y1329329D03*
X1414494Y1328591D03*
X1422704Y1330819D03*
X1421232Y1328361D03*
X1414494Y1331647D03*
X1418990Y1387452D03*
X1422594Y1383301D03*
X1419995Y1397492D03*
X1415620Y1396652D03*
X1419055Y1392497D03*
X1426872Y1405811D03*
X1423256Y1403728D03*
X1424255Y1396612D03*
X1421480Y1415731D03*
X1422371Y1407722D03*
X1421371Y1411719D03*
X1421864Y1419730D03*
X1419991Y1423404D03*
X1424930Y1433850D03*
X1416272Y1433949D03*
X1421435Y1430415D03*
X1419746Y1435932D03*
X1414350Y1516435D03*
X1426020Y1521535D03*
X1414590Y1532255D03*
X1414350Y1521335D03*
X1427120Y1537355D03*
X1414590Y1537155D03*
X1414740Y1543475D03*
Y1548375D03*
X1427320Y1548575D03*
X1425620Y1556662D03*
X1416060Y1574922D03*
X1422680Y1582100D03*
X1419450Y1596150D03*
X1423700Y1600400D03*
X1434600Y59262D03*
X1444275Y57262D03*
X1432220Y61862D03*
X1440800Y66862D03*
X1447340Y157402D03*
X1442434Y210757D03*
X1430120Y225182D03*
X1431636Y230448D03*
X1444570Y238372D03*
X1431933Y238125D03*
X1431431Y267378D03*
X1436120Y315772D03*
X1436270Y312592D03*
X1436335Y309407D03*
X1436320Y305862D03*
Y303362D03*
X1436050Y321352D03*
X1436120Y318272D03*
X1436232Y344176D03*
X1433418Y729104D03*
X1444099Y1259397D03*
X1432899Y1259257D03*
X1444159Y1256827D03*
X1432959Y1256687D03*
X1430293Y1256821D03*
Y1259321D03*
X1444051Y1264704D03*
X1444039Y1261997D03*
X1444046Y1267328D03*
X1432889Y1261867D03*
X1432881Y1264564D03*
X1432846Y1267188D03*
X1430296Y1267128D03*
X1430293Y1261821D03*
X1430305Y1264328D03*
X1440332Y1317092D03*
Y1319592D03*
X1443448Y1325373D03*
X1432528Y1324821D03*
X1436794Y1324591D03*
X1434594Y1323091D03*
X1436794Y1321691D03*
X1429558Y1321177D03*
X1431888Y1321927D03*
X1441332Y1327793D03*
X1434694Y1326091D03*
X1432528Y1327721D03*
X1436794Y1327491D03*
X1437443Y1406289D03*
X1444997Y1392885D03*
X1435462Y1393009D03*
Y1396409D03*
X1434312Y1415197D03*
X1443112Y1417929D03*
X1445020Y1412672D03*
X1443676Y1432624D03*
X1433750Y1429208D03*
X1439742Y1436924D03*
X1434720Y1454862D03*
X1440440Y1454892D03*
X1444468Y1570610D03*
X1433720Y1569762D03*
X1440105Y1593352D03*
X1446700Y1598400D03*
X1438300Y1606800D03*
Y1602600D03*
X1430250Y1612812D03*
X1441800Y1628700D03*
Y1624500D03*
X1438547Y1638212D03*
X1443617D03*
X1431575Y1634842D03*
X1442573Y1649862D03*
X1442587Y1659242D03*
X1438320Y1668292D03*
X1438220Y1673955D03*
X1446715Y1679957D03*
X1446000Y67802D03*
X1458720Y145362D03*
X1450270Y143022D03*
X1450720Y153362D03*
X1448820Y148092D03*
X1450720Y169862D03*
Y161862D03*
X1449740Y166912D03*
X1450720Y181862D03*
Y177862D03*
Y173862D03*
X1462561Y205982D03*
X1457361D03*
X1459961Y210432D03*
X1456150Y214382D03*
X1449110Y233742D03*
X1455600Y297200D03*
X1456770Y342942D03*
X1460849Y343327D03*
X1462790Y359042D03*
X1462870Y355012D03*
X1449777Y362021D03*
X1459900Y370823D03*
X1455920Y373941D03*
X1463600Y374462D03*
X1449777Y371039D03*
X1455642Y409646D03*
X1449296Y407347D03*
X1449600Y402322D03*
X1456777Y418596D03*
Y426546D03*
X1456237Y726945D03*
X1457620Y736195D03*
X1460187Y729805D03*
X1455692Y731401D03*
X1457714Y741622D03*
X1447149Y1161569D03*
X1449649D03*
X1447299Y1153369D03*
X1449799D03*
X1447149Y1170069D03*
X1449649D03*
X1449176Y1256866D03*
X1446666Y1256896D03*
X1449188Y1259373D03*
X1446678Y1259403D03*
X1459960Y1259351D03*
Y1256851D03*
X1449106Y1267358D03*
X1459886Y1267218D03*
X1446556Y1267298D03*
X1446678Y1261903D03*
X1449188Y1261873D03*
Y1264373D03*
X1446678Y1264403D03*
X1459960Y1261851D03*
X1459972Y1264358D03*
X1457026Y1321177D03*
X1461686D03*
X1459356Y1321927D03*
X1450622Y1329329D03*
X1446622Y1328591D03*
X1454832Y1330819D03*
X1453360Y1328361D03*
X1446622Y1331647D03*
X1459968Y1402765D03*
X1451176Y1399026D03*
X1451198Y1403047D03*
X1460224Y1407545D03*
X1458138Y1409955D03*
X1461062Y1413246D03*
X1455006Y1447938D03*
X1459111Y1445669D03*
Y1448669D03*
X1457577Y1526689D03*
X1457817Y1542509D03*
X1457967Y1553729D03*
X1458200Y1565037D03*
Y1560037D03*
X1448620Y1556162D03*
X1456030Y1590302D03*
X1456120Y1586262D03*
X1453600Y1595662D03*
X1451500Y1612800D03*
X1454167Y1638302D03*
X1459127D03*
X1448507Y1638212D03*
X1448920Y1675062D03*
X1474142Y61767D03*
X1462000Y153362D03*
X1470220Y169862D03*
X1473090Y204502D03*
X1472335Y209362D03*
X1467761Y205982D03*
X1471308Y230640D03*
X1463833Y230448D03*
X1474660Y252878D03*
X1463808Y244948D03*
X1463833Y235566D03*
X1473820Y265962D03*
X1471510Y252878D03*
X1471690Y259862D03*
X1463950Y258172D03*
X1463330Y264060D03*
X1463510Y273878D03*
X1475452Y289708D03*
X1475352Y306308D03*
X1476826Y312177D03*
X1467700Y370953D03*
X1472758Y370817D03*
X1465836Y408668D03*
X1470942Y409718D03*
X1475250Y401812D03*
X1469777Y418396D03*
X1469951Y429251D03*
X1469720Y434542D03*
X1469760Y452622D03*
X1471460Y633402D03*
X1468060D03*
X1465171Y647132D03*
X1469020Y647102D03*
X1470841Y721493D03*
X1464999Y1259317D03*
X1476369Y1259237D03*
X1465059Y1256747D03*
X1462470Y1259321D03*
Y1256821D03*
X1476291Y1275224D03*
X1464946Y1267248D03*
X1464989Y1261927D03*
X1464981Y1264624D03*
X1476339Y1264467D03*
Y1267037D03*
X1476309Y1261807D03*
X1476279Y1269637D03*
X1476291Y1272344D03*
X1462396Y1267188D03*
X1462470Y1261821D03*
X1462482Y1264328D03*
X1476291Y1278104D03*
X1464016Y1321927D03*
X1466819Y1324018D03*
X1469019Y1322618D03*
X1473956Y1341068D03*
X1472460Y1330493D03*
Y1333043D03*
X1475576Y1338799D03*
X1469019Y1325518D03*
X1464680Y1325772D03*
X1469019Y1328418D03*
X1466919Y1327018D03*
X1464680Y1328672D03*
X1467567Y1445669D03*
Y1448669D03*
X1475967Y1445669D03*
Y1448669D03*
X1478320Y1522962D03*
X1472565Y1623635D03*
X1478061Y1633864D03*
X1463767Y1638302D03*
X1476570Y1661124D03*
X1493120Y240412D03*
X1487958Y236062D03*
X1490060Y255378D03*
X1485320Y260362D03*
X1478745Y281508D03*
X1493289Y280027D03*
X1478526Y289677D03*
X1481445Y289708D03*
X1479745Y312208D03*
X1478426Y306277D03*
X1481345Y306308D03*
X1481484Y361688D03*
X1481766Y372288D03*
X1489443D03*
X1494784Y374188D03*
X1486040Y368392D03*
X1481766Y406238D03*
X1490384Y407292D03*
X1493384Y411313D03*
X1482650Y411190D03*
X1495527Y406215D03*
X1486880Y416863D03*
X1484805Y427577D03*
X1489310Y426822D03*
X1481539Y1259377D03*
X1478999Y1259257D03*
X1481479Y1261947D03*
X1481419Y1264547D03*
X1481431Y1267254D03*
X1478939Y1261827D03*
X1478879Y1264427D03*
X1478891Y1267134D03*
X1481359Y1271447D03*
X1492039D03*
X1481359Y1274144D03*
X1492091D03*
X1478859Y1271417D03*
Y1274114D03*
X1481361Y1280054D03*
X1492101D03*
X1478821D03*
X1481359Y1277024D03*
X1492091D03*
X1478859Y1276994D03*
X1489154Y1334603D03*
X1493814D03*
X1491484Y1335353D03*
X1482750Y1342755D03*
X1478750Y1342017D03*
X1486960Y1344245D03*
X1485488Y1341787D03*
X1478750Y1345073D03*
X1485387Y1420002D03*
X1481918Y1425579D03*
X1484442Y1445557D03*
Y1448557D03*
X1482830Y1525162D03*
X1480800Y1663600D03*
X1510500Y125992D03*
X1508959Y215802D03*
X1503020D03*
X1499922Y211240D03*
X1496720Y225292D03*
X1504484Y234562D03*
X1508410Y230842D03*
X1510017Y225516D03*
X1501840Y225502D03*
X1512420Y239116D03*
X1510810Y249742D03*
X1509040Y243362D03*
X1504890Y249862D03*
X1506600Y239092D03*
X1504650Y254392D03*
X1508049Y280056D03*
X1498984Y282797D03*
X1508558Y291175D03*
X1512244Y311522D03*
X1505922Y304583D03*
X1509539Y308467D03*
X1498184Y361723D03*
Y369798D03*
X1495150Y369842D03*
X1503450Y385843D03*
X1509638Y738627D03*
X1509350Y741315D03*
X1504747Y747293D03*
X1503514Y801361D03*
Y797961D03*
X1497199Y1275667D03*
X1497259Y1273097D03*
X1494629Y1271477D03*
X1494631Y1274144D03*
X1506569Y1285947D03*
X1508819Y1284797D03*
X1506539Y1288557D03*
X1508759Y1287367D03*
X1508699Y1289967D03*
X1494641Y1280054D03*
X1494631Y1277024D03*
X1506551Y1291254D03*
X1497199Y1278277D03*
X1497161Y1280974D03*
X1506689Y1283377D03*
X1506591Y1297014D03*
Y1294134D03*
X1508711Y1295554D03*
Y1298434D03*
Y1292674D03*
X1496784Y1341147D03*
X1498924Y1334882D03*
X1498950Y1339517D03*
X1501149Y1336287D03*
X1496784Y1338247D03*
X1496144Y1335353D03*
X1504588Y1353316D03*
Y1355816D03*
X1501033Y1341462D03*
X1498959Y1342930D03*
X1505570Y1364212D03*
X1507704Y1361597D03*
X1510027Y1425825D03*
X1507617Y1424045D03*
X1522920Y116180D03*
X1513900Y117762D03*
X1518575Y138662D03*
X1521115Y193262D03*
X1524539Y215551D03*
X1522009Y210825D03*
X1518110Y215551D03*
X1526998Y209645D03*
X1527732Y219488D03*
X1514520Y231116D03*
X1526152Y225114D03*
X1514593Y249698D03*
Y235116D03*
X1519758Y265161D03*
X1522786Y262558D03*
X1522258Y265161D03*
X1519833Y277297D03*
X1522258Y288956D03*
X1517669Y291516D03*
X1515940Y795815D03*
Y799215D03*
X1513789Y1290037D03*
X1511289Y1287397D03*
X1511199Y1290007D03*
X1513791Y1292704D03*
X1516351D03*
X1513791Y1298464D03*
Y1295584D03*
X1516351D03*
Y1298464D03*
X1511251Y1292704D03*
Y1298464D03*
Y1295584D03*
X1521282Y1357401D03*
X1525942D03*
X1514878Y1365553D03*
X1510878Y1364815D03*
X1519088Y1367043D03*
X1517616Y1364585D03*
X1510878Y1367871D03*
X1523612Y1358151D03*
X1512177Y1427795D03*
X1516137Y1432135D03*
X1513657Y1429985D03*
X1544010Y27552D03*
X1536310Y47492D03*
X1534060Y100162D03*
X1530660D03*
X1533520Y110662D03*
X1529500Y122122D03*
X1535575Y118862D03*
X1540090Y122782D03*
X1536925Y129937D03*
X1529500Y125862D03*
X1535520Y151562D03*
X1529233Y153162D03*
X1535450Y155262D03*
X1542401Y141561D03*
X1534720Y199803D03*
X1528720Y199862D03*
X1533385Y193108D03*
X1533148Y211614D03*
X1531824Y207677D03*
X1534194Y217519D03*
X1529670Y225522D03*
X1535561Y225393D03*
X1531110Y264862D03*
X1539150Y267132D03*
X1540958Y307756D03*
X1539720Y589862D03*
Y581862D03*
X1540377Y634165D03*
X1541211Y646178D03*
X1533178Y1360815D03*
X1530978Y1359315D03*
X1528912Y1361045D03*
X1531078Y1362315D03*
X1533178Y1363715D03*
X1528912Y1363945D03*
X1533178Y1357915D03*
X1528272Y1358151D03*
X1556413Y19495D03*
X1549308Y26431D03*
X1552708D03*
X1552960Y124359D03*
X1553189Y127781D03*
X1556049Y147711D03*
X1545763Y159305D03*
X1551160Y189342D03*
X1557900Y220362D03*
X1557760Y214792D03*
X1550353Y217352D03*
X1557320Y203297D03*
X1559400Y229832D03*
X1545668Y305266D03*
X1545768Y302766D03*
X1543958Y307556D03*
X1546458Y307856D03*
X1543858Y310056D03*
X1543720Y581862D03*
X1548720D03*
X1552720Y589862D03*
Y581862D03*
X1554753Y628860D03*
X1553312Y636815D03*
X1559354Y655716D03*
Y659116D03*
X1550487Y681565D03*
X1550320Y696562D03*
X1550917Y704332D03*
X1550390Y709885D03*
X1570586Y19495D03*
X1573986D03*
X1559813D03*
X1563481Y26431D03*
X1566881D03*
X1573560Y245078D03*
X1574760Y251032D03*
X1559722Y243110D03*
X1570675Y267857D03*
X1573246Y306650D03*
X1572396Y309450D03*
X1563714Y572792D03*
X1567114D03*
X1559557Y593290D03*
X1564768Y708159D03*
X1562871Y732316D03*
Y735716D03*
X1571577Y747145D03*
X1567547Y755485D03*
X1571920Y762662D03*
X1568490Y758162D03*
X1570374Y760093D03*
X1584759Y19495D03*
X1588159D03*
X1577654Y26431D03*
X1591828D03*
X1581054D03*
X1576589Y300927D03*
X1588314Y592553D03*
X1585714D03*
X1583114D03*
X1590914D03*
X1588254Y595103D03*
X1588284Y597613D03*
X1585654Y595103D03*
X1585684Y597613D03*
X1583084D03*
X1583054Y595103D03*
X1588284Y608655D03*
X1585684D03*
X1583084D03*
X1590854Y595103D03*
X1590884Y597613D03*
Y608655D03*
X1588254Y613715D03*
X1588224Y611205D03*
X1585654Y613715D03*
X1585624Y611205D03*
X1583024D03*
X1583054Y613715D03*
X1590854D03*
X1590824Y611205D03*
X1591368Y628727D03*
X1591428Y626177D03*
X1588928D03*
X1588868Y628727D03*
X1591398Y631237D03*
X1588898D03*
X1591368Y650877D03*
X1591338Y648367D03*
X1591398Y645817D03*
X1588868Y650877D03*
X1588838Y648367D03*
X1588898Y645817D03*
X1591368Y653377D03*
X1588868D03*
X1591448Y657677D03*
X1588948D03*
Y660177D03*
X1591448D03*
X1588968Y665237D03*
X1591468D03*
X1588938Y662727D03*
X1591438D03*
X1588938Y679807D03*
X1588878Y682357D03*
X1588908Y684867D03*
X1591438Y679807D03*
X1591378Y682357D03*
X1591408Y684867D03*
X1591328Y696727D03*
X1591388Y694177D03*
X1588888D03*
X1588828Y696727D03*
X1591358Y699277D03*
X1588858D03*
X1591358Y718837D03*
X1591328Y716327D03*
X1591388Y713777D03*
X1588858Y718837D03*
X1588828Y716327D03*
X1588888Y713777D03*
X1590915Y755793D03*
X1598933Y19495D03*
X1602333D03*
X1595228Y26431D03*
X1603747Y192951D03*
X1603530Y202402D03*
X1603706Y211526D03*
X1603580Y206902D03*
X1604200Y234642D03*
X1604240Y227892D03*
X1603920Y222922D03*
X1604270Y231490D03*
X1604240Y238242D03*
X1602980Y560002D03*
X1593514Y592553D03*
X1601830Y590685D03*
X1604430D03*
X1607200Y583962D03*
X1593484Y597613D03*
X1593454Y595103D03*
X1593484Y608655D03*
X1593424Y611205D03*
X1593454Y613715D03*
X1601830Y615201D03*
X1604430D03*
X1598868Y628727D03*
X1598928Y626177D03*
X1593868Y628727D03*
X1593928Y626177D03*
X1596428D03*
X1596368Y628727D03*
X1598898Y631237D03*
X1593898D03*
X1596398D03*
X1598868Y650877D03*
X1598838Y648367D03*
X1596368Y650877D03*
X1593868D03*
X1596338Y648367D03*
X1593838D03*
X1598898Y645817D03*
X1596398D03*
X1593898D03*
X1598868Y653377D03*
X1596368D03*
X1593868D03*
X1598948Y657677D03*
X1593948D03*
X1596448D03*
Y660177D03*
X1593948D03*
X1598948D03*
X1596468Y665237D03*
X1593968D03*
X1598968D03*
X1596438Y662727D03*
X1593938D03*
X1598938D03*
X1593938Y679807D03*
X1596438D03*
X1593878Y682357D03*
X1596378D03*
X1593908Y684867D03*
X1596408D03*
X1598878Y682357D03*
X1598908Y684867D03*
X1598938Y679807D03*
X1596288Y688902D03*
X1598888D03*
X1598828Y696727D03*
X1593828D03*
X1593888Y694177D03*
X1596388D03*
X1596328Y696727D03*
X1593858Y699277D03*
X1596358D03*
X1598888Y694177D03*
X1596288Y691502D03*
X1598858Y699277D03*
X1598888Y691502D03*
X1598858Y718837D03*
X1598828Y716327D03*
X1596358Y718837D03*
X1593858D03*
X1596328Y716327D03*
X1593828D03*
X1596388Y713777D03*
X1593888D03*
X1598888D03*
X1596250Y721452D03*
X1598850D03*
X1599010Y724002D03*
X1598440Y736692D03*
X1592760Y736652D03*
X1595600D03*
X1606788Y756199D03*
X1602788D03*
X1621920Y25962D03*
X1622220Y49862D03*
X1623881Y129627D03*
X1610788Y756199D03*
X1614788D03*
X1618788D03*
X1615062Y1421241D03*
X1613047Y1415669D03*
X1614927Y1426076D03*
Y1429896D03*
X1624353Y1428766D03*
Y1431316D03*
X1617215Y1440822D03*
X1634799Y19495D03*
X1638199D03*
X1627694Y26431D03*
X1631094D03*
X1633111Y206693D03*
X1632342Y216015D03*
X1635835Y343002D03*
X1636800Y429982D03*
X1639800D03*
X1636800Y426982D03*
X1639800D03*
X1636800Y438982D03*
X1639800D03*
X1636800Y435982D03*
X1639800D03*
X1636800Y432982D03*
X1639800D03*
X1638928Y756199D03*
X1630928D03*
X1634928D03*
X1638277Y1269065D03*
X1640812Y1270020D03*
X1631203Y1367492D03*
X1628653D03*
X1626153D03*
X1628653Y1372492D03*
X1631203D03*
X1626153D03*
X1631203Y1369992D03*
X1628653D03*
X1626153D03*
X1628653Y1379992D03*
Y1382492D03*
Y1377492D03*
Y1374992D03*
X1631203Y1377492D03*
Y1374992D03*
Y1379992D03*
Y1382492D03*
X1626153Y1379992D03*
Y1382492D03*
Y1374992D03*
Y1377492D03*
X1630643Y1440290D03*
X1627469Y1437072D03*
X1624853Y1440875D03*
X1634643Y1442982D03*
X1638785Y1442483D03*
X1637042Y1440215D03*
X1630643Y1443090D03*
X1635315Y1465745D03*
Y1462745D03*
X1632315Y1468745D03*
X1629815D03*
X1632315Y1465745D03*
X1629815D03*
X1632315Y1462745D03*
X1629815D03*
X1635315Y1468745D03*
Y1460245D03*
X1629815D03*
X1632315D03*
X1629815Y1457745D03*
X1632315D03*
X1635315D03*
X1639645Y1473645D03*
X1648972Y19495D03*
X1652372D03*
X1641867Y26431D03*
X1645267D03*
X1650020Y408952D03*
X1647310Y408922D03*
X1650020Y411452D03*
X1647310Y411422D03*
X1654110Y434177D03*
X1657755Y517910D03*
X1651851Y532057D03*
X1651112Y545572D03*
X1645530Y549160D03*
X1653230Y549322D03*
X1642720Y560862D03*
X1656238Y592113D03*
X1649833Y594946D03*
X1653794Y594956D03*
X1653774Y598576D03*
X1649844Y598555D03*
X1656955Y611090D03*
X1645300Y612202D03*
X1653220Y620662D03*
X1645681Y624011D03*
X1648581D03*
X1651481D03*
X1654809Y638101D03*
X1653319Y642311D03*
X1652351Y639573D03*
X1648811Y628277D03*
X1647081Y626211D03*
X1645917Y628917D03*
Y633577D03*
X1645167Y631247D03*
Y635907D03*
X1650081Y626111D03*
X1651711Y628277D03*
X1651635Y651836D03*
X1652581Y646311D03*
X1643582Y652601D03*
X1655637Y646311D03*
X1641082Y652601D03*
X1649363Y649485D03*
X1654809Y672101D03*
X1652351Y673573D03*
X1645681Y658011D03*
X1648581D03*
X1648811Y662277D03*
X1647081Y660211D03*
X1645917Y662917D03*
Y667577D03*
X1645167Y665247D03*
Y669907D03*
X1650081Y660111D03*
X1651481Y658011D03*
X1651711Y662277D03*
X1641082Y686601D03*
X1651635Y685836D03*
X1652581Y680311D03*
X1653319Y676311D03*
X1643582Y686601D03*
X1655113Y680835D03*
X1649363Y683485D03*
X1654809Y706101D03*
X1648811Y696277D03*
X1645167Y703907D03*
X1645917Y701577D03*
X1645167Y699247D03*
X1645917Y696917D03*
X1650081Y694111D03*
X1645681Y692011D03*
X1647081Y694211D03*
X1648581Y692011D03*
X1651711Y696277D03*
X1651481Y692011D03*
X1641082Y720601D03*
X1651635Y719836D03*
X1652581Y714311D03*
X1653319Y710311D03*
X1652351Y707573D03*
X1643582Y720601D03*
X1655637Y714311D03*
X1649363Y717485D03*
X1651509Y756492D03*
X1650771Y1367492D03*
X1648271D03*
X1645721D03*
X1648271Y1372492D03*
X1650771D03*
X1645721D03*
X1650771Y1369992D03*
X1648271D03*
X1645721D03*
X1648271Y1379992D03*
Y1382492D03*
X1650771Y1379992D03*
Y1382492D03*
X1648271Y1377492D03*
Y1374992D03*
X1650771Y1377492D03*
Y1374992D03*
X1645721Y1377492D03*
Y1374992D03*
Y1379992D03*
Y1382492D03*
X1641047Y1432876D03*
X1645707D03*
X1643377Y1433626D03*
X1648037D03*
X1655762Y1429794D03*
X1648677Y1436220D03*
X1653243Y1435690D03*
X1651043Y1434190D03*
X1653243Y1432790D03*
X1651143Y1437190D03*
X1653243Y1438590D03*
X1648677Y1439120D03*
X1655295Y1453879D03*
X1652295D03*
X1643065Y1462645D03*
Y1465645D03*
Y1468645D03*
Y1460145D03*
Y1457645D03*
X1655295Y1456899D03*
X1652295D03*
X1642645Y1473645D03*
X1646958Y1501553D03*
X1671828Y26431D03*
X1668100Y180852D03*
X1667739Y187187D03*
X1666690Y193290D03*
X1674432Y216981D03*
X1672596Y220541D03*
X1668426Y222432D03*
X1664866Y225162D03*
X1660861Y227548D03*
X1664970Y472112D03*
X1662447Y480619D03*
X1665790Y523417D03*
X1662262Y537334D03*
X1659740Y542222D03*
X1661872Y534703D03*
X1660243Y532071D03*
X1668917Y549992D03*
X1666902Y555115D03*
X1663502D03*
X1658738Y592113D03*
X1661238D03*
X1664197Y602191D03*
X1669222Y604490D03*
X1670700Y594562D03*
X1672500Y596462D03*
X1660660Y602273D03*
X1664410Y617953D03*
X1668920Y617637D03*
X1660754Y609837D03*
X1669397Y614064D03*
X1663471Y609837D03*
X1666686Y757162D03*
X1669303Y1372492D03*
X1664253D03*
X1666753D03*
X1669303Y1367492D03*
Y1369992D03*
X1666753Y1367492D03*
X1664253D03*
Y1369992D03*
X1666753D03*
X1669303Y1379992D03*
Y1382492D03*
Y1377492D03*
Y1374992D03*
X1666753Y1379992D03*
X1664253D03*
X1666753Y1382492D03*
X1664253D03*
X1666753Y1377492D03*
X1664253D03*
Y1374992D03*
X1666753D03*
X1662496Y1428791D03*
Y1431291D03*
X1665612Y1437072D03*
X1662996Y1440922D03*
X1672786Y1442982D03*
X1668786Y1440290D03*
Y1443256D03*
X1657920Y1453405D03*
X1660920D03*
X1657860Y1466545D03*
Y1464045D03*
X1657950Y1456210D03*
X1657860Y1459045D03*
Y1461545D03*
X1660950Y1456210D03*
X1660860Y1466545D03*
Y1464045D03*
Y1459045D03*
Y1461545D03*
X1666123Y1493362D03*
Y1501362D03*
Y1533862D03*
Y1520862D03*
Y1545862D03*
X1671673Y1550815D03*
X1666123Y1557557D03*
X1666198Y1561557D03*
X1671660Y1569412D03*
X1666198Y1581321D03*
X1678933Y19495D03*
X1682333D03*
X1686001Y26431D03*
X1689401D03*
X1675228D03*
X1678994Y217231D03*
X1690208Y421855D03*
X1689095Y462640D03*
X1684940Y463030D03*
X1685779Y491230D03*
X1690229Y481845D03*
X1687238Y485496D03*
X1681817Y495290D03*
X1675664Y513802D03*
X1690999Y513107D03*
X1683702Y514687D03*
X1676600Y523902D03*
X1688768Y518107D03*
X1689544Y543874D03*
X1689506Y539882D03*
X1679941Y552222D03*
X1678860Y556752D03*
X1683369Y562698D03*
Y566098D03*
X1676644Y655345D03*
Y652745D03*
X1679244Y655345D03*
X1681864Y655286D03*
X1679244Y652745D03*
X1676624Y642404D03*
X1676644Y644945D03*
Y647545D03*
Y650145D03*
X1679244Y642345D03*
X1681864Y642286D03*
X1679244Y644945D03*
Y647545D03*
X1681864Y644886D03*
Y647486D03*
Y650086D03*
Y652686D03*
X1679244Y650145D03*
X1673860Y726522D03*
X1681810Y752955D03*
X1688912Y1372492D03*
X1686362D03*
Y1367492D03*
Y1369992D03*
X1688912Y1367492D03*
Y1369992D03*
Y1377492D03*
Y1374992D03*
Y1382492D03*
Y1379992D03*
X1686362D03*
Y1382492D03*
Y1374992D03*
Y1377492D03*
X1679190Y1432876D03*
X1683850D03*
X1681520Y1433626D03*
X1686180D03*
X1686820Y1436520D03*
X1688886Y1434790D03*
X1688986Y1437790D03*
X1676928Y1442483D03*
X1675185Y1440215D03*
X1686820Y1439420D03*
X1680720Y1487062D03*
X1679508Y1498303D03*
X1678340Y1500862D03*
X1679508Y1517803D03*
X1677930Y1520362D03*
X1679508Y1538803D03*
X1678340Y1541362D03*
X1678230Y1590542D03*
X1674220Y1585321D03*
X1696506Y19495D03*
X1693106D03*
X1703617Y26459D03*
X1700217D03*
X1703570Y50649D03*
X1700170D03*
X1702490Y204780D03*
X1704223Y209707D03*
Y212207D03*
X1701164Y209758D03*
X1698566Y214904D03*
X1696066D03*
X1693725Y217409D03*
X1698566Y212404D03*
X1696066D03*
X1698725Y217409D03*
X1696225D03*
X1701164Y212258D03*
X1704264Y217458D03*
X1701264D03*
X1704264Y214958D03*
X1701264D03*
X1698566Y209704D03*
X1696066D03*
X1693466Y209504D03*
Y214704D03*
Y212204D03*
X1693725Y219909D03*
X1698725D03*
X1696225D03*
X1704264Y219958D03*
X1701264D03*
X1704185Y222710D03*
X1698220Y369652D03*
X1699809Y403985D03*
X1695579D03*
X1702959Y404243D03*
X1707780Y410738D03*
X1697161Y406602D03*
X1692429Y403985D03*
X1701124Y423802D03*
X1694050Y416643D03*
X1695455Y422287D03*
X1707544Y431745D03*
X1707568Y420370D03*
X1690140Y434160D03*
X1693720Y455862D03*
X1697220D03*
X1702127Y468719D03*
X1693236Y472650D03*
X1691151Y493678D03*
X1689943Y479304D03*
X1701811Y501318D03*
X1701635Y497177D03*
X1699300Y498632D03*
X1697210Y500802D03*
X1694050Y501422D03*
X1693711Y498527D03*
X1691129Y501697D03*
X1707200Y498962D03*
X1699553Y513107D03*
X1707552Y506731D03*
X1707716Y513562D03*
X1702930Y526102D03*
X1699265Y521507D03*
X1690999Y525507D03*
X1701726Y518107D03*
X1699666Y541507D03*
X1699251Y533642D03*
X1691104Y530503D03*
X1691445Y535011D03*
X1704886Y534564D03*
X1689769Y537339D03*
X1699107Y555783D03*
X1703306Y550064D03*
X1703452Y639381D03*
X1700852D03*
X1698232Y639440D03*
X1700852Y655141D03*
X1703452Y647341D03*
Y649941D03*
Y652541D03*
Y644741D03*
X1700852Y647341D03*
Y649941D03*
Y652541D03*
Y644741D03*
X1698232Y655200D03*
Y644800D03*
Y647400D03*
Y650000D03*
Y652600D03*
X1703452Y641981D03*
X1700852D03*
X1698232Y642040D03*
X1700922Y657781D03*
X1698302Y657840D03*
X1698048Y705662D03*
X1701320Y705678D03*
X1698020Y702962D03*
X1696402Y709533D03*
X1699110Y727452D03*
X1705035Y729210D03*
X1704973Y753019D03*
X1703310Y749455D03*
X1690620Y760702D03*
X1691412Y1372492D03*
Y1367492D03*
Y1369992D03*
Y1377492D03*
Y1374992D03*
Y1382492D03*
Y1379992D03*
X1691086Y1436290D03*
Y1433390D03*
X1693392Y1429808D03*
X1691086Y1439190D03*
X1704723Y1500862D03*
Y1520362D03*
Y1541362D03*
X1705003Y1564057D03*
X1707220Y15662D03*
X1715210Y18282D03*
X1714589Y21562D03*
X1709589Y26062D03*
X1719589Y25862D03*
X1717089D03*
X1710106Y48720D03*
Y40020D03*
X1720895Y68062D03*
X1716875D03*
X1712520Y117862D03*
X1712720Y111862D03*
X1719943Y112667D03*
Y116667D03*
X1713418Y130862D03*
X1721418Y135327D03*
X1717418D03*
X1714490Y142920D03*
X1717140Y148910D03*
X1711700Y140200D03*
X1717619Y165909D03*
X1718110Y159040D03*
X1719530Y162950D03*
X1722078Y189483D03*
X1720310Y191252D03*
X1707159Y217580D03*
Y215080D03*
Y210080D03*
Y222580D03*
Y225080D03*
Y220080D03*
X1713720Y381152D03*
X1717220D03*
X1719200Y371162D03*
X1713720Y391652D03*
Y384652D03*
Y388152D03*
X1717220Y391652D03*
Y388152D03*
Y384652D03*
X1709000Y413362D03*
X1706500D03*
X1709000Y415862D03*
X1706500D03*
X1721220Y458362D03*
X1713977Y457137D03*
X1708977Y458542D03*
X1721936Y469263D03*
X1716134Y478443D03*
X1715711Y474399D03*
X1713977Y470804D03*
X1708977D03*
X1716148Y483720D03*
X1716087Y495665D03*
X1716156Y487685D03*
X1716278Y491676D03*
X1707552Y503331D03*
X1709844Y516106D03*
X1707610Y534113D03*
X1709356Y541144D03*
X1709680Y545432D03*
X1716110Y532632D03*
X1707346Y547504D03*
X1717987Y569705D03*
X1716480Y691410D03*
X1710550Y691327D03*
X1712824Y696476D03*
X1710122Y703509D03*
X1713920Y700962D03*
X1709828Y719283D03*
X1713450Y728222D03*
X1719727Y1472088D03*
X1726720Y49862D03*
X1733720D03*
X1730220D03*
X1736040Y41792D03*
X1732810Y52482D03*
X1736040Y44292D03*
X1730140Y52552D03*
X1727600Y52582D03*
X1725320Y67962D03*
X1723018Y101667D03*
X1723218Y93267D03*
X1738220Y98862D03*
X1736720Y101862D03*
X1729080Y118132D03*
X1739720Y120892D03*
X1728999Y112895D03*
X1730765Y151362D03*
X1733920D03*
X1723670Y149102D03*
X1728320Y169862D03*
X1723090Y173072D03*
Y177072D03*
X1734857Y184865D03*
X1737470Y177147D03*
X1737500Y217962D03*
Y214962D03*
Y211962D03*
Y208962D03*
Y226962D03*
Y223962D03*
Y220962D03*
X1725344Y359334D03*
X1728300Y377787D03*
X1733780Y390620D03*
X1729810D03*
X1737660D03*
X1734290Y423820D03*
X1727700Y417265D03*
X1739316Y480939D03*
X1730954Y478062D03*
X1725522Y482869D03*
X1733354Y490869D03*
Y486869D03*
X1738014Y1287344D03*
X1724431Y1336311D03*
X1734717Y1404340D03*
X1729700Y1462932D03*
X1733200D03*
X1736700D03*
X1736400Y1458942D03*
Y1455442D03*
X1731600Y1457230D03*
X1726120Y1490262D03*
X1726149Y1496270D03*
X1724649Y1513945D03*
X1727674D03*
X1729310Y1520951D03*
X1735310D03*
X1724649Y1505895D03*
X1727674D03*
X1726310Y1530445D03*
X1732310D03*
X1729310D03*
X1735310D03*
X1726310Y1520951D03*
X1732310D03*
X1751065Y39017D03*
X1754620Y39062D03*
X1747720Y31862D03*
Y34362D03*
X1740858Y72330D03*
Y79830D03*
Y74830D03*
Y82330D03*
X1745220Y98862D03*
X1741720D03*
X1743720Y101862D03*
X1740220D03*
X1748720Y97362D03*
X1745010Y122952D03*
X1750820Y119972D03*
X1738520Y151362D03*
X1751220Y147562D03*
X1748465D03*
X1754120Y171562D03*
X1750920Y171662D03*
X1754234Y190836D03*
X1752078Y216728D03*
X1740500Y217962D03*
Y214962D03*
Y211962D03*
Y208962D03*
X1747600Y209062D03*
X1744600D03*
X1751800Y206762D03*
X1752078Y226728D03*
Y224228D03*
Y221728D03*
Y219228D03*
X1740500Y226962D03*
Y223962D03*
Y220962D03*
X1746484Y279682D03*
X1749450Y293862D03*
X1756204Y301695D03*
X1752000Y306562D03*
X1756933Y372452D03*
X1744380Y382892D03*
X1744510Y377452D03*
X1747080Y435870D03*
X1746720Y464862D03*
X1752316Y703969D03*
Y695669D03*
X1752217Y692988D03*
X1752276Y720529D03*
X1752316Y712269D03*
X1747814Y1287344D03*
X1742714Y1287244D03*
X1754165Y1304422D03*
Y1307422D03*
Y1301422D03*
Y1295422D03*
Y1298422D03*
Y1310422D03*
X1738740Y1451742D03*
X1740200Y1462932D03*
X1745111Y1463262D03*
X1747677Y1507388D03*
X1744677D03*
X1747304Y1524976D03*
X1744304D03*
X1762420Y21562D03*
X1765238Y22062D03*
X1768026Y24165D03*
X1769669Y15244D03*
X1761998Y15187D03*
X1765260Y18262D03*
X1757320Y15872D03*
X1758672Y26431D03*
X1755272D03*
X1767220Y26962D03*
X1758669Y50649D03*
X1755269D03*
X1762738Y53262D03*
X1767220Y53342D03*
X1767185Y48817D03*
X1767400Y39915D03*
X1769274Y50742D03*
X1771774Y53682D03*
X1758063Y72623D03*
X1767170Y83607D03*
X1767990Y76797D03*
X1760478Y90027D03*
X1770368Y72691D03*
X1757978Y116727D03*
X1760978D03*
X1763678Y106127D03*
X1769278Y108027D03*
Y110927D03*
Y113727D03*
X1755978Y108427D03*
Y111027D03*
X1760478Y106127D03*
X1758300Y128242D03*
X1763435Y166862D03*
X1765820Y182282D03*
X1767300Y174587D03*
X1755078Y216928D03*
X1761500Y214062D03*
X1765000D03*
X1768500D03*
X1755078Y219428D03*
Y221928D03*
Y224428D03*
X1760104Y301648D03*
X1761936Y310709D03*
X1769230Y310478D03*
X1756800Y364048D03*
Y368048D03*
X1770280Y372452D03*
X1770220Y377452D03*
Y382952D03*
X1757066Y435721D03*
X1757650Y461393D03*
X1768560Y539042D03*
X1766060D03*
X1768317Y686375D03*
X1755112Y703948D03*
Y695648D03*
X1755013Y692967D03*
X1757612Y703948D03*
Y695648D03*
X1755072Y720508D03*
X1755112Y712248D03*
X1757572Y720508D03*
X1757612Y712248D03*
X1757165Y1304422D03*
X1760165D03*
Y1307422D03*
X1757165D03*
X1769165Y1301422D03*
X1766165D03*
X1763165D03*
X1757165D03*
X1760165D03*
X1769165Y1295422D03*
X1766165D03*
X1763165D03*
X1760165D03*
X1757165D03*
X1760165Y1298422D03*
X1757165D03*
X1763165D03*
X1766165D03*
X1769165D03*
X1758352Y1317368D03*
Y1322168D03*
X1757165Y1310422D03*
X1760165D03*
X1759987Y1325375D03*
Y1328275D03*
X1763829Y1337548D03*
X1766829D03*
Y1340448D03*
X1769829Y1337548D03*
Y1340448D03*
X1766829Y1343348D03*
X1769829Y1346248D03*
Y1343348D03*
Y1349148D03*
Y1351858D03*
X1782305Y13647D03*
X1775556Y21471D03*
X1775830Y26522D03*
X1777754Y37746D03*
X1781774Y54462D03*
X1774274Y50742D03*
X1776710Y53562D03*
X1779411Y50692D03*
X1774328Y60087D03*
X1779778Y70027D03*
X1774328Y62987D03*
X1775580Y73330D03*
X1779778Y72927D03*
X1787790Y85132D03*
X1781485Y88192D03*
X1785142Y76032D03*
X1773611Y88293D03*
X1778578Y97927D03*
X1778478Y90627D03*
X1784178Y108227D03*
Y111127D03*
Y113927D03*
X1780320Y153162D03*
X1774950Y167392D03*
X1779500Y171692D03*
X1777520Y178403D03*
Y173903D03*
X1782600Y175932D03*
X1778778Y216928D03*
X1783878D03*
X1772000Y214062D03*
X1778778Y219428D03*
Y221928D03*
X1783878Y224428D03*
Y226928D03*
Y219428D03*
Y221928D03*
X1786089Y287641D03*
X1783563D03*
X1777354Y295489D03*
X1783018Y301729D03*
X1782324Y410432D03*
Y403932D03*
Y425432D03*
Y418932D03*
X1782420Y447137D03*
X1781470Y452065D03*
X1778310Y591152D03*
X1781720Y592742D03*
X1778165Y1307422D03*
Y1304422D03*
Y1301422D03*
X1775165D03*
X1772165D03*
X1778165Y1295422D03*
X1775165D03*
X1772165D03*
Y1298422D03*
X1775165D03*
X1778165D03*
X1784165Y1307422D03*
Y1304422D03*
X1781165Y1307422D03*
Y1304422D03*
X1784165Y1301422D03*
Y1295422D03*
Y1298422D03*
X1781165Y1301422D03*
Y1295422D03*
Y1298422D03*
X1781829Y1324448D03*
X1784829D03*
X1778829D03*
X1778165Y1310422D03*
Y1312922D03*
X1784165Y1310422D03*
Y1312922D03*
X1781165Y1310422D03*
Y1312922D03*
X1781829Y1333148D03*
Y1330248D03*
Y1327348D03*
X1784829Y1333148D03*
Y1330248D03*
Y1327348D03*
X1781829Y1337548D03*
Y1340448D03*
X1784829Y1337548D03*
Y1340448D03*
X1778829Y1333148D03*
Y1330248D03*
Y1327348D03*
Y1337548D03*
X1772829D03*
X1775829D03*
X1778829Y1340448D03*
X1775829D03*
X1772829D03*
X1781829Y1346248D03*
Y1343348D03*
Y1349148D03*
Y1351858D03*
Y1354758D03*
X1772829Y1346248D03*
X1775829D03*
X1778829D03*
X1772829Y1343348D03*
X1775829D03*
X1778829D03*
X1772829Y1349148D03*
X1775829D03*
X1778829D03*
X1772829Y1351858D03*
X1775829D03*
X1778829D03*
X1772829Y1354758D03*
X1775829D03*
X1778829D03*
X1799920Y52594D03*
X1788238Y82292D03*
Y78062D03*
Y74912D03*
X1803215Y154032D03*
X1793269Y287641D03*
X1790743D03*
X1791619Y294441D03*
X1789093D03*
X1800160Y362542D03*
X1800340Y387062D03*
X1791494Y386536D03*
X1792450Y410615D03*
X1792507Y403932D03*
X1792220Y425432D03*
X1792335Y418775D03*
X1796020Y451162D03*
X1791888Y683805D03*
X1800450Y1505230D03*
X1795561Y1524729D03*
X1806920Y150862D03*
X1808910Y143902D03*
X1813335Y155435D03*
X1813325Y177257D03*
X1807220Y179897D03*
X1817157Y373829D03*
X1816224Y410432D03*
X1816994Y398052D03*
X1815724Y423932D03*
X1810792Y417432D03*
X1812161Y472521D03*
X1814537Y1322105D03*
X1813700Y1494762D03*
X1807150Y1505675D03*
X1818289Y1501591D03*
X1811494Y1505349D03*
X1813994Y1507891D03*
X1825762Y167662D03*
X1835760Y185772D03*
X1829695Y226333D03*
X1832295D03*
X1827095D03*
X1824095D03*
X1834895D03*
Y223733D03*
X1824095D03*
X1827095D03*
X1832295D03*
X1829695D03*
X1832295Y233933D03*
X1829695D03*
X1827095D03*
X1824095D03*
X1829695Y231433D03*
X1832295D03*
X1829695Y228933D03*
X1832295D03*
X1827095Y231433D03*
X1824095D03*
X1827095Y228933D03*
X1824095D03*
X1834895Y233933D03*
Y231433D03*
Y228933D03*
X1828204Y328654D03*
X1829189Y363731D03*
X1829434Y406348D03*
X1834005Y401421D03*
X1821280Y413432D03*
X1834600Y406442D03*
X1826914Y431718D03*
X1829514Y1498198D03*
Y1500807D03*
X1832114Y1498198D03*
Y1500807D03*
X1824995Y1502201D03*
X1846691Y166450D03*
X1844157Y182210D03*
X1848435Y172187D03*
X1838880Y195162D03*
X1837895Y226333D03*
Y223733D03*
Y233933D03*
Y231433D03*
Y228933D03*
X1836294Y383592D03*
X1838379Y453921D03*
G54D31*
X174685Y647210D03*
X174393Y678354D03*
X195316Y1430034D03*
X383224Y1354446D03*
X412990D03*
X443326D03*
X458600Y1379662D03*
X472700Y1353962D03*
X526478Y1449795D03*
X708795Y1429579D03*
X1131715Y1532913D03*
X1168627Y1466363D03*
X1175215Y1532913D03*
X1359365Y1353946D03*
X1389131D03*
X1419467D03*
X1434200Y1379362D03*
X1449233Y1353946D03*
X1502956Y1449373D03*
X1670101Y1463655D03*
X1682882Y628017D03*
Y678952D03*
X1769790Y204632D03*
X1799350D03*
X1826405Y269763D03*
Y299056D03*
G54D27*
X70472Y173228D03*
Y236220D03*
G54D45*
X450000Y278543D03*
X470000D03*
X483500Y246362D03*
X473500D03*
X480000Y278543D03*
X490000D03*
X500000D03*
X498563Y607067D03*
X510000Y278543D03*
X520000D03*
X518563Y607067D03*
X508563D03*
X549236Y1441207D03*
X569236D03*
X688500Y1611900D03*
Y1621900D03*
X1041435Y143357D03*
X1056225Y143131D03*
X1041435Y163357D03*
X1056225Y163131D03*
X1099970Y1712570D03*
Y1722570D03*
X1689646Y115669D03*
X1679646D03*
X1689646Y125669D03*
Y135669D03*
X1679646Y125669D03*
Y135669D03*
X1689646Y145669D03*
Y155669D03*
X1679646Y145669D03*
Y155669D03*
X1689646Y165669D03*
X1679646D03*
X1689646Y175669D03*
X1679646D03*
X1771457Y1624646D03*
Y1644646D03*
G54D17*
X27699Y1258727D03*
Y1255381D03*
Y1265420D03*
Y1262074D03*
X43841Y994357D03*
X36399Y1054593D03*
X43841Y1255381D03*
Y1258727D03*
Y1252034D03*
Y1262074D03*
Y1265420D03*
X57299Y766798D03*
X52541Y957546D03*
Y954200D03*
Y1021129D03*
Y1024475D03*
Y1051247D03*
X57399Y1258727D03*
X52820Y1253862D03*
X57399Y1265420D03*
Y1262074D03*
X66099Y780184D03*
Y773491D03*
Y786877D03*
Y803609D03*
Y796916D03*
Y790223D03*
Y847113D03*
Y853806D03*
Y860499D03*
Y863845D03*
Y883924D03*
Y877231D03*
Y870538D03*
Y890617D03*
Y897310D03*
Y900656D03*
Y914042D03*
Y907349D03*
Y927428D03*
Y920735D03*
Y934121D03*
Y944160D03*
Y937467D03*
Y950853D03*
Y980971D03*
Y974278D03*
Y994357D03*
Y987664D03*
Y1027822D03*
Y1021129D03*
Y1047900D03*
Y1041207D03*
Y1034515D03*
Y1061286D03*
Y1054593D03*
Y1074672D03*
Y1067979D03*
Y1091404D03*
Y1081365D03*
Y1084711D03*
Y1098097D03*
Y1111483D03*
Y1104790D03*
Y1128215D03*
Y1118176D03*
Y1121522D03*
Y1141601D03*
Y1134908D03*
Y1148294D03*
Y1154987D03*
Y1158333D03*
Y1171719D03*
Y1165026D03*
Y1185105D03*
Y1178412D03*
Y1191798D03*
Y1208530D03*
Y1201837D03*
Y1195144D03*
X73541Y1255381D03*
Y1258727D03*
Y1252034D03*
Y1265420D03*
Y1262074D03*
X82241Y770144D03*
X86999Y766798D03*
X82241Y776837D03*
Y786877D03*
Y783530D03*
Y800263D03*
Y793570D03*
Y850459D03*
Y843766D03*
Y867192D03*
Y860499D03*
Y857152D03*
Y873885D03*
Y880577D03*
Y887270D03*
Y897310D03*
Y893963D03*
Y917389D03*
Y910696D03*
Y904003D03*
Y924081D03*
Y934121D03*
Y930774D03*
Y947507D03*
Y940814D03*
Y957546D03*
Y954200D03*
Y977625D03*
Y970932D03*
Y991011D03*
Y984318D03*
Y994357D03*
Y1021129D03*
Y1024475D03*
Y1031168D03*
Y1044554D03*
Y1037861D03*
Y1051247D03*
Y1071326D03*
Y1064633D03*
Y1078018D03*
Y1094751D03*
Y1088058D03*
Y1081365D03*
Y1108137D03*
Y1101444D03*
Y1124869D03*
Y1118176D03*
Y1114829D03*
Y1144948D03*
Y1138255D03*
Y1131562D03*
Y1161680D03*
Y1154987D03*
Y1151641D03*
Y1175066D03*
Y1168373D03*
Y1181759D03*
Y1191798D03*
Y1188452D03*
Y1205184D03*
Y1198491D03*
X87099Y1258727D03*
X82241Y1248688D03*
X84334Y1254263D03*
X87099Y1265420D03*
Y1262074D03*
X103241Y994357D03*
Y1255381D03*
Y1258727D03*
Y1252034D03*
Y1265420D03*
Y1262074D03*
X116567Y766775D03*
X111941Y957546D03*
Y954200D03*
X125499Y1061286D03*
X116799Y1258727D03*
X111941Y1248688D03*
X114191Y1254604D03*
X116799Y1265420D03*
Y1262074D03*
X141641Y957546D03*
Y954200D03*
Y994357D03*
Y1057940D03*
X129933Y1238461D03*
X132941Y1255381D03*
Y1258727D03*
Y1252034D03*
X141641Y1248688D03*
X143675Y1255567D03*
X132941Y1265420D03*
Y1262074D03*
X146367Y766775D03*
X160130Y1251847D03*
X146499Y1258727D03*
Y1265420D03*
Y1262074D03*
X176099Y766798D03*
X171341Y957546D03*
Y954200D03*
X162641Y994357D03*
X176199Y1258727D03*
X162641Y1255381D03*
Y1258727D03*
Y1252034D03*
X171341Y1248688D03*
X171947Y1255837D03*
X176199Y1265420D03*
X162641D03*
Y1262074D03*
X176199D03*
X184899Y1061286D03*
X192341Y1255381D03*
Y1258727D03*
Y1252034D03*
Y1265420D03*
Y1262074D03*
X188897Y1578182D03*
X192297D03*
X188897Y1590094D03*
X192297D03*
X205799Y766798D03*
X201041Y957546D03*
Y954200D03*
Y994357D03*
X205899Y1258727D03*
X201041Y1248688D03*
X201193Y1257900D03*
X205899Y1265420D03*
Y1262074D03*
X200957Y1578182D03*
X204357D03*
X200957Y1590094D03*
X204357D03*
X222041Y957546D03*
Y954200D03*
Y994357D03*
Y1255381D03*
X219660Y1260492D03*
X222041Y1252034D03*
Y1265420D03*
Y1262074D03*
X225077Y1578182D03*
X213017D03*
X216417D03*
X225077Y1590094D03*
X213017D03*
X216417D03*
X235499Y766798D03*
X236391Y1002557D03*
X240521Y1000395D03*
X237841Y1000437D03*
X233891Y1002557D03*
X231391D03*
X228891D03*
X235599Y1258727D03*
X230741Y1248688D03*
X235480Y1265406D03*
X235599Y1262074D03*
X237137Y1578182D03*
X240537D03*
X228477D03*
X237137Y1590094D03*
X240537D03*
X228477D03*
X251741Y957546D03*
Y954200D03*
Y994357D03*
X254881Y999650D03*
X257561Y999608D03*
X244299Y1061286D03*
X248047Y1259155D03*
X250467Y1259175D03*
X251707Y1252034D03*
X249603Y1266204D03*
X251699Y1265254D03*
X249197Y1578182D03*
X252597D03*
X249197Y1590094D03*
X252597D03*
X272529Y111053D03*
X265442D03*
X261899D03*
Y108553D03*
X265442D03*
X268985Y111053D03*
Y108553D03*
X272529D03*
X260441Y1057940D03*
Y1248688D03*
X273317Y1578182D03*
X261257D03*
X264657D03*
X273317Y1590094D03*
X261257D03*
X264657D03*
X285377Y1578182D03*
X288777D03*
X276717D03*
X285377Y1590094D03*
X288777D03*
X276717D03*
X297437Y1578182D03*
X300837D03*
X297437Y1590094D03*
X300837D03*
X321557Y1578182D03*
X309497D03*
X312897D03*
X321557Y1590094D03*
X309497D03*
X312897D03*
X333617Y1578182D03*
X337017D03*
X324957D03*
X333617Y1590094D03*
X337017D03*
X324957D03*
X345677Y1578182D03*
X349077D03*
X345677Y1590094D03*
X349077D03*
X369797Y1578182D03*
X357737D03*
X361137D03*
X369797Y1590094D03*
X357737D03*
X361137D03*
X373197Y1578182D03*
Y1590094D03*
X476451Y1578182D03*
X485111D03*
X473051D03*
X476451Y1590094D03*
X485111D03*
X473051D03*
X500571Y1578182D03*
X488511D03*
X497171D03*
X500571Y1590094D03*
X488511D03*
X497171D03*
X512631Y1578182D03*
X509231D03*
X512631Y1590094D03*
X509231D03*
X524691Y1578182D03*
X533351D03*
X521291D03*
X524691Y1590094D03*
X533351D03*
X521291D03*
X536751Y1578182D03*
X548811D03*
X545411D03*
X536751Y1590094D03*
X548811D03*
X545411D03*
X560871Y1578182D03*
X557471D03*
X560871Y1590094D03*
X557471D03*
X572931Y1578182D03*
X581591D03*
X569531D03*
X572931Y1590094D03*
X581591D03*
X569531D03*
X597051Y1578182D03*
X584991D03*
X593651D03*
X597051Y1590094D03*
X584991D03*
X593651D03*
X609111Y1578182D03*
X605711D03*
X609111Y1590094D03*
X605711D03*
X629658Y766478D03*
X623347Y999665D03*
X625780Y1000198D03*
X620899Y1061286D03*
X629931Y1258727D03*
X632080Y1262074D03*
X629699Y1255381D03*
X631270Y1264942D03*
X621171Y1578182D03*
X629831D03*
X617771D03*
X621171Y1590094D03*
X629831D03*
X617771D03*
X636941Y957546D03*
Y954200D03*
X644347Y1003135D03*
X640327D03*
X640467Y1000735D03*
X647447Y1002865D03*
X647397Y1000135D03*
X644257Y1000325D03*
X636946Y1258414D03*
X647690Y1260812D03*
X637041Y1252034D03*
X645897Y1248785D03*
X647877Y1254076D03*
X636877Y1261235D03*
X645291Y1578182D03*
X633231D03*
X641891D03*
X645291Y1590094D03*
X633231D03*
X641891D03*
X667677Y441636D03*
X650107Y1002825D03*
X650599Y1258727D03*
X666741Y1255381D03*
X664630Y1259442D03*
X649587Y1266766D03*
X661400Y1263522D03*
X657351Y1578182D03*
X653951D03*
X657351Y1590094D03*
X653951D03*
X674628Y424313D03*
X671479Y421163D03*
X667660Y429037D03*
X674628Y427462D03*
X677778Y414864D03*
Y424313D03*
X671479Y414864D03*
X674628Y421163D03*
Y418013D03*
X677778D03*
Y421163D03*
X668329D03*
X677778Y427462D03*
Y430612D03*
X674628Y436911D03*
X671479D03*
X677778Y433761D03*
X668329Y436911D03*
X677778Y440061D03*
X674628D03*
X677778Y436911D03*
Y443210D03*
X680928Y440061D03*
X674628Y430612D03*
X671479Y443211D03*
X677778Y449510D03*
X668329Y452659D03*
X674628D03*
X671479D03*
X677778D03*
X668329Y455809D03*
X671479Y458959D03*
X674628D03*
X668329D03*
X677778D03*
Y455809D03*
X674628D03*
X668067Y462090D03*
X677778Y462108D03*
X671479Y455809D03*
X680928Y458959D03*
X674628Y449510D03*
Y462108D03*
X677778Y477856D03*
Y471557D03*
Y474707D03*
X671479Y465258D03*
X674628D03*
X668329D03*
X677778D03*
Y468407D03*
X671479Y481006D03*
X667350Y470680D03*
X671479Y474707D03*
X674628Y484006D03*
X680299Y766798D03*
X666641Y957546D03*
Y954200D03*
X672063Y998632D03*
X680299Y1061286D03*
Y1258727D03*
X666741Y1252034D03*
X675537Y1248885D03*
X677980Y1262074D03*
X666741D03*
X666646Y1264464D03*
X680046Y1264964D03*
X695055Y112678D03*
Y115178D03*
X687227Y414864D03*
X690376Y421163D03*
Y418013D03*
Y414864D03*
X693526Y427462D03*
X687227Y424313D03*
X690376Y427462D03*
X680928Y414864D03*
Y418013D03*
X684077Y421163D03*
X680928Y427462D03*
X684077Y418013D03*
Y427462D03*
X680928Y421163D03*
X684077Y424313D03*
X687227Y427462D03*
X696676D03*
X693526Y421163D03*
Y424313D03*
X690376D03*
X696676Y421163D03*
Y424313D03*
Y418013D03*
X680928Y436911D03*
Y433761D03*
X693526Y430612D03*
X696676Y440061D03*
Y443210D03*
X684077Y430612D03*
Y440061D03*
X687227Y436911D03*
Y443210D03*
X684077D03*
Y436911D03*
X680928Y443210D03*
X690376Y436911D03*
Y443210D03*
X687227Y440061D03*
X693526Y433761D03*
X696676D03*
X684077D03*
X687227Y430612D03*
X690376D03*
X696676D03*
X687227Y433761D03*
X680928Y430612D03*
X687227Y462108D03*
X680928Y455809D03*
X693526Y462108D03*
X680928Y449510D03*
X687227D03*
X690376Y462108D03*
X684077Y449510D03*
X680928Y452659D03*
X684077D03*
X687227Y455809D03*
X684077D03*
X680928Y462108D03*
X696676Y449510D03*
Y452659D03*
X690376Y449510D03*
Y455809D03*
X687227Y452659D03*
X693526Y458959D03*
X696676D03*
Y462108D03*
X687227Y458959D03*
X684077D03*
Y468407D03*
X687227Y471557D03*
Y474707D03*
Y477856D03*
X684077Y471557D03*
X690376Y465258D03*
X684077D03*
X680928Y471557D03*
Y474707D03*
Y477856D03*
X693526Y465258D03*
Y471557D03*
X690376Y468407D03*
Y477856D03*
Y471557D03*
X687227Y465258D03*
X690376Y474707D03*
X687227Y468407D03*
X693526D03*
X684077Y474707D03*
X696676Y465258D03*
Y474707D03*
Y468407D03*
X693526Y474707D03*
X696676Y471557D03*
X693526Y477856D03*
X696441Y957546D03*
Y954200D03*
Y994357D03*
Y1255381D03*
X694100Y1261562D03*
X696441Y1248688D03*
X692233Y1252480D03*
X696046Y1263764D03*
X698598Y115178D03*
X705685D03*
X702141D03*
X698598Y112678D03*
X705685D03*
X702141D03*
X706125Y418013D03*
X712424Y424313D03*
X699825Y427462D03*
X699826Y414864D03*
X699825Y424313D03*
X712424Y430612D03*
X709274Y440061D03*
Y443210D03*
X706125D03*
X699825D03*
X709274Y433761D03*
X712424D03*
X699825D03*
X706125D03*
X699825Y430612D03*
X706125Y462108D03*
X709274D03*
X712424D03*
X709274Y449510D03*
X699825D03*
X706125D03*
X709274Y452659D03*
X699825Y458959D03*
X706125D03*
X709274D03*
X712424D03*
X699825Y462108D03*
X709274Y474707D03*
Y471557D03*
Y465258D03*
Y468407D03*
X712424Y474707D03*
Y468407D03*
Y465258D03*
X706125Y471557D03*
Y468407D03*
X699825Y471557D03*
Y474707D03*
X706125Y477856D03*
X699825Y465258D03*
X712424Y471557D03*
X706125Y481006D03*
X709899Y766798D03*
X709999Y1258727D03*
X708090Y1262074D03*
X705037Y1252034D03*
X706493Y1256563D03*
X705167Y1262074D03*
X709977Y1264985D03*
X721873Y427462D03*
X725022D03*
X728172Y418013D03*
X718723D03*
X715574Y427462D03*
X728172Y421163D03*
X718723Y414864D03*
X725022Y424313D03*
X721873D03*
X725022Y421163D03*
X728172Y427462D03*
X731322Y421163D03*
X725022Y418013D03*
X718723Y427462D03*
Y424313D03*
Y421163D03*
X715574Y424313D03*
Y421163D03*
Y418013D03*
X728172Y424313D03*
X718723Y436911D03*
X721873Y433761D03*
Y436911D03*
Y440061D03*
Y430612D03*
X718723Y433761D03*
Y440061D03*
X725022Y436911D03*
Y433761D03*
X728172D03*
X718723Y430612D03*
X715574D03*
X725022D03*
X728172Y436911D03*
X715574D03*
Y440061D03*
Y443210D03*
X728172D03*
Y430612D03*
X725022Y440061D03*
X718723Y443210D03*
X721873D03*
X725022D03*
X728172Y440061D03*
X731322D03*
X728172Y455809D03*
Y458959D03*
X718723Y455809D03*
X721873Y458959D03*
Y452659D03*
X725022D03*
X728172D03*
X715574Y462108D03*
X725022Y458959D03*
X721873Y455809D03*
X725022Y462108D03*
X718723Y452659D03*
X715574Y449510D03*
Y452659D03*
Y455809D03*
X728172Y462108D03*
X718723Y449510D03*
X721873D03*
X725022D03*
X718723Y458959D03*
X721873Y462108D03*
X718723D03*
X725022Y468407D03*
X721873Y465258D03*
Y477856D03*
X718723Y468407D03*
X715574Y474707D03*
Y471557D03*
Y468407D03*
Y465258D03*
X718723Y474707D03*
Y471557D03*
X728172Y477856D03*
X721873Y471557D03*
X725022D03*
X718723Y465258D03*
X728172D03*
X725022Y474707D03*
X728172Y468407D03*
X721873Y474707D03*
Y468407D03*
X728172Y474707D03*
Y471557D03*
X725022Y465258D03*
X718723Y477856D03*
X725132Y481116D03*
X728272Y481006D03*
X726041Y957546D03*
Y954200D03*
Y994357D03*
X726141Y1057940D03*
Y1255381D03*
X723700Y1258727D03*
X726141Y1248688D03*
Y1262074D03*
X726107Y1265420D03*
X734471Y418013D03*
X731322Y427462D03*
Y418013D03*
X734471Y421163D03*
X731322Y424313D03*
X734471D03*
X737621D03*
X731322Y414864D03*
Y433761D03*
X734471Y436911D03*
X731322D03*
X734471Y443210D03*
X737621D03*
X731322D03*
Y455809D03*
X737621Y458959D03*
X731322D03*
X734471Y452659D03*
X731322D03*
Y449510D03*
X734471Y458959D03*
X731322Y465258D03*
Y477856D03*
X737621Y471557D03*
X734471Y468407D03*
X731322D03*
X731321Y474707D03*
X731322Y471557D03*
X734471Y481006D03*
X739699Y766798D03*
Y1061286D03*
Y1258727D03*
X734967Y1252034D03*
X737580Y1262074D03*
X739697Y1265420D03*
X755841Y957546D03*
Y954200D03*
Y994357D03*
X755541Y1057940D03*
X750890Y1248500D03*
X755890Y1255381D03*
X753000Y1261352D03*
X755841Y1252034D03*
Y1248688D03*
X750040Y1254179D03*
X755841Y1262074D03*
X755797Y1265420D03*
X769399Y766798D03*
Y1258727D03*
X767080Y1262074D03*
X766148Y1255882D03*
X769399Y1265420D03*
X785541Y957546D03*
Y954200D03*
Y994357D03*
Y1255381D03*
X783130Y1259372D03*
X794157Y1252034D03*
X785541Y1248688D03*
X796880Y1262074D03*
X796280Y1254402D03*
X785541Y1265420D03*
Y1262074D03*
X797417Y767345D03*
X799099Y780184D03*
Y773491D03*
Y786877D03*
Y803609D03*
Y796916D03*
Y790223D03*
Y847113D03*
Y853806D03*
Y860499D03*
Y863845D03*
Y883924D03*
Y877231D03*
Y870538D03*
Y890617D03*
Y897310D03*
Y900656D03*
Y914042D03*
Y907349D03*
Y927428D03*
Y920735D03*
Y934121D03*
Y944160D03*
Y937467D03*
Y950853D03*
Y980971D03*
Y974278D03*
Y994357D03*
Y987664D03*
Y1027822D03*
Y1021129D03*
Y1047900D03*
Y1041207D03*
Y1034515D03*
Y1061286D03*
Y1054593D03*
Y1074672D03*
Y1067979D03*
Y1091404D03*
Y1081365D03*
Y1084711D03*
Y1098097D03*
Y1111483D03*
Y1104790D03*
Y1128215D03*
Y1118176D03*
Y1121522D03*
Y1141601D03*
Y1134908D03*
Y1148294D03*
Y1154987D03*
Y1158333D03*
Y1171719D03*
Y1165026D03*
Y1185105D03*
Y1178412D03*
Y1191798D03*
Y1208530D03*
Y1201837D03*
Y1195144D03*
Y1258727D03*
X812440D03*
X799099Y1265420D03*
X815241Y770144D03*
Y776837D03*
Y786877D03*
Y783530D03*
Y800263D03*
Y793570D03*
Y850459D03*
Y843766D03*
Y867192D03*
Y860499D03*
Y857152D03*
Y873885D03*
Y880577D03*
Y887270D03*
Y897310D03*
Y893963D03*
Y917389D03*
Y910696D03*
Y904003D03*
Y924081D03*
Y934121D03*
Y930774D03*
Y947507D03*
Y940814D03*
Y957546D03*
Y954200D03*
Y977625D03*
Y970932D03*
Y991011D03*
Y984318D03*
Y994357D03*
Y1021129D03*
Y1024475D03*
Y1031168D03*
Y1044554D03*
Y1037861D03*
X814941Y1051247D03*
X815241Y1071325D03*
Y1064633D03*
Y1078018D03*
Y1094751D03*
Y1088058D03*
Y1081365D03*
Y1108136D03*
Y1101444D03*
Y1124869D03*
Y1118176D03*
Y1114829D03*
Y1144947D03*
Y1138255D03*
Y1131562D03*
Y1161680D03*
Y1154987D03*
Y1151640D03*
Y1175066D03*
Y1168373D03*
Y1181758D03*
Y1191798D03*
Y1188451D03*
Y1205184D03*
Y1198491D03*
Y1255381D03*
X826750Y1262074D03*
X823877Y1252034D03*
X815241Y1248688D03*
X826501Y1254553D03*
X815241Y1265420D03*
Y1262074D03*
X828699Y766798D03*
X828799Y1054593D03*
Y1258727D03*
X842630Y1256912D03*
X828799Y1265420D03*
X844841Y957546D03*
Y954200D03*
Y994357D03*
X844941Y1021129D03*
Y1024475D03*
Y1051247D03*
Y1258727D03*
Y1252034D03*
X844997Y1248155D03*
X844941Y1265420D03*
Y1262074D03*
X998205Y195735D03*
Y192191D03*
X1000705Y195735D03*
Y192191D03*
X998205Y199278D03*
X1000705D03*
X998205Y202821D03*
X1000705D03*
X1001970Y1251522D03*
X1003831Y1259077D03*
X1002070Y1256942D03*
X1003841Y1265420D03*
Y1262074D03*
X1012769Y766798D03*
X1019983Y994357D03*
X1012541Y1054593D03*
X1017900Y1247632D03*
X1019983Y1255381D03*
Y1252034D03*
Y1248688D03*
Y1262074D03*
Y1265420D03*
X1033441Y766798D03*
X1028683Y957546D03*
Y954200D03*
Y1021129D03*
Y1024475D03*
Y1051247D03*
X1033541Y1258727D03*
X1030830Y1261302D03*
X1030270Y1256042D03*
X1033541Y1265420D03*
X1042241Y780184D03*
Y773491D03*
Y786877D03*
Y803609D03*
Y796916D03*
Y790223D03*
Y847113D03*
Y853806D03*
Y860499D03*
Y863845D03*
Y883924D03*
Y877231D03*
Y870538D03*
Y890617D03*
Y897310D03*
Y900656D03*
Y914042D03*
Y907349D03*
Y927428D03*
Y920735D03*
Y934121D03*
Y944160D03*
Y937467D03*
Y950853D03*
Y980971D03*
Y974278D03*
Y994357D03*
Y987664D03*
Y1027822D03*
Y1021129D03*
Y1047900D03*
Y1041207D03*
Y1034515D03*
Y1061286D03*
Y1054593D03*
Y1074672D03*
Y1067979D03*
Y1091404D03*
Y1081365D03*
Y1084711D03*
Y1098097D03*
Y1111483D03*
Y1104790D03*
Y1128215D03*
Y1118176D03*
Y1121522D03*
Y1141601D03*
Y1134908D03*
Y1148294D03*
Y1154987D03*
Y1158333D03*
Y1171719D03*
Y1165026D03*
Y1185105D03*
Y1178412D03*
Y1191798D03*
Y1208530D03*
Y1201837D03*
Y1195144D03*
X1047010Y1259222D03*
X1049683Y1258727D03*
Y1265420D03*
Y1262074D03*
X1044930Y1263492D03*
X1058383Y770144D03*
X1063141Y766798D03*
X1058383Y776837D03*
Y786877D03*
Y783530D03*
Y800263D03*
Y793570D03*
Y850459D03*
Y843766D03*
Y867192D03*
Y860499D03*
Y857152D03*
Y873885D03*
Y880577D03*
Y887270D03*
Y897310D03*
Y893963D03*
Y917389D03*
Y910696D03*
Y904003D03*
Y924081D03*
Y934121D03*
Y930774D03*
Y947507D03*
Y940814D03*
Y957546D03*
Y954200D03*
Y977625D03*
Y970932D03*
Y991011D03*
Y984318D03*
Y994357D03*
Y1021129D03*
Y1024475D03*
Y1031168D03*
Y1044554D03*
Y1037861D03*
Y1051247D03*
Y1071326D03*
Y1064633D03*
Y1078018D03*
Y1094751D03*
Y1088058D03*
Y1081365D03*
Y1108137D03*
Y1101444D03*
Y1124869D03*
Y1118176D03*
Y1114829D03*
Y1144948D03*
Y1138255D03*
Y1131562D03*
Y1161680D03*
Y1154987D03*
Y1151641D03*
Y1175066D03*
Y1168373D03*
Y1181759D03*
Y1191798D03*
Y1188452D03*
Y1205184D03*
Y1198491D03*
X1063241Y1258727D03*
X1061330Y1262074D03*
X1058383Y1248688D03*
X1059410Y1252272D03*
X1063241Y1265420D03*
X1079383Y994357D03*
X1076520Y1259072D03*
X1079383Y1258727D03*
X1088262Y1252293D03*
X1079383Y1265420D03*
Y1262074D03*
X1092709Y766775D03*
X1088083Y957546D03*
Y954200D03*
X1101641Y1061286D03*
X1090273Y1246800D03*
X1092941Y1258727D03*
X1088083Y1248688D03*
X1091000Y1262074D03*
X1106200Y1250162D03*
X1092941Y1265420D03*
X1103530Y1263602D03*
X1117783Y957546D03*
Y954200D03*
Y994357D03*
Y1057940D03*
X1120800Y1262074D03*
X1117783Y1248688D03*
X1109083Y1265420D03*
X1109050Y1262972D03*
X1106740Y1267902D03*
X1122541Y766798D03*
X1122641Y1258727D03*
X1133200Y1255702D03*
X1122620Y1264622D03*
X1152241Y766798D03*
X1147483Y957546D03*
Y954200D03*
X1138783Y994357D03*
X1152341Y1258727D03*
X1138783Y1255381D03*
Y1258727D03*
Y1252034D03*
X1147483Y1248688D03*
X1150400Y1262074D03*
X1148563Y1257097D03*
X1152341Y1265420D03*
X1138783Y1262027D03*
X1137980Y1264212D03*
X1161041Y1061286D03*
X1168483Y1255381D03*
Y1258727D03*
Y1252034D03*
Y1265420D03*
Y1262074D03*
X1177183Y957546D03*
Y954200D03*
Y994357D03*
X1177120Y1248688D03*
X1177222Y1255567D03*
X1182041Y1265420D03*
X1181850Y1260192D03*
X1179180Y1265872D03*
X1198183Y957546D03*
Y954200D03*
Y994357D03*
Y1252034D03*
X1198180Y1262112D03*
X1196470Y1265382D03*
X1193590Y1267912D03*
X1195470Y1262802D03*
X1211641Y766798D03*
X1213983Y1000437D03*
X1216663Y1000395D03*
X1212533Y1002557D03*
X1205033D03*
X1207533D03*
X1210033D03*
X1208830Y1256692D03*
X1206883Y1248688D03*
X1207048Y1255174D03*
X1211240Y1265502D03*
X1208750Y1266546D03*
X1214132Y1614292D03*
X1202072D03*
X1217532D03*
X1205472D03*
X1214132Y1602380D03*
X1202072D03*
X1217532D03*
X1205472D03*
X1227883Y957546D03*
Y954200D03*
Y994357D03*
X1233703Y999608D03*
X1231023Y999650D03*
X1220441Y1061286D03*
X1224189Y1259155D03*
X1226899Y1257968D03*
X1227847Y1251715D03*
X1227670Y1265162D03*
X1225540Y1266402D03*
X1226192Y1614292D03*
X1229592D03*
X1226192Y1602380D03*
X1229592D03*
X1236583Y1057940D03*
Y1248688D03*
X1238252Y1614292D03*
X1241652D03*
X1238252Y1602380D03*
X1241652D03*
X1262372Y1614292D03*
X1250312D03*
X1265772D03*
X1253712D03*
X1262372Y1602380D03*
X1250312D03*
X1265772D03*
X1253712D03*
X1274432Y1614292D03*
X1277832D03*
X1274432Y1602380D03*
X1277832D03*
X1298552Y1614292D03*
X1286492D03*
X1289892D03*
X1298552Y1602380D03*
X1286492D03*
X1289892D03*
X1310612Y1614292D03*
X1314012D03*
X1301952D03*
X1310612Y1602380D03*
X1314012D03*
X1301952D03*
X1322672Y1614292D03*
X1326072D03*
X1322672Y1602380D03*
X1326072D03*
X1346792Y1614292D03*
X1334732D03*
X1338132D03*
X1346792Y1602380D03*
X1334732D03*
X1338132D03*
X1358852Y1614292D03*
X1362252D03*
X1350192D03*
X1358852Y1602380D03*
X1362252D03*
X1350192D03*
X1370912Y1614292D03*
X1374312D03*
X1370912Y1602380D03*
X1374312D03*
X1382972Y1614292D03*
X1386372D03*
X1382972Y1602380D03*
X1386372D03*
X1477755Y1578182D03*
X1462295D03*
X1474355D03*
X1465695D03*
X1477755Y1590094D03*
X1462295D03*
X1474355D03*
X1465695D03*
X1489815Y1578182D03*
X1486415D03*
X1489815Y1590094D03*
X1486415D03*
X1501875Y1578182D03*
X1498475D03*
X1501875Y1590094D03*
X1498475D03*
X1525995Y1578182D03*
X1513935D03*
X1522595D03*
X1510535D03*
X1525995Y1590094D03*
X1513935D03*
X1522595D03*
X1510535D03*
X1538055Y1578182D03*
X1534655D03*
X1538055Y1590094D03*
X1534655D03*
X1550115Y1578182D03*
X1558775D03*
X1546715D03*
X1550115Y1590094D03*
X1558775D03*
X1546715D03*
X1574235Y1578182D03*
X1562175D03*
X1570835D03*
X1574235Y1590094D03*
X1562175D03*
X1570835D03*
X1586295Y1578182D03*
X1582895D03*
X1586295Y1590094D03*
X1582895D03*
X1605800Y766478D03*
X1601922Y1000198D03*
X1599489Y999665D03*
X1597041Y1061286D03*
X1606481Y1258649D03*
X1608000Y1261662D03*
X1607897Y1264445D03*
X1598355Y1578182D03*
X1607015D03*
X1594955D03*
X1598355Y1590094D03*
X1607015D03*
X1594955D03*
X1613083Y957546D03*
Y954200D03*
X1616609Y1000735D03*
X1616469Y1003135D03*
X1623539Y1000135D03*
X1620489Y1003135D03*
X1623589Y1002865D03*
X1620399Y1000325D03*
X1621983Y1258727D03*
X1624600Y1262074D03*
X1613183Y1252034D03*
X1613027Y1248805D03*
X1609056Y1250602D03*
X1623930Y1252242D03*
X1613019Y1261235D03*
X1622475Y1578182D03*
X1610415D03*
X1619075D03*
X1622475Y1590094D03*
X1610415D03*
X1619075D03*
X1626741Y766798D03*
X1626249Y1002825D03*
X1626741Y1258727D03*
X1634535Y1578182D03*
X1631135D03*
X1634535Y1590094D03*
X1631135D03*
X1656441Y766798D03*
X1642783Y957546D03*
Y954200D03*
X1648205Y998632D03*
X1656441Y1061286D03*
X1642883Y1255381D03*
Y1258727D03*
Y1252034D03*
X1651679Y1248885D03*
X1653140Y1257862D03*
X1656188Y1264964D03*
X1642788Y1264464D03*
X1642883Y1262074D03*
X1656170Y1260352D03*
X1654600Y1262742D03*
X1646595Y1578182D03*
X1643195D03*
X1646595Y1590094D03*
X1643195D03*
X1672583Y957546D03*
Y954200D03*
Y994357D03*
Y1255381D03*
Y1258727D03*
Y1248688D03*
X1672188Y1263764D03*
X1686041Y766798D03*
X1686141Y1258727D03*
X1681179Y1252034D03*
X1683578Y1253780D03*
X1686119Y1264985D03*
X1681309Y1262074D03*
X1683500Y1264312D03*
X1702183Y957546D03*
Y954200D03*
Y994357D03*
X1702283Y1057940D03*
X1699852Y1245418D03*
X1699089Y1258842D03*
X1702283Y1248688D03*
X1702249Y1265420D03*
X1702283Y1262074D03*
X1699030Y1263912D03*
X1715841Y766798D03*
Y1061286D03*
X1713620Y1258512D03*
X1711109Y1252034D03*
X1713930Y1262074D03*
X1715839Y1265420D03*
X1737020Y112177D03*
Y109677D03*
X1731983Y957546D03*
Y954200D03*
Y994357D03*
X1731683Y1057940D03*
X1727041Y1248688D03*
X1731983Y1255381D03*
Y1258727D03*
Y1252034D03*
Y1248688D03*
X1731939Y1265420D03*
X1731983Y1262074D03*
X1747650Y109677D03*
Y112177D03*
X1744106Y109677D03*
Y112177D03*
X1740563Y109677D03*
Y112177D03*
X1745541Y766798D03*
Y1258727D03*
X1743710Y1262074D03*
X1742337Y1252300D03*
X1745541Y1265420D03*
X1761683Y957546D03*
Y954200D03*
Y994357D03*
X1756922Y1247632D03*
X1761683Y1255381D03*
Y1258727D03*
X1770299Y1252034D03*
X1761683Y1248688D03*
Y1262074D03*
Y1265420D03*
X1773559Y767345D03*
X1775241Y780184D03*
Y773491D03*
Y786877D03*
Y803609D03*
Y796916D03*
Y790223D03*
Y847113D03*
Y853806D03*
Y860499D03*
Y863845D03*
Y883924D03*
Y877231D03*
Y870538D03*
Y890617D03*
Y897310D03*
Y900656D03*
Y914042D03*
Y907349D03*
Y927428D03*
Y920735D03*
Y934121D03*
Y944160D03*
Y937467D03*
Y950853D03*
Y980971D03*
Y974278D03*
Y994357D03*
Y987664D03*
Y1027822D03*
Y1021129D03*
Y1047900D03*
Y1041207D03*
Y1034515D03*
Y1061286D03*
Y1054593D03*
Y1074672D03*
Y1067979D03*
Y1091404D03*
Y1081365D03*
Y1084711D03*
Y1098097D03*
Y1111483D03*
Y1104790D03*
Y1128215D03*
Y1118176D03*
Y1121522D03*
Y1141601D03*
Y1134908D03*
Y1148294D03*
Y1154987D03*
Y1158333D03*
Y1171719D03*
Y1165026D03*
Y1185105D03*
Y1178412D03*
Y1191798D03*
Y1208530D03*
Y1201837D03*
Y1195144D03*
Y1258727D03*
X1788219Y1259312D03*
X1773390Y1262074D03*
X1773480Y1253692D03*
X1775241Y1265420D03*
X1788360Y1264522D03*
X1791383Y770144D03*
Y776837D03*
Y786877D03*
Y783530D03*
Y800263D03*
Y793570D03*
Y850459D03*
Y843766D03*
Y867192D03*
Y860499D03*
Y857152D03*
Y873885D03*
Y880577D03*
Y887270D03*
Y897310D03*
Y893963D03*
Y917389D03*
Y910696D03*
Y904003D03*
Y924081D03*
Y934121D03*
Y930774D03*
Y947507D03*
Y940814D03*
Y957546D03*
Y954200D03*
Y977625D03*
Y970932D03*
Y991011D03*
Y984318D03*
Y994357D03*
Y1021129D03*
Y1024475D03*
Y1031168D03*
Y1044554D03*
Y1037861D03*
X1791083Y1051247D03*
X1791383Y1071325D03*
Y1064633D03*
Y1078018D03*
Y1094751D03*
Y1088058D03*
Y1081365D03*
Y1108136D03*
Y1101444D03*
Y1124869D03*
Y1118176D03*
Y1114829D03*
Y1144947D03*
Y1138255D03*
Y1131562D03*
Y1161680D03*
Y1154987D03*
Y1151640D03*
Y1175066D03*
Y1168373D03*
Y1181758D03*
Y1191798D03*
Y1188451D03*
Y1205184D03*
Y1198491D03*
X1788373Y1241769D03*
X1800427Y1248125D03*
X1803100Y1262074D03*
X1800019Y1252034D03*
X1791383Y1248688D03*
Y1265420D03*
Y1262074D03*
X1804841Y766798D03*
X1804941Y1054593D03*
X1815063Y1233103D03*
X1804941Y1258727D03*
X1813814Y1254693D03*
X1804941Y1265420D03*
X1820983Y957546D03*
Y954200D03*
Y994357D03*
X1821083Y1021129D03*
Y1024475D03*
Y1051247D03*
X1830379Y1250358D03*
X1829920Y1258322D03*
X1821139Y1248155D03*
X1821083Y1262074D03*
Y1265420D03*
X1829940Y1263662D03*
G54D29*
X159474Y1328627D03*
X183847Y1328652D03*
X208247D03*
X275289Y583576D03*
Y607735D03*
Y631889D03*
Y656043D03*
X270252Y676260D03*
Y700414D03*
X387897Y1242785D03*
X412297D03*
X436619D03*
X461019D03*
X485419D03*
X673093Y1328652D03*
X697466Y1328677D03*
X721866D03*
X1100800Y259362D03*
X1100700Y283662D03*
X1131100Y1364962D03*
X1155500D03*
X1179900D03*
X1364038Y1242785D03*
X1388438D03*
X1412760D03*
X1437160D03*
X1461560D03*
X1577000Y599762D03*
Y624262D03*
Y648762D03*
Y673162D03*
Y697662D03*
Y722162D03*
X1634259Y1362248D03*
X1658632Y1362273D03*
X1683032D03*
G54D51*
X705760Y-26500D03*
Y-16500D03*
D03*
Y-6500D03*
X730760Y-26500D03*
Y-16500D03*
D03*
Y-6500D03*
X822720Y3500D03*
Y13500D03*
D03*
Y23500D03*
X847720Y3500D03*
Y13500D03*
D03*
Y23500D03*
X973180Y-26500D03*
Y-16500D03*
D03*
Y-6500D03*
Y3500D03*
Y13500D03*
Y23500D03*
Y13500D03*
X998180Y-26500D03*
Y-16500D03*
D03*
Y-6500D03*
Y3500D03*
Y13500D03*
Y23500D03*
Y13500D03*
X1015152Y-26511D03*
Y-36511D03*
Y-26511D03*
Y-16511D03*
D03*
Y-6511D03*
D03*
Y3489D03*
D03*
Y13489D03*
D03*
Y23489D03*
X1040152Y-26511D03*
Y-36511D03*
Y-26511D03*
Y-16511D03*
D03*
Y-6511D03*
D03*
Y3489D03*
D03*
Y13489D03*
D03*
Y23489D03*
X1282572Y-36511D03*
Y-26511D03*
D03*
Y-16511D03*
D03*
Y-6511D03*
Y3489D03*
Y-6511D03*
Y3489D03*
Y13489D03*
Y23489D03*
Y13489D03*
X1307572Y-36511D03*
Y-26511D03*
D03*
Y-16511D03*
D03*
Y-6511D03*
Y3489D03*
Y-6511D03*
Y3489D03*
Y13489D03*
Y23489D03*
Y13489D03*
X1324471Y-26511D03*
Y-36511D03*
Y-26511D03*
Y-16511D03*
D03*
Y-6511D03*
D03*
Y3489D03*
D03*
Y13489D03*
D03*
Y23489D03*
X1349471Y-26511D03*
Y-36511D03*
Y-26511D03*
Y-16511D03*
D03*
Y-6511D03*
D03*
Y3489D03*
D03*
Y13489D03*
D03*
Y23489D03*
X1474931Y-36511D03*
Y-26511D03*
D03*
Y-16511D03*
D03*
Y-6511D03*
Y3489D03*
Y-6511D03*
Y3489D03*
Y13489D03*
Y23489D03*
Y13489D03*
X1499931Y-36511D03*
Y-26511D03*
D03*
Y-16511D03*
D03*
Y-6511D03*
Y3489D03*
Y-6511D03*
Y3489D03*
Y13489D03*
Y23489D03*
Y13489D03*
X1565236Y184783D03*
Y264035D03*
G54D54*
X793879Y194881D03*
X789942Y204724D03*
X793879Y214567D03*
X805690Y188976D03*
Y220472D03*
X817501Y194881D03*
Y214567D03*
X821438Y204724D03*
X841240Y1407480D03*
X832154Y1411244D03*
X828390Y1420330D03*
X832154Y1429416D03*
X841240Y1433180D03*
X850326Y1411244D03*
X854090Y1420330D03*
X850326Y1429416D03*
X1003390Y1420330D03*
X1016240Y1407480D03*
X1007154Y1411244D03*
Y1429416D03*
X1016240Y1433180D03*
X1025326Y1411244D03*
X1029090Y1420330D03*
X1025326Y1429416D03*
X1045847Y194881D03*
X1041910Y204724D03*
X1045847Y214567D03*
X1069469Y194881D03*
X1057658Y188976D03*
X1069469Y214567D03*
X1057658Y220472D03*
X1073406Y204724D03*
G54D11*
X3010Y63308D03*
Y123308D03*
Y163308D03*
Y183308D03*
Y203308D03*
Y223308D03*
Y243308D03*
Y263308D03*
Y283308D03*
Y303308D03*
X10884Y321693D03*
Y341693D03*
Y361693D03*
Y381693D03*
Y401693D03*
Y421693D03*
Y441693D03*
Y461693D03*
Y481693D03*
Y501693D03*
Y521693D03*
Y661693D03*
Y681693D03*
Y701693D03*
Y721693D03*
Y741693D03*
Y781693D03*
Y801693D03*
Y821693D03*
Y841693D03*
Y861693D03*
Y881693D03*
Y901693D03*
Y921693D03*
Y941693D03*
Y961693D03*
Y981693D03*
Y1001693D03*
Y1021693D03*
Y1041693D03*
Y1061693D03*
Y1081693D03*
Y1101693D03*
Y1121693D03*
Y1141693D03*
Y1161693D03*
Y1181693D03*
Y1201693D03*
Y1221693D03*
Y1241693D03*
Y1401693D03*
Y1421693D03*
Y1441693D03*
Y1461693D03*
Y1481693D03*
Y1501693D03*
Y1521693D03*
Y1541693D03*
Y1561693D03*
Y1581693D03*
X26615Y670036D03*
X28601Y1617541D03*
Y1637541D03*
Y1657541D03*
Y1677541D03*
X38220Y595862D03*
X54593Y19183D03*
X87565Y670441D03*
X94473Y698926D03*
X127313Y649765D03*
X114021Y669409D03*
X118021D03*
X127738Y659226D03*
X117220Y1680287D03*
X130067Y650213D03*
X134205Y643603D03*
X128193Y662015D03*
X128275Y665515D03*
X190800Y675662D03*
X219752Y1405499D03*
Y1401999D03*
Y1398599D03*
X259845Y461117D03*
X282640Y214102D03*
X301751Y127466D03*
Y124466D03*
Y121466D03*
X311758Y124469D03*
Y121469D03*
Y127469D03*
X313995Y237724D03*
X335285Y210609D03*
X332285D03*
X325755Y230719D03*
X338985Y229509D03*
X325855Y227619D03*
X325055Y237219D03*
X328965Y237214D03*
X332465D03*
X381068Y1674824D03*
X373320Y1688202D03*
X388220Y1631404D03*
X445944Y359053D03*
X446730Y382432D03*
X443744Y429553D03*
X451421D03*
X443744Y452462D03*
X437520Y484837D03*
X447520D03*
X442520D03*
X451520D03*
X448079Y1562177D03*
X443910Y1555602D03*
X450020Y1570412D03*
X453621Y359053D03*
X462720Y404762D03*
X465421Y424928D03*
X466520Y475812D03*
X456520Y484837D03*
X461520D03*
X456961Y1559697D03*
X456020Y1580412D03*
X464020D03*
X462079Y1572177D03*
X454661Y1596755D03*
X459779Y1609235D03*
X480393Y429412D03*
X479169Y484696D03*
X474169D03*
X484169D03*
X478308Y1439986D03*
X502070Y424787D03*
X488070Y429412D03*
X498169Y484696D03*
X493169D03*
X488169D03*
X513444Y473281D03*
X503169Y475671D03*
X550024Y369123D03*
Y401023D03*
X557701Y369123D03*
X649218Y504277D03*
X641386Y1687283D03*
X661534Y41748D03*
X656877Y514716D03*
X661743Y521166D03*
X657734Y528255D03*
X656725Y1657619D03*
X669004Y41698D03*
X694720Y491962D03*
X690720D03*
X702462Y1673258D03*
X725537Y-23978D03*
Y-19022D03*
Y-13978D03*
Y-9022D03*
X719194Y172909D03*
X714202D03*
X719194Y177865D03*
X714202D03*
X719194Y184909D03*
X714202D03*
X719194Y189865D03*
X714202D03*
X719194Y196409D03*
X714202D03*
X719194Y201365D03*
X714202D03*
X719194Y208243D03*
X714202D03*
X719194Y213199D03*
X714202D03*
X714203Y1639776D03*
X745685Y265322D03*
Y269322D03*
X730282Y1580391D03*
X741382Y1585251D03*
Y1580121D03*
X735882Y1580391D03*
X730282Y1590651D03*
Y1585521D03*
X735882Y1590651D03*
X732504Y1600321D03*
Y1597321D03*
X744504D03*
Y1600321D03*
X741504Y1597321D03*
Y1600321D03*
X735504Y1597321D03*
Y1600321D03*
X738504Y1597321D03*
Y1600321D03*
X744504Y1609521D03*
Y1612521D03*
X741504Y1609521D03*
X738504D03*
X735504D03*
X741504Y1612521D03*
X738504D03*
X735504D03*
X732504Y1603321D03*
Y1606321D03*
X744504Y1603321D03*
Y1606321D03*
X741504Y1603321D03*
Y1606321D03*
X738504Y1603321D03*
X735504D03*
X738504Y1606321D03*
X735504D03*
X742655Y1682362D03*
Y1678362D03*
X761720Y283262D03*
X748085Y278942D03*
X758360Y276122D03*
X747504Y1600321D03*
Y1609521D03*
Y1612521D03*
X750504D03*
Y1609521D03*
X747504Y1603321D03*
Y1606321D03*
X755859Y1686090D03*
X755183Y1709850D03*
X764850Y249792D03*
X776052Y1611893D03*
X763359Y1729520D03*
X785135Y281822D03*
Y267822D03*
X788079Y1580393D03*
X782479D03*
X793579D03*
X788079Y1590653D03*
X782479D03*
Y1585523D03*
X793579Y1590653D03*
Y1585523D03*
X785052Y1600693D03*
Y1597693D03*
X782052D03*
Y1600693D03*
X794052D03*
X788052D03*
X791052D03*
X794052Y1597693D03*
X788052D03*
X791052D03*
X785052Y1607793D03*
X782052D03*
X779052D03*
X785052Y1611893D03*
X782052D03*
X779052D03*
X794052Y1607793D03*
X791052D03*
X788052D03*
X797052Y1611893D03*
X794052D03*
X788052D03*
X791052D03*
X785052Y1603693D03*
X782052D03*
X794052D03*
X788052D03*
X791052D03*
X797052Y1607793D03*
X824479Y1580393D03*
Y1590653D03*
Y1585523D03*
X824052Y1597693D03*
Y1600693D03*
X827052D03*
Y1597693D03*
X824052Y1611893D03*
Y1607793D03*
Y1603693D03*
X827052Y1611893D03*
Y1607793D03*
Y1603693D03*
X821052Y1611893D03*
Y1607793D03*
X818052Y1611893D03*
X842497Y6022D03*
Y16022D03*
Y20978D03*
Y10978D03*
X830079Y1580393D03*
X835579D03*
X833052Y1597693D03*
X836052D03*
X830079Y1590653D03*
X835579D03*
X833052Y1600693D03*
X836052D03*
X835579Y1585523D03*
X830052Y1600693D03*
Y1597693D03*
X833052Y1603693D03*
X836052D03*
X839052Y1611893D03*
X833052Y1607793D03*
Y1611893D03*
X836052Y1607793D03*
Y1611893D03*
X830052D03*
Y1607793D03*
Y1603693D03*
X839052Y1607793D03*
X866479Y1580393D03*
X872079D03*
X866052Y1597693D03*
X869052D03*
X866479Y1590653D03*
X869052Y1600693D03*
X866052D03*
X872052Y1597693D03*
X872079Y1590653D03*
X872052Y1600693D03*
X866479Y1585523D03*
X875052Y1597693D03*
Y1600693D03*
X869052Y1603693D03*
X866052D03*
X872052D03*
X869052Y1607793D03*
Y1611893D03*
X866052Y1607793D03*
X863052Y1611893D03*
X866052D03*
X872052Y1607793D03*
Y1611893D03*
X875052Y1603693D03*
Y1607793D03*
Y1611893D03*
X863052Y1607793D03*
X860052Y1611893D03*
X877579Y1580393D03*
Y1585523D03*
X878052Y1597693D03*
Y1600693D03*
X877579Y1590653D03*
X878052Y1603693D03*
Y1607793D03*
X881052Y1611893D03*
X878052D03*
X881052Y1607793D03*
X908675Y455386D03*
X908479Y1580393D03*
Y1590653D03*
Y1585523D03*
X908052Y1600693D03*
Y1597693D03*
Y1611893D03*
X905052D03*
X902052D03*
X908052Y1607793D03*
X905052D03*
X908052Y1603693D03*
X913913Y455396D03*
X919579Y1580393D03*
X914079D03*
X919579Y1590653D03*
X914079D03*
X919579Y1585523D03*
X917052Y1600693D03*
Y1597693D03*
X914052Y1600693D03*
Y1597693D03*
X911052Y1600693D03*
Y1597693D03*
X920052Y1600693D03*
Y1597693D03*
X917052Y1611893D03*
X914052D03*
X911052D03*
X917052Y1607793D03*
X914052D03*
X911052D03*
X920052Y1611893D03*
X923052D03*
Y1607793D03*
X920052D03*
X917052Y1603693D03*
X914052D03*
X911052D03*
X920052D03*
X957420Y153699D03*
X960420D03*
X968022Y1620730D03*
X965022D03*
X971022D03*
X965022Y1632730D03*
X968022Y1629730D03*
X965022D03*
X968022Y1626730D03*
X965022D03*
Y1623730D03*
X968022D03*
X971022Y1626730D03*
Y1623730D03*
Y1629730D03*
Y1632730D03*
X968022D03*
X981445Y181058D03*
X1002735Y153943D03*
X999735D03*
X999915Y180548D03*
X996415D03*
X992505Y180553D03*
X993205Y174053D03*
X993305Y170953D03*
X990495Y212923D03*
X1001065Y304622D03*
Y307122D03*
Y309622D03*
X996662Y1620870D03*
X999662D03*
X1002662D03*
Y1626870D03*
Y1623870D03*
X996662Y1629870D03*
X999662Y1626870D03*
X996662D03*
Y1623870D03*
X999662D03*
X996662Y1632870D03*
X1021908Y60392D03*
Y120392D03*
X1015300Y148736D03*
X1012187Y148749D03*
X1006435Y172843D03*
X1009895Y192359D03*
X1008067Y194356D03*
X1019935Y206463D03*
Y203333D03*
X1010828Y304822D03*
Y307322D03*
Y309822D03*
X1034929Y-33989D03*
Y-29033D03*
Y-13989D03*
Y-9033D03*
Y-23989D03*
Y-19033D03*
Y-3989D03*
Y967D03*
X1036915Y290969D03*
X1035920Y428962D03*
X1034252Y1623870D03*
Y1626870D03*
X1031252Y1623870D03*
Y1626870D03*
X1028252Y1623870D03*
Y1626870D03*
X1031252Y1620870D03*
X1034252D03*
X1028252D03*
X1065721Y1633043D03*
X1068721D03*
Y1624043D03*
Y1627043D03*
Y1630043D03*
X1065721Y1624043D03*
Y1627043D03*
Y1630043D03*
X1062721Y1633043D03*
Y1624043D03*
Y1627043D03*
Y1630043D03*
X1059721Y1633043D03*
Y1624043D03*
Y1627043D03*
Y1630043D03*
X1068721Y1621043D03*
X1065721D03*
X1062721D03*
X1059721D03*
X1099901Y1633203D03*
Y1624203D03*
Y1627203D03*
Y1630203D03*
Y1621203D03*
X1093901Y1633203D03*
X1096901D03*
Y1624203D03*
Y1627203D03*
Y1630203D03*
X1093901Y1624203D03*
Y1627203D03*
Y1630203D03*
X1090901Y1633203D03*
X1087901D03*
X1090901Y1624203D03*
X1087901D03*
Y1627203D03*
X1090901D03*
X1087901Y1630203D03*
X1090901D03*
X1096901Y1621203D03*
X1093901D03*
X1087901D03*
X1090901D03*
X1132142Y1555301D03*
X1120472Y1615010D03*
X1127377Y1628485D03*
X1131632Y1625969D03*
X1148220Y501362D03*
X1139392Y1620851D03*
X1172720Y527862D03*
X1202600Y759662D03*
X1245574Y234042D03*
X1245593Y241462D03*
Y237462D03*
X1280223Y256841D03*
X1279841Y253052D03*
X1344248Y-33989D03*
Y-29033D03*
Y-13989D03*
Y-9033D03*
Y-23989D03*
Y-19033D03*
Y-3989D03*
Y967D03*
X1412954Y138742D03*
X1404402D03*
X1409716Y171696D03*
X1418268D03*
X1454829Y1439732D03*
X1465179Y213102D03*
X1477700Y236522D03*
X1466292Y631634D03*
X1473228D03*
X1486884Y374338D03*
X1479207D03*
X1478203Y406207D03*
X1493384Y419263D03*
X1481384Y419392D03*
X1505378Y225502D03*
X1509571Y239053D03*
X1507860Y249792D03*
X1513110Y247412D03*
X1522883Y305187D03*
X1526216Y306909D03*
X1529002Y32290D03*
X1528716Y306909D03*
X1533716D03*
X1536216D03*
X1534899Y310447D03*
X1559387Y589340D03*
X1564690Y663302D03*
X1619980Y590685D03*
X1615800Y584062D03*
X1620170Y623762D03*
X1622770D03*
X1612980D03*
X1620170Y626362D03*
X1622770D03*
X1612980D03*
X1615580Y650092D03*
Y657762D03*
X1620170D03*
X1622770D03*
X1622109Y652469D03*
X1619509D03*
X1612980Y657762D03*
Y650092D03*
X1615580Y660362D03*
X1620170D03*
X1622770D03*
X1612980D03*
X1622109Y686469D03*
X1619509D03*
X1615580Y684092D03*
X1612980D03*
X1622770Y691762D03*
Y694362D03*
X1620170Y691762D03*
Y694362D03*
X1615580D03*
X1612980D03*
X1615580Y691762D03*
X1612980D03*
X1619509Y720469D03*
X1622109D03*
X1612980Y718092D03*
X1615580D03*
X1610100Y725152D03*
X1637667Y587844D03*
Y590444D03*
X1629867D03*
Y587844D03*
X1632467Y590444D03*
Y587844D03*
X1635067Y590444D03*
Y587844D03*
X1626606Y616576D03*
X1629206D03*
X1631806D03*
X1634406D03*
X1637006D03*
X1639606D03*
X1630570Y623762D03*
X1627970D03*
X1625370D03*
X1636412Y638451D03*
X1636417Y630007D03*
X1640061Y639497D03*
X1636412Y641051D03*
X1630570Y626362D03*
X1627970D03*
X1625370D03*
X1630198Y638651D03*
Y636051D03*
Y641251D03*
X1633305Y638651D03*
Y641251D03*
X1630198Y632851D03*
X1630214Y629907D03*
X1633321D03*
X1640061Y644457D03*
Y641977D03*
X1630570Y657762D03*
X1627970D03*
X1625370D03*
X1629909Y652469D03*
X1632509D03*
X1624709D03*
X1627309D03*
X1630198Y643851D03*
X1633305Y646451D03*
Y643851D03*
X1630198Y646451D03*
X1636412Y672451D03*
X1636417Y664007D03*
X1640061Y673497D03*
X1630570Y660362D03*
X1627970D03*
X1625370D03*
X1630198Y672651D03*
Y670051D03*
X1633305Y672651D03*
X1630198Y666851D03*
X1630214Y663907D03*
X1633321D03*
X1629909Y686469D03*
X1632509D03*
X1624709D03*
X1627309D03*
X1640061Y678457D03*
Y675977D03*
X1636412Y675051D03*
X1630198Y677851D03*
Y675251D03*
X1633305Y680451D03*
Y675251D03*
Y677851D03*
X1630198Y680451D03*
X1636417Y698007D03*
X1636412Y706451D03*
X1630214Y697907D03*
X1633321D03*
X1630198Y704051D03*
Y706651D03*
X1633305D03*
X1630198Y700851D03*
X1625370Y691762D03*
Y694362D03*
X1630570D03*
Y691762D03*
X1627970D03*
Y694362D03*
X1640061Y707497D03*
Y712457D03*
Y709977D03*
X1636412Y709051D03*
X1632509Y720469D03*
X1627309D03*
X1629909D03*
X1624709D03*
X1633305Y711851D03*
Y709251D03*
X1630198D03*
Y711851D03*
X1633305Y714451D03*
X1630198D03*
X1642873Y604206D03*
Y607206D03*
X1645625Y600495D03*
Y603295D03*
X1642873Y601206D03*
Y598206D03*
X1645625Y597795D03*
Y594995D03*
X1642873Y595006D03*
X1642340Y618546D03*
X1642873Y610206D03*
X1645661Y639497D03*
X1656550Y653086D03*
X1645661Y644457D03*
Y641977D03*
Y673497D03*
X1656550Y687086D03*
X1645661Y678457D03*
Y675977D03*
Y707497D03*
Y709977D03*
Y712457D03*
X1665700Y583462D03*
X1661510Y583442D03*
X1672770Y580512D03*
X1669770D03*
X1663720Y620434D03*
X1659914Y649681D03*
Y683681D03*
Y717681D03*
X1686154Y434160D03*
X1704444Y407045D03*
X1697914Y427155D03*
X1698014Y424055D03*
X1701124Y433650D03*
X1697214Y433655D03*
X1704624Y433650D03*
X1717280Y174970D03*
X1707444Y407045D03*
X1711144Y425945D03*
X1765870Y179392D03*
X1780320Y177602D03*
G54D14*
X26054Y195148D03*
X25752Y203274D03*
X24754Y220220D03*
X24814Y236472D03*
X35600Y227380D03*
X45182Y426310D03*
X45034Y449106D03*
X62833Y410047D03*
X62808Y418425D03*
X50138Y426310D03*
X60393D03*
X49990Y449106D03*
X73020Y28406D03*
Y40020D03*
X65349Y426310D03*
X75516Y436519D03*
X73865Y763164D03*
X94279Y28406D03*
X87193D03*
X80106D03*
X94279Y40020D03*
X87193D03*
X80106D03*
X85826Y424319D03*
Y420319D03*
X82661Y449604D03*
X79451Y699517D03*
X92895Y1737108D03*
X108453Y28406D03*
X101366D03*
X108453Y40020D03*
X101366D03*
X104220Y400862D03*
X101720D03*
X113597Y488434D03*
X102152Y509374D03*
X102334Y500628D03*
X102359Y497374D03*
X102152Y513374D03*
X108909Y654926D03*
X102909Y648926D03*
Y642926D03*
Y655102D03*
X108909Y642926D03*
X122626Y28406D03*
X115539D03*
X122626Y40020D03*
X115539D03*
X125007Y392071D03*
Y388071D03*
Y384071D03*
Y396071D03*
X114507Y404571D03*
X117597Y488434D03*
X114909Y654926D03*
Y648926D03*
Y642926D03*
X116798Y1617262D03*
X112895Y1737108D03*
X129713Y28406D03*
Y40020D03*
X136301Y179095D03*
X143340Y204622D03*
X140974Y396885D03*
Y401885D03*
Y399385D03*
X142166Y490835D03*
X144263Y1412275D03*
X138492Y1717592D03*
X132895Y1737108D03*
X158492Y28406D03*
X151405D03*
X158492Y40020D03*
X151405D03*
X147901Y188852D03*
X159125Y448664D03*
X152171Y490615D03*
X149472Y502810D03*
X149486Y498810D03*
X149518Y522810D03*
X159898Y1360790D03*
X152895Y1737108D03*
X172665Y28406D03*
X165579D03*
X172665Y40020D03*
X165579D03*
X175640Y453779D03*
X162398Y1360790D03*
X164898D03*
X172895Y1737108D03*
X166761Y1732967D03*
X179752Y28406D03*
Y40020D03*
X184490Y402203D03*
X191305Y430216D03*
X188221Y454048D03*
X184147Y447078D03*
X192895Y1737108D03*
X202626Y28406D03*
X195539D03*
X202626Y40020D03*
X195539D03*
X199047Y428626D03*
X199139Y422882D03*
X196215Y447565D03*
X194858Y684348D03*
X203441Y1360790D03*
X198041D03*
X200941D03*
X223886Y28406D03*
X216799D03*
X209713D03*
X223886Y40020D03*
X216799D03*
X209713D03*
X223330Y426467D03*
X220843Y430004D03*
X220874Y442079D03*
X224137Y1414345D03*
X224077Y1416975D03*
X224350Y1432032D03*
X212895Y1737108D03*
X230972Y28406D03*
Y40020D03*
X242215Y151788D03*
X253000Y28362D03*
X256500D03*
X249500D03*
X252195Y144320D03*
X257434Y415896D03*
X252895Y1737108D03*
X260000Y28362D03*
X258746Y407842D03*
X260807Y424403D03*
X270322Y740207D03*
X272895Y1737108D03*
X286071Y28406D03*
X278984D03*
X279277Y99183D03*
X289557Y121803D03*
X280687Y140746D03*
X284482Y569548D03*
X286582Y630757D03*
X305025Y144202D03*
X302891Y141811D03*
X292895Y1737108D03*
X324733Y148598D03*
X321119Y1313108D03*
X317119D03*
X313119D03*
X330417Y380482D03*
X336370Y406302D03*
X325119Y1313108D03*
X328915Y1326704D03*
X331515D03*
X332895Y1737108D03*
X344776Y148462D03*
X343411Y363143D03*
Y375364D03*
X343354Y387988D03*
X343720Y400628D03*
X339769Y1299868D03*
X342769D03*
X352895Y1737108D03*
X366675Y158702D03*
X364179Y394596D03*
X371066Y400628D03*
X369690Y431812D03*
X365970Y444662D03*
X361769Y1300008D03*
X364769D03*
X383140Y119822D03*
X375330Y121182D03*
X374981Y131433D03*
X376770Y387272D03*
X385520Y429262D03*
X373190Y438342D03*
X384510Y438662D03*
X385730Y460922D03*
X382860Y471122D03*
X383239Y1286578D03*
X378069Y1286568D03*
X375069D03*
X386239Y1286578D03*
X372895Y1737108D03*
X403700Y402422D03*
X390892Y406863D03*
X403260Y439352D03*
X391150Y445302D03*
X396570Y472602D03*
X391360Y495712D03*
X402780Y499372D03*
X394860Y518812D03*
X403200Y572622D03*
X396139Y1286708D03*
X399139D03*
X400926Y1402207D03*
X391249Y1401048D03*
X396921Y1549810D03*
X396946Y1560810D03*
X419012Y368762D03*
X418602Y394722D03*
X417010Y439352D03*
X415130Y480202D03*
X410532Y1153341D03*
X407948Y1153370D03*
Y1161570D03*
X410532Y1161541D03*
X407948Y1169597D03*
X410532D03*
X429050Y117491D03*
X430980Y132672D03*
X432006Y363644D03*
X431596Y389604D03*
X424980Y439462D03*
X427790Y500862D03*
X427880Y506442D03*
X428510Y515842D03*
X436822Y1161570D03*
Y1153370D03*
X431722D03*
Y1161570D03*
X434272Y1153370D03*
Y1161570D03*
X436822Y1170070D03*
X431722D03*
X434272D03*
X430999Y1286758D03*
X423229D03*
X426229D03*
X433999D03*
X436920Y1541562D03*
X422566Y1550046D03*
X432996Y1558322D03*
X436840Y1632682D03*
X436880Y1622442D03*
X432895Y1737108D03*
X447100Y1622562D03*
X447020Y1632632D03*
X452895Y1737108D03*
X465236Y293823D03*
X467736Y312938D03*
X455326Y520389D03*
X457196Y1161570D03*
X459696D03*
X462196D03*
X459696Y1153370D03*
X457196D03*
X462196D03*
X459696Y1170070D03*
X462196D03*
X457196D03*
X460049Y1286978D03*
X463049D03*
X469019Y1286718D03*
X465749Y1401238D03*
X455602Y1412334D03*
X473870Y506622D03*
X474220Y572782D03*
X471940Y597532D03*
X483030Y1153370D03*
Y1161570D03*
Y1170070D03*
X474509Y1286848D03*
X481509D03*
X477509D03*
X484509D03*
X475285Y1395402D03*
X477835Y1673462D03*
Y1685462D03*
X472895Y1737108D03*
X498636Y293123D03*
X501136Y312238D03*
X486861Y309398D03*
X490759Y1291978D03*
X495309Y1300058D03*
X498309D03*
X492895Y1737108D03*
X517914Y42257D03*
X517902Y49194D03*
X510815D03*
X517989Y1300108D03*
X514989D03*
X508881Y1404880D03*
X506181D03*
X503559Y1405025D03*
X508775Y1409889D03*
X508828Y1407385D03*
X508802Y1412420D03*
X506075Y1409889D03*
X506128Y1407385D03*
X503572Y1407539D03*
Y1415039D03*
Y1412539D03*
X506102Y1412420D03*
X503572Y1410039D03*
X512895Y1737108D03*
X525000Y42257D03*
X524988Y49194D03*
X532533Y299500D03*
X529533D03*
X526941Y447802D03*
X521561Y550819D03*
X526280Y569122D03*
X520710Y592552D03*
X532895Y1737108D03*
X549610Y120682D03*
X535290Y572932D03*
X543450Y590262D03*
X562780Y32842D03*
X564430Y45132D03*
X565849Y1346968D03*
X552895Y1737108D03*
X578620Y45112D03*
X573849Y1346968D03*
X569849D03*
X572895Y1737108D03*
X596840Y45152D03*
X593925Y49193D03*
X590350Y294402D03*
X607890Y34389D03*
X615420Y42342D03*
X605060Y42402D03*
X615185Y49193D03*
X611310Y266272D03*
X612895Y1737108D03*
X621740Y265952D03*
X632895Y1737108D03*
X661681Y49193D03*
X654595D03*
X652895Y1737108D03*
X675854Y49193D03*
X668768D03*
X673517Y1360815D03*
X676017D03*
X678517D03*
X671112Y1639962D03*
X672895Y1737108D03*
X697122Y1632667D03*
X683592Y1634844D03*
X697197Y1644667D03*
X712433Y103308D03*
X712060Y1360815D03*
X722580Y49182D03*
X724133Y141288D03*
X713820Y488762D03*
Y484662D03*
X714560Y1360815D03*
X717060D03*
X744800Y1664840D03*
X732895Y1737108D03*
X762198Y129684D03*
Y126684D03*
X758110Y172636D03*
X752895Y1737108D03*
X777283Y320892D03*
X772208Y1731911D03*
X792208D03*
X810781Y372615D03*
X821164Y372312D03*
X812208Y1731911D03*
X836502Y161553D03*
X837975Y210064D03*
X832208Y1731911D03*
X856776Y129268D03*
X846846Y127064D03*
X851895Y160262D03*
X849710Y212062D03*
X845220Y216532D03*
X854706Y229878D03*
X852206D03*
X856842Y410760D03*
X852208Y1731911D03*
X874295Y163862D03*
X863488Y176332D03*
X872208Y1731911D03*
X886280Y174085D03*
X887671Y487831D03*
Y494767D03*
X878931Y509051D03*
X878941Y503813D03*
X892208Y1731911D03*
X899625Y473856D03*
X893321Y480293D03*
X893311Y485531D03*
X893572Y503050D03*
Y496114D03*
X920246Y184138D03*
X914550Y239924D03*
X923403Y983327D03*
X923322Y990227D03*
X921880Y1525110D03*
X924380D03*
X921880Y1527610D03*
X924380D03*
X912208Y1731911D03*
X935496Y195925D03*
Y203012D03*
Y210098D03*
Y217185D03*
Y224272D03*
Y231358D03*
X940596Y498648D03*
X939097Y527257D03*
X939282Y534020D03*
X930233Y983298D03*
X930274Y990237D03*
X939380Y1525110D03*
X926880D03*
X929380D03*
X931880D03*
X934380D03*
X936880D03*
X926880Y1527610D03*
X929380D03*
X931880D03*
X934380D03*
X936880D03*
X939380D03*
X932208Y1731911D03*
X947190Y527330D03*
X952208Y1731911D03*
X972208D03*
X989910Y-27961D03*
X989925Y-25446D03*
X983632Y-26655D03*
X989925Y-21572D03*
X983632Y-16626D03*
X989910Y-17932D03*
X989925Y-15417D03*
Y-11543D03*
X989910Y-7903D03*
X989925Y-5388D03*
X983632Y-6597D03*
X989925Y4641D03*
X989910Y2126D03*
X983632Y3432D03*
X989925Y14670D03*
X989910Y12155D03*
X989925Y8515D03*
X983632Y13461D03*
X989925Y19044D03*
X983632Y23990D03*
X987259Y276094D03*
X998500Y269862D03*
X1002500D03*
X992208Y1731911D03*
X1014500Y269862D03*
X1018000D03*
X1006500D03*
X1010500D03*
X1021419Y305704D03*
X1012208Y1731911D03*
X1032208D03*
X1053028Y246518D03*
X1053428Y261118D03*
X1052208Y1731911D03*
X1058028Y246518D03*
X1055528D03*
X1068093Y265503D03*
X1058428Y261118D03*
X1055928D03*
X1067618Y273800D03*
X1070718Y273700D03*
X1067718Y285600D03*
X1070618D03*
X1072208Y1731911D03*
X1102561Y78461D03*
X1117574Y1448604D03*
X1111866Y1737108D03*
X1135709Y1397119D03*
X1133209D03*
X1127008Y1524203D03*
X1135748Y1524187D03*
X1131866Y1737108D03*
X1138209Y1397119D03*
X1170337Y607327D03*
X1171752Y1397119D03*
X1176752D03*
X1174252D03*
X1179922Y1524203D03*
X1201110Y1681767D03*
X1191866Y1737108D03*
X1211866D03*
X1231866D03*
X1253586Y1334649D03*
X1257586D03*
X1251866Y1737108D03*
X1276745Y125850D03*
X1275807Y132922D03*
X1281600Y137962D03*
X1282568Y212722D03*
X1272707Y1334865D03*
X1271866Y1737108D03*
X1293024Y-36695D03*
Y-26666D03*
Y-16637D03*
Y-6608D03*
Y3421D03*
Y13450D03*
Y23979D03*
X1291280Y58262D03*
X1293860Y58312D03*
X1284930Y124922D03*
X1285793Y141562D03*
X1288258Y145501D03*
X1283781Y149115D03*
Y155788D03*
X1283425Y179272D03*
X1283397Y202085D03*
X1295150Y1323217D03*
X1298150D03*
X1291010Y1323307D03*
X1288010D03*
X1291866Y1737108D03*
X1299317Y-35486D03*
Y-31612D03*
X1299302Y-38001D03*
Y-27972D03*
X1299317Y-25457D03*
Y-21583D03*
X1299302Y-17943D03*
X1299317Y-15428D03*
Y-11554D03*
X1299302Y-7914D03*
X1299317Y-5399D03*
Y4630D03*
X1299302Y2115D03*
X1299317Y-1525D03*
Y14659D03*
X1299302Y12144D03*
X1299317Y8504D03*
Y19033D03*
X1304066Y1323578D03*
X1307656Y1326704D03*
X1305056D03*
X1311866Y1737108D03*
X1323958Y146227D03*
X1333811Y235348D03*
X1338652Y536654D03*
Y543590D03*
X1337663Y1301001D03*
X1340663D03*
X1331866Y1737108D03*
X1349704Y145385D03*
X1357888Y145893D03*
X1361111Y236448D03*
X1353982Y1287048D03*
X1362382D03*
X1359382D03*
X1350982D03*
X1351866Y1737108D03*
X1366868Y147341D03*
X1369593Y147462D03*
X1369916Y154132D03*
X1379969Y176330D03*
X1370586Y176366D03*
X1370405Y186938D03*
X1369479Y208384D03*
X1370636Y227292D03*
X1369410Y224504D03*
X1375463Y1287048D03*
X1372463D03*
X1376666Y1402778D03*
X1376686Y1399758D03*
X1371866Y1737108D03*
X1384173Y1161549D03*
X1384089Y1153369D03*
X1386673Y1161520D03*
Y1153340D03*
X1384173Y1169599D03*
X1386673Y1169570D03*
X1391866Y1737108D03*
X1407613Y177159D03*
X1398770D03*
X1402258Y184263D03*
X1411101D03*
X1407913Y1161569D03*
X1410413Y1153369D03*
X1407913D03*
X1410613Y1161569D03*
X1407913Y1170069D03*
X1410613D03*
X1410819Y1287198D03*
X1407819D03*
X1399419D03*
X1402419D03*
X1411866Y1737108D03*
X1420222Y184263D03*
X1429250Y1623391D03*
X1419270Y1631000D03*
X1429382Y184263D03*
X1430000Y220018D03*
X1435387Y1161569D03*
X1435837Y1153369D03*
X1432887Y1161569D03*
X1433337Y1153369D03*
X1435387Y1170069D03*
X1432887D03*
X1437258Y1287198D03*
X1445106Y1287158D03*
X1440258Y1287198D03*
X1431829Y1412370D03*
X1443325Y1410068D03*
X1431717Y1424125D03*
X1441800Y1620300D03*
Y1632900D03*
X1431866Y1737108D03*
X1458911Y1161569D03*
Y1170069D03*
X1453366Y1287198D03*
X1458766D03*
X1461766D03*
X1450366D03*
X1474180Y1300407D03*
X1471180D03*
X1491661Y-27972D03*
X1491676Y-25457D03*
X1485383Y-26666D03*
X1491661Y-38001D03*
X1491676Y-35486D03*
Y-31612D03*
X1485383Y-36695D03*
X1491661Y-17943D03*
X1491676Y-15428D03*
Y-11554D03*
X1485383Y-16637D03*
X1491676Y-21583D03*
X1485383Y3421D03*
X1491661Y2115D03*
X1491676Y4630D03*
X1491661Y-7914D03*
X1491676Y-5399D03*
Y-1525D03*
X1485383Y-6608D03*
X1491676Y14659D03*
X1491661Y12144D03*
X1485383Y13450D03*
X1491676Y8504D03*
Y19033D03*
X1485383Y23979D03*
X1487058Y281456D03*
X1484958Y289656D03*
X1487658D03*
X1484758Y312356D03*
X1487458D03*
X1484858Y305956D03*
X1487558D03*
X1491840Y1300447D03*
X1479658Y1405397D03*
X1485301Y1409442D03*
X1485274Y1406911D03*
X1485380Y1412202D03*
X1479671Y1410411D03*
Y1412911D03*
Y1407911D03*
X1482201Y1409442D03*
X1482174Y1406911D03*
X1482280Y1412202D03*
X1491866Y1737108D03*
X1504602Y312867D03*
X1494840Y1300447D03*
X1511866Y1737108D03*
X1540937Y576522D03*
X1536527Y589012D03*
X1531866Y1737108D03*
X1547429Y28406D03*
X1554515D03*
Y40020D03*
X1547429D03*
X1547312Y579080D03*
X1551866Y1737108D03*
X1561602Y28406D03*
X1568688D03*
Y40020D03*
X1561602D03*
X1575775Y28406D03*
X1582862D03*
X1589948D03*
Y40020D03*
X1582862D03*
X1575775D03*
X1591866Y1737108D03*
X1597035Y28406D03*
X1604122D03*
Y40020D03*
X1597035D03*
X1623881Y117627D03*
X1619980Y615201D03*
X1614116Y1411169D03*
X1611866Y1737108D03*
X1625814Y28406D03*
X1632901D03*
X1639988D03*
X1625814Y40020D03*
X1632901D03*
X1639988D03*
X1637183Y1394411D03*
X1639683D03*
X1634683D03*
X1631866Y1737108D03*
X1654161Y28406D03*
X1647074D03*
Y40020D03*
X1654161D03*
X1652113Y527325D03*
X1652138Y524071D03*
X1651931Y540071D03*
Y536071D03*
X1649291Y556057D03*
X1649149Y607022D03*
X1653929Y604546D03*
X1649139Y604576D03*
X1653736Y607033D03*
X1649117Y602139D03*
X1653930Y602099D03*
X1651866Y1737108D03*
X1669948Y28406D03*
Y40020D03*
X1663376Y515531D03*
X1667376D03*
X1664997Y604762D03*
X1659458Y637149D03*
X1658085Y639511D03*
X1659458Y671149D03*
X1658085Y673511D03*
X1659458Y705149D03*
X1658085Y707511D03*
X1673226Y1394411D03*
X1671866Y1737108D03*
X1677035Y28406D03*
X1684122D03*
X1677035Y40020D03*
X1684122D03*
X1681612Y499290D03*
X1675926Y1394411D03*
X1678426D03*
X1691208Y28406D03*
X1698295D03*
X1705381D03*
X1697824Y39974D03*
X1691208Y40020D03*
X1693987Y230174D03*
Y233174D03*
X1703487Y232174D03*
X1699265Y525507D03*
X1699291Y537507D03*
X1699251Y529507D03*
X1699297Y549507D03*
X1705723Y1583821D03*
X1691866Y1737108D03*
X1711866D03*
X1738200Y193862D03*
X1731866Y1737108D03*
X1753388Y28360D03*
X1754398Y100307D03*
X1752200Y197762D03*
X1748500Y193862D03*
X1745500D03*
X1741200D03*
X1740831Y489362D03*
X1740886Y493960D03*
X1751866Y1737108D03*
X1760475Y28360D03*
X1764678Y122927D03*
X1766880Y234842D03*
Y231842D03*
X1758500Y231822D03*
Y234822D03*
X1755378Y233528D03*
X1782000Y128455D03*
X1771915Y128393D03*
X1782000Y125955D03*
Y123455D03*
X1771915Y125893D03*
Y123393D03*
X1783800Y231762D03*
Y234762D03*
X1775140Y234792D03*
Y231792D03*
X1779226Y275604D03*
X1783563Y273471D03*
X1786089D03*
X1771866Y1737108D03*
X1797663Y269571D03*
X1800189D03*
X1790563Y273471D03*
X1793089D03*
X1802763Y308671D03*
X1795763D03*
X1798289D03*
X1788763D03*
X1791289D03*
X1814349Y269634D03*
X1811823D03*
X1807249D03*
X1804723D03*
X1812349Y308734D03*
X1809823D03*
X1805289Y308671D03*
X1828777Y156520D03*
X1841257Y151402D03*
G54D19*
X20188Y1599396D03*
G54D66*
X1156378Y133866D03*
G54D70*
X1850331Y311946D03*
G54D26*
X60303Y20354D03*
X312921Y24291D03*
X505185Y41142D03*
X757803Y45079D03*
X922441Y237697D03*
X929331Y160413D03*
X1534712Y20354D03*
X1787330Y24291D03*
G54D41*
X337778Y854584D03*
X335924Y857789D03*
X334079Y880219D03*
X332228Y877014D03*
X335928D03*
X334078Y893036D03*
X335928Y896240D03*
X332229Y902649D03*
X332228Y915466D03*
X335928D03*
X332229Y921875D03*
Y941100D03*
X332228Y934692D03*
X335928D03*
X334079Y957122D03*
X335928Y953917D03*
X332228D03*
X332229Y973143D03*
X334079Y976347D03*
X338210Y996480D03*
X332661Y1006093D03*
X338211Y1002888D03*
X332661Y1025318D03*
Y1018910D03*
X338211Y1015705D03*
Y1022114D03*
X332661Y1044544D03*
X338211Y1041340D03*
X334511D03*
X338211Y1060565D03*
X336360Y1082995D03*
X338211Y1111834D03*
Y1105426D03*
Y1124651D03*
X336361Y1115039D03*
Y1127856D03*
X347028Y844971D03*
X345178Y848176D03*
X350727Y844971D03*
X347027Y851380D03*
X343327D03*
X354429D03*
X341478Y854584D03*
X339628Y857789D03*
X347029Y864197D03*
Y857789D03*
X348878Y854584D03*
X345179Y860993D03*
X343327Y857789D03*
X354429Y864197D03*
X350729D03*
X341479Y867401D03*
X348879D03*
X352579D03*
X354429Y877014D03*
X339629D03*
X341479Y873810D03*
X345179Y880219D03*
Y873810D03*
X343329Y877014D03*
X352579Y880219D03*
X350729Y877014D03*
X339629Y883423D03*
X347029D03*
X350729D03*
X352578Y899445D03*
X339629Y896240D03*
Y889832D03*
X348879Y886627D03*
X345179Y893036D03*
X343328Y896240D03*
X352578Y893036D03*
Y886627D03*
X345179Y899445D03*
X348878Y905853D03*
X352578D03*
X341479Y912262D03*
X341478Y905853D03*
X347029Y909057D03*
Y902649D03*
X345179Y912262D03*
X352578D03*
X339629Y915466D03*
X343329D03*
X348878Y925079D03*
X352578D03*
Y918670D03*
X341478Y925079D03*
X347029Y928283D03*
Y921875D03*
X345179Y918670D03*
X341479Y931488D03*
X345179D03*
X352578D03*
X341478Y944304D03*
X352578D03*
X347029Y941100D03*
X348878Y944304D03*
X347029Y947509D03*
X352578Y937896D03*
X339629Y934692D03*
X345179Y937896D03*
X343328Y934692D03*
X348878Y963530D03*
X347029Y960326D03*
X343328D03*
X343329Y966735D03*
X339629D03*
Y953917D03*
X343328D03*
X345179Y957122D03*
X352578D03*
X347029Y966735D03*
X352578Y963530D03*
X341479Y950713D03*
X345179D03*
X352578D03*
X354428Y973143D03*
X339629D03*
X345179Y976347D03*
Y969939D03*
X350729Y973143D03*
X347029Y979552D03*
X352579Y976347D03*
X352578Y969939D03*
X348878Y982756D03*
X352578D03*
X339629Y979552D03*
X343329Y973143D03*
X341911Y1009297D03*
Y1002888D03*
X347461Y999684D03*
X345611Y1009297D03*
X343761Y1006093D03*
X345611Y1002888D03*
X351162Y1006093D03*
X354861D03*
X353011Y1009297D03*
Y1002888D03*
X347461Y1012501D03*
X353011Y1028523D03*
Y1015705D03*
X341911Y1022114D03*
Y1015705D03*
X349311D03*
X347461Y1018910D03*
X345611Y1028523D03*
X343761Y1018910D03*
X345611Y1022114D03*
Y1015705D03*
X353011Y1022114D03*
X343761Y1031727D03*
X347461D03*
X353011Y1034931D03*
Y1047749D03*
X341911Y1041340D03*
X343761Y1038136D03*
X349311Y1034931D03*
X347461Y1038136D03*
X345611Y1041340D03*
X343761Y1044544D03*
X353011Y1041340D03*
X345611Y1047749D03*
X349311Y1054157D03*
X353011Y1060565D03*
Y1054157D03*
X343761Y1057361D03*
Y1050952D03*
X347461D03*
Y1057361D03*
X345611Y1060565D03*
X343761Y1063770D03*
X353011Y1073383D03*
X343761Y1076587D03*
Y1070178D03*
X340062Y1076587D03*
X347461D03*
Y1070178D03*
X349312Y1073383D03*
X345611Y1066974D03*
X353011D03*
X345611Y1079791D03*
X341911D03*
X353011D03*
Y1086200D03*
X349310Y1092609D03*
X347461Y1089404D03*
X345610Y1086200D03*
X343760Y1082995D03*
X340060D03*
X353011Y1092608D03*
X340061Y1095813D03*
X347461Y1108630D03*
X354861D03*
X353011Y1099017D03*
X340061Y1108630D03*
Y1102221D03*
X349311Y1099017D03*
X347461Y1102221D03*
X343761D03*
X340061Y1115039D03*
X349311Y1124651D03*
X349312Y1118243D03*
X345611D03*
X343761Y1115039D03*
X341911Y1124651D03*
X354861Y1115039D03*
X351161Y1121447D03*
Y1115039D03*
X345611Y1137469D03*
Y1131060D03*
X349311D03*
X343761Y1134264D03*
X353011Y1137469D03*
Y1131060D03*
X361829Y851380D03*
X358129D03*
X365529Y864197D03*
X361829D03*
X359979Y854584D03*
X358129Y864197D03*
X369229D03*
X367379Y854584D03*
X359979Y867401D03*
X367379D03*
X365529Y877014D03*
X361829D03*
X358129D03*
X369229D03*
X367379Y880219D03*
X356278Y886627D03*
X365529Y896240D03*
Y889832D03*
X361828Y896240D03*
X361829Y889832D03*
X359979Y893036D03*
X358128Y889832D03*
X369229Y896240D03*
Y889832D03*
X356278Y905853D03*
X365529Y909057D03*
Y902649D03*
X359978Y912262D03*
X358128Y909057D03*
X358129Y902649D03*
X371079Y912262D03*
X365529Y915466D03*
X361828D03*
X369229D03*
X356279Y925079D03*
X365529Y928283D03*
Y921875D03*
X358128Y928283D03*
X358129Y921875D03*
X371078Y918670D03*
X359978Y931488D03*
X371079D03*
X358128Y947509D03*
X358129Y941100D03*
X356279Y944304D03*
X365529Y947509D03*
Y934691D03*
X361828D03*
X369229D03*
X356279Y963530D03*
X358129Y960326D03*
X359979Y957122D03*
X358128Y966735D03*
X361829Y953917D03*
X359978Y950713D03*
X371078Y957122D03*
X371079Y950713D03*
X365529Y953917D03*
X367378Y963530D03*
X363679D03*
X365529Y960326D03*
X365528Y966735D03*
X369229Y953917D03*
X359979Y976347D03*
X358129Y979552D03*
X359978Y969939D03*
X361828Y973143D03*
X356279Y982756D03*
X371078Y976347D03*
X371079Y969939D03*
X369229Y973143D03*
X365529Y979552D03*
Y973143D03*
X365962Y999684D03*
Y1006093D03*
X362261D03*
X360411Y1009297D03*
X360412Y1002888D03*
X358562Y999684D03*
X371512Y1009297D03*
X365961Y1012501D03*
X358561D03*
X356712Y1015705D03*
X365962Y1025318D03*
Y1018910D03*
X364112Y1015705D03*
X360411Y1028523D03*
X362261Y1025318D03*
X360412Y1022114D03*
X358562Y1018910D03*
X369662Y1025318D03*
X367811Y1015705D03*
X371511Y1028523D03*
Y1022114D03*
X365962Y1031727D03*
X358561D03*
X356712Y1034931D03*
X365962Y1044544D03*
Y1038136D03*
X362261Y1044544D03*
X360412Y1041340D03*
X358562Y1038136D03*
X369662Y1044544D03*
X371511Y1041340D03*
X360411Y1047749D03*
X371511D03*
X356712Y1054157D03*
X365962Y1057361D03*
Y1050952D03*
X360412Y1060565D03*
X358562Y1057361D03*
X358561Y1050952D03*
X371511Y1060565D03*
X365962Y1063770D03*
X362261D03*
X369662D03*
X356712Y1073383D03*
X365962Y1070178D03*
X360411Y1066974D03*
X358561Y1070178D03*
X358562Y1076587D03*
X371512Y1066974D03*
X360412Y1079791D03*
X371511D03*
X365962Y1089404D03*
Y1082995D03*
X362261D03*
X360411Y1086200D03*
X358561Y1089404D03*
X356712Y1092608D03*
X369662Y1082995D03*
X371512Y1086200D03*
X365962Y1095813D03*
X358561D03*
X365962Y1102221D03*
X362262D03*
X360411Y1099017D03*
X356711Y1105426D03*
Y1099017D03*
X371512Y1105426D03*
Y1099017D03*
X364112Y1111834D03*
X356712D03*
X371512D03*
X364111Y1118243D03*
X362261Y1115039D03*
X360411Y1118243D03*
X356711D03*
X367811D03*
X371511D03*
X365962Y1127856D03*
X358561D03*
X365961Y1140973D03*
X364112Y1131060D03*
X360412D03*
X358561Y1140973D03*
X356712Y1131060D03*
X367811D03*
X371511D03*
X382179Y854584D03*
X380329Y864197D03*
X376629D03*
X374779Y854584D03*
X372929Y864197D03*
X384029D03*
X387729D03*
X382179Y867401D03*
X374779D03*
X382179Y880219D03*
X380329Y877014D03*
X376629D03*
X374779Y880219D03*
X372929Y877014D03*
X384029D03*
X387729D03*
X380329Y889832D03*
X378479Y893036D03*
X376629Y889832D03*
X372929D03*
X384029D03*
X387729Y896240D03*
Y889832D03*
X378478Y899445D03*
X385879D03*
X382179Y905853D03*
X378478Y912262D03*
Y905853D03*
X374778D03*
X372929Y909057D03*
X372928Y902649D03*
X385878Y912262D03*
X384028Y909057D03*
X384029Y902649D03*
X387728Y915466D03*
X382179Y925079D03*
X378478D03*
Y918670D03*
X374778Y925079D03*
X372929Y928283D03*
X372928Y921875D03*
X385879Y918670D03*
X384028Y928283D03*
X384029Y921875D03*
X385878Y931488D03*
X384029Y941100D03*
X384028Y947509D03*
X374778Y944304D03*
X372929Y947509D03*
X372928Y941100D03*
X382179Y944304D03*
X378478D03*
Y937896D03*
X385879D03*
X387728Y934691D03*
X387729Y953917D03*
X372928Y960326D03*
X374778Y963530D03*
X372929Y966735D03*
X382179Y963530D03*
X378478D03*
Y957122D03*
X384029Y960326D03*
X385879Y957122D03*
X384028Y966735D03*
X385878Y950713D03*
X378478D03*
X387728Y973143D03*
X376629D03*
X380328D03*
X378479Y976347D03*
X378478Y969939D03*
X385879Y976347D03*
X384029Y979552D03*
X385878Y969939D03*
X374778Y982756D03*
X382179D03*
X378478D03*
X372928Y979552D03*
X375210Y996480D03*
X373361Y999684D03*
X378911Y1009297D03*
Y1002888D03*
X386311Y1009297D03*
X386312Y1002888D03*
X384462Y999684D03*
X373362Y1012501D03*
X384461D03*
X382612Y1015705D03*
X378911Y1028523D03*
Y1022114D03*
Y1015705D03*
X375211D03*
X373361Y1018910D03*
X386311Y1028523D03*
X386312Y1022114D03*
X384462Y1018910D03*
X373362Y1031727D03*
X384461D03*
X382612Y1034931D03*
X378911Y1041340D03*
Y1034931D03*
X375211D03*
X373361Y1038136D03*
X386312Y1041340D03*
X384462Y1038136D03*
X378911Y1047749D03*
X386311D03*
X382612Y1054157D03*
X378911D03*
X375211D03*
X373361Y1057361D03*
X373362Y1050952D03*
X386312Y1060565D03*
X384462Y1057361D03*
X384461Y1050952D03*
X382612Y1073383D03*
X378911D03*
Y1066974D03*
X375211Y1073383D03*
X373361Y1076587D03*
X373362Y1070178D03*
X386311Y1066974D03*
X384462Y1076587D03*
X384461Y1070178D03*
X378911Y1079791D03*
X386311D03*
X382611Y1092608D03*
X378911D03*
Y1086200D03*
X375211Y1092608D03*
X373362Y1089404D03*
X386311Y1086200D03*
X384461Y1089404D03*
X373362Y1095813D03*
X384462D03*
X380762Y1108630D03*
X378911Y1099017D03*
X377062Y1102221D03*
X373361Y1108630D03*
Y1102221D03*
X386312Y1099017D03*
X384462Y1102221D03*
X382611Y1118243D03*
X378911D03*
X377061Y1115039D03*
X375211Y1118243D03*
X373361Y1115039D03*
X386311Y1118243D03*
X384461Y1115039D03*
X380761Y1127856D03*
X373361D03*
X382611Y1131060D03*
X380761Y1140973D03*
X378911Y1131060D03*
X375211D03*
X373361Y1140973D03*
X386311Y1131060D03*
X396979Y841467D03*
X398829Y851380D03*
X395129D03*
X391429D03*
X402529D03*
X398829Y864197D03*
X396979Y854584D03*
X395129Y864197D03*
X391429D03*
X389579Y854584D03*
X402529Y864197D03*
X396979Y867401D03*
X389579D03*
X398829Y877014D03*
X396979Y880219D03*
X395129Y877014D03*
X391429D03*
X389579Y880219D03*
X402529Y877014D03*
X398829Y889832D03*
X395129Y896240D03*
Y889832D03*
X391428Y896240D03*
X391429Y889832D03*
X389579Y893036D03*
X402529Y889832D03*
X398829Y909057D03*
X398828Y902649D03*
X396979Y912262D03*
X391429Y909057D03*
Y902649D03*
X395129Y915466D03*
X391429D03*
X398829Y928283D03*
X398828Y921875D03*
X396978Y918670D03*
X391429Y928283D03*
Y921875D03*
X400678Y925079D03*
X396979Y931488D03*
X398828Y941100D03*
X395129Y934691D03*
X391429Y941100D03*
Y934691D03*
X400678Y937896D03*
X398829Y947509D03*
X391429D03*
X398828Y960326D03*
X396978Y957122D03*
X396979Y950713D03*
X395129Y953917D03*
X391429Y960326D03*
Y953917D03*
X400678Y957122D03*
X398829Y966735D03*
X391429D03*
X400678Y963530D03*
X398828Y979552D03*
X396978Y976347D03*
X396979Y969939D03*
X395129Y973143D03*
X391429Y979552D03*
Y973143D03*
X400678Y982756D03*
Y969939D03*
X397412Y1009297D03*
X397411Y1002888D03*
X395562Y1006093D03*
X391862D03*
Y999684D03*
X388161Y1006093D03*
X401111Y1002888D03*
X399262Y1012501D03*
X391861D03*
X399261Y1018910D03*
X397411Y1028523D03*
Y1022114D03*
X395562Y1025318D03*
X393711Y1015705D03*
X391862Y1025318D03*
Y1018910D03*
X390012Y1015705D03*
X388161Y1025318D03*
X399262Y1031727D03*
X391862D03*
X399261Y1038136D03*
X397411Y1041340D03*
X395562Y1044544D03*
X391862D03*
Y1038136D03*
X388161Y1044544D03*
X397411Y1047749D03*
X399261Y1057361D03*
X399262Y1050952D03*
X397411Y1060565D03*
X391862Y1057361D03*
Y1050952D03*
X395562Y1063770D03*
X391862D03*
X388161D03*
X399261Y1076587D03*
X399262Y1070178D03*
X397412Y1066974D03*
X391862Y1076587D03*
Y1070178D03*
X401111Y1073383D03*
X397411Y1079791D03*
X401111D03*
X399262Y1089404D03*
X397412Y1086200D03*
X395562Y1082995D03*
X391862Y1089404D03*
Y1082995D03*
X388161D03*
X401112Y1092608D03*
X401111Y1086200D03*
X399261Y1095813D03*
X391862D03*
X402962D03*
X399262Y1102221D03*
X397412Y1099017D03*
X395562Y1102221D03*
X390011Y1105426D03*
X388162Y1108630D03*
Y1102221D03*
X401111Y1105426D03*
X397411Y1111834D03*
X390011D03*
X397411Y1118243D03*
X395561Y1115039D03*
X393711Y1118243D03*
X390011D03*
X388161Y1115039D03*
X401111Y1118243D03*
X395561Y1127856D03*
X388161D03*
X402961D03*
X397411Y1131060D03*
X395561Y1140973D03*
X393711Y1131060D03*
X390011D03*
X388161Y1140973D03*
X402961D03*
X401111Y1131060D03*
X419179Y841467D03*
X404379D03*
X411779D03*
X413629Y851380D03*
X409929D03*
X406229D03*
X417329D03*
X404379Y854584D03*
X413629Y864197D03*
X411779Y854584D03*
X409929Y864197D03*
X406229D03*
X419179Y854584D03*
X417329Y864197D03*
X404379Y867401D03*
X411779D03*
X419179D03*
X404379Y880219D03*
X413629Y877014D03*
X411779Y880219D03*
X409929Y877014D03*
Y870606D03*
X406229Y877014D03*
X419179Y880219D03*
X417329Y877014D03*
X413629Y889832D03*
X411779Y893036D03*
X409929Y889832D03*
X408079Y893036D03*
X406229Y889832D03*
X419179Y893036D03*
X417329Y889832D03*
X413629Y902649D03*
X409929Y909057D03*
Y902649D03*
X404378Y912262D03*
Y905853D03*
X419178Y912262D03*
X419179Y905853D03*
X417329Y902649D03*
X409929Y915466D03*
Y921875D03*
X404378Y918670D03*
X418229Y926896D03*
X419178Y918670D03*
X405048Y930812D03*
X405145Y946239D03*
Y948539D03*
X414093Y942098D03*
X405048Y938046D03*
Y935746D03*
X416393Y942098D03*
X418693D03*
X405122Y965896D03*
Y963596D03*
X414365Y971140D03*
X416755D03*
X404861Y981269D03*
Y978969D03*
Y986421D03*
X405101Y992971D03*
Y995271D03*
X404861Y988721D03*
X405227Y1007156D03*
X405231Y1004848D03*
X417575Y1000060D03*
X415185D03*
X404986Y1022427D03*
X404998Y1026821D03*
X408325Y1031971D03*
Y1034271D03*
X408511Y1041340D03*
X417762Y1044544D03*
X412211Y1047749D03*
X404811D03*
X415911Y1060565D03*
Y1054157D03*
X412211Y1060565D03*
X410361Y1050952D03*
X408511Y1054157D03*
X404811Y1060565D03*
X417761Y1050952D03*
X415911Y1066974D03*
X410362Y1076587D03*
Y1070178D03*
X406661Y1076587D03*
X404811Y1066974D03*
X419611Y1073383D03*
X412211Y1079791D03*
X404811D03*
X415911Y1092608D03*
X415912Y1086200D03*
X412211Y1092608D03*
X408511Y1086200D03*
X417761Y1089404D03*
Y1082995D03*
X410362Y1095813D03*
X406662D03*
X415912Y1099017D03*
X414062Y1108630D03*
X412211Y1099017D03*
X410362Y1102221D03*
X406661Y1108630D03*
Y1102221D03*
X404812Y1105426D03*
X417762Y1102221D03*
X404812Y1111834D03*
X415911Y1118243D03*
X414061Y1121447D03*
X412211Y1124651D03*
Y1118243D03*
X410361Y1115039D03*
X408511Y1118243D03*
X406661Y1115039D03*
X404811Y1118243D03*
X417761Y1115039D03*
X410361Y1127856D03*
X414062Y1134264D03*
X412212Y1131060D03*
X410361Y1140973D03*
X408511Y1131060D03*
X404811D03*
X432128Y844671D03*
X426579Y841467D03*
X432129Y851380D03*
X428429D03*
X424729D03*
X421029D03*
X432129Y864197D03*
X428429D03*
X426579Y854584D03*
X424729Y864197D03*
X421029D03*
X433979Y854584D03*
X426579Y867401D03*
X433979D03*
X432129Y877014D03*
X428429D03*
X426579Y880219D03*
X424729Y877014D03*
X421029D03*
X433979Y880219D03*
X432129Y889832D03*
X428429D03*
X426579Y893036D03*
X424729Y889832D03*
X421029D03*
X433979Y893036D03*
X424729Y902649D03*
X432129D03*
X428429Y909057D03*
Y902649D03*
X421029D03*
X428429Y915466D03*
X433980Y925079D03*
Y931487D03*
X426875Y947199D03*
Y949499D03*
X427875Y936470D03*
X426905Y965935D03*
Y963635D03*
Y980336D03*
Y978036D03*
Y994722D03*
Y992422D03*
Y1006875D03*
Y1009175D03*
Y1021963D03*
Y1019663D03*
X428862Y1044544D03*
X430712Y1047749D03*
X423311D03*
X425162Y1057361D03*
X432561Y1050952D03*
X434411Y1060565D03*
Y1054157D03*
X421462Y1063770D03*
X430711Y1073383D03*
X427011D03*
Y1066974D03*
X425162Y1076587D03*
X423311Y1066974D03*
X432561Y1076587D03*
X434411Y1073383D03*
Y1066974D03*
X427012Y1079791D03*
X434411D03*
X428861Y1082995D03*
X425162Y1089404D03*
X421462Y1082995D03*
X432561Y1089404D03*
Y1082995D03*
X434411Y1086200D03*
X428861Y1095813D03*
X421462D03*
X432561D03*
X427011Y1099017D03*
X425161Y1102221D03*
X423311Y1105426D03*
X421462Y1108630D03*
X434411Y1105426D03*
X423311Y1111834D03*
X434411D03*
X423311Y1124651D03*
Y1118243D03*
X421462Y1115039D03*
X434411Y1124651D03*
Y1118243D03*
X423312Y1137469D03*
X423311Y1131060D03*
X434412Y1137769D03*
X434411Y1131060D03*
X452478Y848176D03*
X445078D03*
X441378D03*
X439529Y844671D03*
X446929Y851380D03*
X443228D03*
X439529D03*
X448779Y854584D03*
X446929Y864197D03*
X443229D03*
X441379Y854584D03*
X439529Y864197D03*
X439528Y857789D03*
X437680Y860992D03*
X450629Y864197D03*
X448779Y867401D03*
X441379D03*
X448779Y880219D03*
X446929Y877014D03*
X443229D03*
X441379Y880219D03*
X439529Y877014D03*
X448779Y893036D03*
X446929Y889832D03*
X443229D03*
X441379Y893036D03*
X439529Y896240D03*
Y889832D03*
X437678Y886627D03*
X450629Y889832D03*
X437679Y899445D03*
X446929Y909057D03*
Y902649D03*
X443229D03*
X439528D03*
X437679Y905853D03*
X450629Y902649D03*
X446929Y915466D03*
X446930Y928283D03*
X441379Y925079D03*
Y931487D03*
X446929Y921875D03*
X437678Y918670D03*
X448779Y937897D03*
X447360Y1038136D03*
X452911Y1041340D03*
X451061Y1044544D03*
X449211Y1047749D03*
X447361Y1057361D03*
Y1050952D03*
X452911Y1060565D03*
X447361Y1063770D03*
Y1076587D03*
Y1070178D03*
X449211Y1073383D03*
X452911Y1079791D03*
X449211D03*
X447361Y1082995D03*
X452911Y1092608D03*
X451062Y1089404D03*
X449212Y1086200D03*
X451062Y1095813D03*
X447361Y1108630D03*
Y1102221D03*
X452911Y1099017D03*
X447361Y1121447D03*
Y1115039D03*
Y1127856D03*
Y1134264D03*
X461729Y851380D03*
X458029D03*
X454328D03*
X456179Y841467D03*
X463579D03*
X469129Y851380D03*
X465429D03*
X456179Y854584D03*
X463579D03*
X461729Y864197D03*
X458029D03*
X454329D03*
X469129D03*
X465429D03*
X456179Y867401D03*
X463579D03*
X461729Y877014D03*
X458029D03*
X456179Y880219D03*
X454329Y877014D03*
X463579Y880219D03*
X469129Y877014D03*
X465429D03*
X461729Y889832D03*
X458029D03*
X456179Y893036D03*
X454329Y889832D03*
X463579Y893036D03*
X469129Y896240D03*
Y889832D03*
X465429D03*
X461729Y902649D03*
X458029D03*
X456178Y905853D03*
X454329Y902649D03*
X465429D03*
Y909057D03*
Y915466D03*
X454103Y931359D03*
Y933659D03*
X456178Y918670D03*
X454434Y1022186D03*
Y1019886D03*
X460311Y1041340D03*
X467372Y1036874D03*
X465861Y1044544D03*
X456611Y1047749D03*
X464011D03*
X456611Y1054157D03*
X462162Y1050952D03*
X454761Y1076587D03*
X462162Y1070178D03*
X456612Y1079791D03*
X467711D03*
X458461Y1082995D03*
X456611Y1086200D03*
X460311Y1092608D03*
X464011Y1086200D03*
X467712D03*
Y1092608D03*
X460312Y1105426D03*
X458462Y1102221D03*
X456611Y1099017D03*
X464012Y1105426D03*
Y1099017D03*
X462162Y1108630D03*
X465861D03*
Y1102221D03*
X464012Y1111834D03*
X467711Y1105426D03*
Y1111834D03*
X458462Y1121447D03*
Y1115039D03*
X467712Y1124651D03*
X467711Y1118243D03*
X465862Y1121447D03*
Y1115039D03*
X458462Y1127856D03*
Y1134264D03*
X478379Y841467D03*
X470979D03*
X476529Y851380D03*
X480229D03*
X472829D03*
X483929D03*
X480229Y864197D03*
X478379Y854584D03*
X476529Y864197D03*
X470979Y854584D03*
X472829Y864197D03*
X483929D03*
X478379Y867401D03*
X470979D03*
X480229Y877014D03*
X478379Y880219D03*
X476529Y877014D03*
X472829D03*
X472828Y870606D03*
X470979Y880219D03*
Y873810D03*
X483929Y877014D03*
X480228Y896240D03*
X480229Y889832D03*
X478379Y893036D03*
X470979D03*
X476529Y889832D03*
X472829D03*
X483929D03*
X482078Y899445D03*
X474678Y905853D03*
X483929Y909057D03*
X482079Y912262D03*
X483928Y902649D03*
X476285Y930126D03*
X476528Y921875D03*
X474678Y918670D03*
X483929Y928283D03*
X482078Y918670D03*
X483928Y921875D03*
X482079Y931488D03*
X476285Y934726D03*
X476180Y945355D03*
Y947655D03*
X478378Y944304D03*
X480229Y934691D03*
X483928Y941100D03*
X482079Y944304D03*
X482078Y937896D03*
X483928Y947509D03*
X476285Y962326D03*
Y960026D03*
Y964626D03*
X483928Y960326D03*
X482078Y957122D03*
X482079Y950713D03*
X483929Y966735D03*
X476285Y966926D03*
X476192Y977670D03*
X476335Y980737D03*
X482079Y969939D03*
X483928Y979552D03*
X482078Y976347D03*
X476285Y996826D03*
Y994526D03*
Y989926D03*
Y987626D03*
X476295Y1010500D03*
X476285Y1012926D03*
Y1006026D03*
Y1003726D03*
X484361Y999684D03*
X482512Y1009297D03*
X482511Y1002888D03*
X484362Y1012501D03*
X476275Y1022636D03*
X476285Y1017526D03*
X482511Y1028523D03*
Y1022114D03*
X484361Y1018910D03*
Y1031727D03*
X471282Y1036526D03*
X473507Y1035928D03*
X475111Y1041340D03*
X482511D03*
X482512Y1034931D03*
X484361Y1038136D03*
X471411Y1047749D03*
X482511D03*
X480662Y1050952D03*
X471411Y1054157D03*
X482511Y1060565D03*
X484362Y1050952D03*
Y1070178D03*
X482511Y1079791D03*
X480662Y1082995D03*
X476962Y1089404D03*
X473262Y1082995D03*
X469561Y1089404D03*
X482512Y1086200D03*
X484362Y1089404D03*
X480661Y1095813D03*
X469562D03*
X484362D03*
X480662Y1108630D03*
X478811Y1099017D03*
X473262Y1108630D03*
X476962Y1102221D03*
X475112Y1099017D03*
X471411D03*
X469562Y1102221D03*
X482511Y1105426D03*
Y1111834D03*
X484362Y1108630D03*
X475111Y1111834D03*
X471411D03*
X478811Y1105426D03*
X469562Y1108630D03*
X473262Y1102221D03*
X482511Y1099017D03*
X478811Y1111834D03*
X476962Y1108630D03*
X471411Y1105426D03*
X475111D03*
X484362Y1102221D03*
X480661Y1115039D03*
X478811Y1118243D03*
X476961Y1115039D03*
X475111Y1118243D03*
X471411D03*
X469561Y1115039D03*
X482511Y1118243D03*
X476961Y1127856D03*
X469562D03*
X484361D03*
X484362Y1115039D03*
X473262D03*
X478811Y1131060D03*
X476961Y1140973D03*
X475111Y1131060D03*
X471412Y1137469D03*
Y1131060D03*
X469561Y1140973D03*
X473261Y1134264D03*
X482511Y1131060D03*
X484361Y1140973D03*
X493179Y841467D03*
X485779D03*
X500579D03*
X495029Y851380D03*
X491329D03*
X487629D03*
X498729D03*
X495029Y864197D03*
X493179Y854584D03*
X491329Y864197D03*
X487629D03*
X485779Y854584D03*
X498729Y864197D03*
X500579Y854584D03*
X493179Y867401D03*
X485779D03*
X500579D03*
X495029Y877014D03*
X493179Y880219D03*
X491329Y877014D03*
X487629D03*
X485779Y880219D03*
X500579D03*
X498729Y877014D03*
X489479Y893036D03*
X495029Y889832D03*
X491329D03*
X487629D03*
X498729D03*
X500579Y893036D03*
X498729Y896240D03*
X496879Y899445D03*
X489478D03*
X496878Y912262D03*
X495029Y909057D03*
X489478Y905853D03*
X495029Y902649D03*
X493179Y905853D03*
X485778D03*
X498728Y915466D03*
X495028Y928283D03*
X493179Y925079D03*
X489478D03*
Y918670D03*
X485778Y925079D03*
X496879Y918670D03*
X495029Y921875D03*
X496878Y931488D03*
X489478D03*
X496879Y937896D03*
X495029Y941100D03*
X493179Y944304D03*
X489478D03*
Y937896D03*
X485778Y944304D03*
X498729Y934691D03*
X495028Y947509D03*
X496879Y957122D03*
X495029Y960326D03*
X489478Y957122D03*
Y950713D03*
X496878D03*
X498729Y953917D03*
X495028Y966735D03*
X493179Y963530D03*
X485778D03*
X489478D03*
X500579D03*
X496879Y976347D03*
X496878Y969939D03*
X489478Y976347D03*
Y969939D03*
X495029Y979552D03*
X498728Y973143D03*
X493179Y982756D03*
X489478D03*
X485778D03*
X497311Y1009297D03*
X497312Y1002888D03*
X495462Y999684D03*
X489911Y1009297D03*
X489912Y1002888D03*
X491761Y1006093D03*
X488062D03*
X499161D03*
X495461Y1012501D03*
X497311Y1028523D03*
X489911D03*
Y1022114D03*
Y1015705D03*
X497311Y1022114D03*
X495462Y1018910D03*
X493612Y1015705D03*
X486211D03*
X501012D03*
X499161Y1025318D03*
X495461Y1031727D03*
X497312Y1041340D03*
X489911D03*
Y1034931D03*
X495462Y1038136D03*
X493612Y1034931D03*
X486211D03*
X499161Y1044544D03*
X489911Y1047749D03*
X497311D03*
Y1060565D03*
X489911D03*
Y1054157D03*
X495461Y1050952D03*
X493611Y1054157D03*
X486211D03*
X489911Y1066974D03*
X495461Y1070178D03*
X489911Y1073383D03*
X497312Y1079791D03*
X489911D03*
X497311Y1086200D03*
X493612Y1092608D03*
X489911D03*
Y1086200D03*
X486211Y1092608D03*
X495461Y1089404D03*
X499161Y1082995D03*
X495462Y1095813D03*
X499162D03*
X491762D03*
X497312Y1105426D03*
X493611D03*
X491762Y1102221D03*
X488061D03*
X486211Y1105426D03*
X486212Y1099017D03*
X499161Y1108630D03*
Y1102221D03*
X497312Y1111834D03*
X489911D03*
Y1099017D03*
X495462Y1102221D03*
X501011Y1099017D03*
X493611D03*
X497311D03*
X489911Y1105426D03*
X486211Y1111834D03*
X491762Y1108630D03*
X488062D03*
X497311Y1118243D03*
X495462Y1121447D03*
X493612Y1118243D03*
X489911D03*
X486211D03*
X501011D03*
X499161Y1115039D03*
X491761Y1127856D03*
X499161D03*
X491762Y1115039D03*
X495462D03*
X497311Y1131060D03*
X493611D03*
X489911D03*
X486211D03*
X491761Y1140973D03*
X501011Y1131060D03*
X499161Y1140973D03*
X507979Y841467D03*
X515379D03*
X506129Y851380D03*
X502429D03*
X513529D03*
X509829D03*
X517229D03*
X513529Y864197D03*
X509829D03*
X506129D03*
X502429D03*
X507979Y854584D03*
X515379D03*
X517229Y864197D03*
X507979Y867401D03*
X515379D03*
X509829Y877014D03*
X507979Y880219D03*
X502429Y877014D03*
X513529D03*
X506129D03*
X515379Y880219D03*
X517229Y877014D03*
X506129Y889832D03*
X502428Y896240D03*
X502429Y889832D03*
X513529D03*
X509829D03*
X506128Y896240D03*
X504279Y893036D03*
X515379D03*
X517229Y889832D03*
X507978Y899445D03*
X515378D03*
X511678Y905853D03*
X509829Y909057D03*
X507979Y912262D03*
X502429Y909057D03*
Y902649D03*
X509828D03*
X515378Y912262D03*
Y905853D03*
X502429Y915466D03*
X506129D03*
X511678Y925079D03*
X509829Y928283D03*
X502429D03*
Y921875D03*
X509828D03*
X507978Y918670D03*
X515378Y925079D03*
Y918670D03*
X507979Y931488D03*
X515378D03*
X511678Y944304D03*
X509828Y941100D03*
X506129Y934691D03*
X502429Y941100D03*
Y934691D03*
X515378Y944304D03*
Y937896D03*
X502429Y947509D03*
X509828Y960326D03*
X507978Y957122D03*
X506129Y953917D03*
X502429Y960326D03*
Y953917D03*
X507979Y950713D03*
X515378Y957122D03*
Y950713D03*
X509829Y966735D03*
X502428D03*
X511678Y963530D03*
X504278D03*
X515378D03*
X507978Y976347D03*
X507979Y969939D03*
X502429Y979552D03*
Y973143D03*
X513529D03*
X509828Y979552D03*
X506129Y973143D03*
X515379Y976347D03*
X515378Y969939D03*
X517228Y973143D03*
X511678Y982756D03*
X515378D03*
X510261Y999684D03*
X508411Y1002888D03*
X506562Y1006093D03*
X502862Y999684D03*
X502861Y1012501D03*
X508412Y1009297D03*
X510262Y1012501D03*
X515811Y1009297D03*
Y1002888D03*
X508411Y1028523D03*
X502862Y1025318D03*
Y1018910D03*
X510261D03*
X508411Y1022114D03*
X506562Y1025318D03*
X504711Y1015705D03*
X515811Y1028523D03*
Y1022114D03*
X510262Y1031727D03*
X502862D03*
X515811Y1015705D03*
X512111D03*
X502862Y1044544D03*
Y1038136D03*
X512111Y1034931D03*
X510261Y1038136D03*
X508411Y1041340D03*
X506562Y1044544D03*
X515811Y1034931D03*
Y1041340D03*
X508411Y1047749D03*
X515811D03*
X508411Y1060565D03*
X502862Y1057361D03*
Y1050952D03*
X512111Y1054157D03*
X510262Y1050952D03*
X515811Y1054157D03*
Y1060565D03*
X502862Y1063770D03*
X510262Y1070178D03*
X502862Y1076587D03*
Y1070178D03*
X515811Y1073383D03*
Y1079791D03*
X512112Y1092608D03*
X510262Y1089404D03*
X508412Y1086200D03*
X506562Y1082995D03*
X502862Y1089404D03*
Y1082995D03*
X515812Y1092608D03*
X513961Y1095813D03*
X502862D03*
X517662D03*
X513962Y1108630D03*
Y1102221D03*
X512112Y1099017D03*
X508411D03*
X506562Y1108630D03*
X504711Y1099017D03*
X502862Y1102221D03*
X515811Y1105426D03*
Y1111834D03*
X517662Y1108630D03*
X513961Y1115039D03*
X512111Y1118243D03*
X508411D03*
X504711D03*
X510261Y1115039D03*
X515811Y1118243D03*
X513961Y1127856D03*
X506561D03*
X517662Y1115039D03*
X513961Y1140973D03*
X512111Y1131060D03*
X508411D03*
X504711D03*
X506561Y1140973D03*
X515811Y1131060D03*
X528329Y844671D03*
X522779Y841467D03*
X528329Y851380D03*
X524629D03*
X520929D03*
X532029D03*
X528329Y864197D03*
X524629D03*
X520929D03*
X530179Y860993D03*
Y854584D03*
X522779D03*
X532028Y857789D03*
X533879Y860993D03*
X530178Y867401D03*
X522779D03*
X533879D03*
X528329Y877014D03*
X522779Y880219D03*
X520929Y877014D03*
X530179Y880219D03*
X524629Y877014D03*
X532029D03*
X533879Y880219D03*
Y873810D03*
X532028Y883423D03*
X528329Y896240D03*
Y889832D03*
X524629D03*
X526479Y893036D03*
X524629Y896240D03*
X520929Y889832D03*
X532029D03*
Y896240D03*
X533879Y893036D03*
X522779Y899445D03*
X533879D03*
X528329Y902649D03*
X522778Y912262D03*
X520928Y909057D03*
X519079Y905853D03*
X520929Y902649D03*
X528329Y915466D03*
X524628D03*
X532029D03*
X528329Y909057D03*
X533879Y912262D03*
X528329Y921875D03*
X520928Y928283D03*
X519079Y925079D03*
X522779Y918670D03*
X520929Y921875D03*
X522778Y931488D03*
X528329Y928283D03*
X533879Y918670D03*
X533878Y931488D03*
X528329Y941100D03*
Y934691D03*
X524628D03*
X522779Y937896D03*
X520929Y941100D03*
X519079Y944304D03*
X520928Y947509D03*
X532029Y934691D03*
X533879Y937896D03*
X528329Y947509D03*
Y960326D03*
Y953917D03*
X524629D03*
X522779Y957122D03*
X520929Y960326D03*
X522778Y950713D03*
X520928Y966735D03*
X526479Y963530D03*
X519079D03*
X533879Y957122D03*
X532029Y953917D03*
X533879Y950713D03*
X530178Y963530D03*
X528329Y966735D03*
Y979552D03*
Y973143D03*
X522779Y976347D03*
X522778Y969939D03*
X524628Y973143D03*
X520929Y979552D03*
X533879Y976347D03*
X519079Y982756D03*
X533901Y980606D03*
X533879Y969939D03*
X532029Y973143D03*
X521361Y1012501D03*
Y999684D03*
X528762Y1006093D03*
Y999684D03*
X525061Y1006093D03*
X523211Y1009297D03*
X523212Y1002888D03*
X534311Y1009297D03*
Y1002888D03*
X532461Y1006093D03*
X528761Y1012501D03*
X528762Y1025318D03*
X523211Y1028523D03*
X525061Y1025318D03*
X528762Y1031727D03*
X521361D03*
X519512Y1015705D03*
X521362Y1018910D03*
X523211Y1022114D03*
X526912Y1015705D03*
X528762Y1018910D03*
X530611Y1015705D03*
X534311Y1028523D03*
X534310Y1022114D03*
X532461Y1025318D03*
X528762Y1044544D03*
X525061D03*
X523212Y1041340D03*
X521362Y1038136D03*
X519512Y1034931D03*
X532462Y1044544D03*
X523211Y1047749D03*
X528762Y1038136D03*
X534311Y1041340D03*
Y1047749D03*
X528762Y1057361D03*
Y1050952D03*
X523212Y1060565D03*
X521361Y1050952D03*
X519512Y1054157D03*
X528762Y1063770D03*
X534311Y1060565D03*
X528762Y1076587D03*
Y1070178D03*
X521361D03*
X523212Y1079791D03*
X534311D03*
X523211Y1086200D03*
X521361Y1089404D03*
X519511Y1092608D03*
X528762Y1089404D03*
Y1082995D03*
X525061D03*
X532462Y1082996D03*
X534311Y1086200D03*
X528761Y1095813D03*
X526911Y1105426D03*
X521361Y1102221D03*
X519511Y1105426D03*
X519512Y1099017D03*
X532461Y1108630D03*
X530612Y1111834D03*
X523211D03*
X526911Y1099017D03*
X534311D03*
X532460Y1102221D03*
X521362Y1108630D03*
X525062D03*
X534311Y1111834D03*
X523211Y1105426D03*
X534311D03*
X528762Y1108630D03*
X519511Y1111834D03*
X526911D03*
X530611Y1124651D03*
Y1118243D03*
X528762Y1121447D03*
X523211Y1118243D03*
X521361Y1115039D03*
X519511Y1118243D03*
X532461Y1115039D03*
X528761Y1127856D03*
X521361D03*
X525062Y1115039D03*
X528762D03*
X530612Y1137469D03*
Y1131060D03*
X526912D03*
X523211D03*
X519511D03*
X528761Y1134264D03*
X521361Y1140973D03*
X534311Y1131060D03*
X537580Y848176D03*
X535729Y844671D03*
Y851380D03*
X544979Y860993D03*
Y854584D03*
X539428Y864197D03*
X537579Y854584D03*
Y860993D03*
X544979Y867401D03*
X541279D03*
X537579D03*
X546829Y870606D03*
X541279Y873810D03*
X535729Y870606D03*
Y883423D03*
X541279Y880219D03*
X546829Y883423D03*
X537579Y893036D03*
X541279Y886627D03*
X544979D03*
X537579D03*
X535729Y889832D03*
X550529D03*
X537579Y899445D03*
X548679Y912262D03*
X537579D03*
X539429Y909057D03*
X537579Y905853D03*
X535729Y909057D03*
X543129D03*
X535729Y902649D03*
X548679Y905853D03*
X537579Y918670D03*
X535729Y921875D03*
X537578Y931488D03*
X548678D03*
X537579Y937896D03*
X535729Y941100D03*
X539429Y947509D03*
X535729D03*
X537579Y957122D03*
Y950713D03*
X535729Y960326D03*
Y966735D03*
X537579Y963530D03*
X539429Y979552D03*
X537579Y982756D03*
X541279Y969939D03*
X539429Y973143D03*
X535729D03*
X539862Y1006092D03*
X539861Y999684D03*
X536161D03*
Y1006093D03*
X543563Y1006092D03*
X549254Y1000648D03*
X536161Y1012501D03*
Y1025318D03*
X539861Y1018910D03*
X541712Y1015705D03*
X545412D03*
X538012D03*
X536161Y1018910D03*
X549112Y1015705D03*
X536161Y1031727D03*
X545412Y1034931D03*
X539862Y1044544D03*
X539861Y1038136D03*
X541711Y1034931D03*
X538011D03*
X536161Y1038136D03*
X549112Y1034931D03*
X541711Y1054157D03*
X538011D03*
X545411D03*
X538011Y1060565D03*
X536161Y1050952D03*
X538011Y1066974D03*
X539861Y1076587D03*
X536162Y1082996D03*
X538011Y1092608D03*
X536161Y1089404D03*
X545411Y1092608D03*
X547262Y1082996D03*
X543561Y1095813D03*
X536161D03*
X547261D03*
X545412Y1105426D03*
X541711D03*
X539861Y1108630D03*
Y1102221D03*
X536161D03*
X541711Y1111834D03*
X545411D03*
X538011Y1105426D03*
X536161Y1108630D03*
X538011Y1111834D03*
X543561Y1108630D03*
X545411Y1124651D03*
Y1118243D03*
X543562Y1115039D03*
X539862D03*
X538011Y1124651D03*
X536161Y1115039D03*
X541711Y1131060D03*
X536162Y1134264D03*
X551429Y979057D03*
X550701Y972608D03*
X550961Y1031727D03*
X560571Y1614292D03*
X580431Y1602380D03*
X688999Y1051247D03*
X748399D03*
X1293802Y162999D03*
X1297007Y161149D03*
X1297012Y168549D03*
X1297007Y164849D03*
X1293802Y183349D03*
Y187049D03*
Y190749D03*
Y198149D03*
Y194449D03*
Y201849D03*
X1296999Y209249D03*
X1300774Y155288D03*
X1309832Y161149D03*
X1303417D03*
X1309832Y168549D03*
X1303417D03*
X1303422Y172249D03*
X1313033Y174099D03*
X1306622D03*
X1300207Y185199D03*
X1306617Y181499D03*
X1300207Y192599D03*
X1309817Y187049D03*
X1306617Y192599D03*
X1313023Y199999D03*
X1306617D03*
X1300207D03*
X1303407Y201849D03*
X1303422Y209249D03*
X1313032Y214799D03*
X1306622Y218499D03*
X1303417Y212949D03*
Y216649D03*
X1300207Y214799D03*
X1301151Y225450D03*
X1309828Y224049D03*
X1306622Y222199D03*
X1309100Y236477D03*
X1313920Y854584D03*
X1312266Y857972D03*
X1312070Y877014D03*
X1310221Y880219D03*
X1308370Y877014D03*
X1312070Y896240D03*
X1310220Y893036D03*
X1308371Y902649D03*
X1312070Y915466D03*
X1308370D03*
X1308371Y921875D03*
X1312070Y934692D03*
X1308371Y941100D03*
X1308370Y934692D03*
X1312070Y953917D03*
X1308370D03*
X1310221Y957122D03*
X1308371Y973143D03*
X1310221Y976347D03*
X1314352Y996480D03*
X1314353Y1002888D03*
X1308803Y1006093D03*
X1314353Y1015705D03*
Y1022114D03*
X1308803Y1025318D03*
Y1018910D03*
X1314353Y1041340D03*
X1308803Y1044544D03*
X1310653Y1041340D03*
X1314353Y1060565D03*
X1312502Y1082995D03*
X1314353Y1111834D03*
Y1105426D03*
X1312503Y1115039D03*
Y1127856D03*
X1320469Y155288D03*
X1322652Y161149D03*
X1316242D03*
X1319452Y166699D03*
X1329062Y168549D03*
X1319442Y170399D03*
X1318502Y176574D03*
Y186024D03*
Y182874D03*
X1329062Y172249D03*
X1316237D03*
X1331102Y176574D03*
X1327952Y186024D03*
Y182874D03*
X1318502Y189174D03*
X1315352Y195474D03*
X1327952Y189174D03*
X1331102Y195474D03*
X1327952Y198624D03*
X1321652D03*
X1325852Y214799D03*
X1319442Y218499D03*
X1329062Y209249D03*
X1319442Y207399D03*
X1329062Y216649D03*
X1319442Y222199D03*
X1329061Y224049D03*
X1326377Y235784D03*
X1321986Y236726D03*
X1326869Y844971D03*
X1323170D03*
X1321320Y848176D03*
X1330571Y851380D03*
X1323170D03*
X1319469D03*
X1317620Y854584D03*
X1315770Y857789D03*
X1330571Y864197D03*
X1326871D03*
X1323171D03*
Y857789D03*
X1325020Y854584D03*
X1321321Y860993D03*
X1319469Y857789D03*
X1317621Y867401D03*
X1328721D03*
X1325021D03*
X1330571Y877014D03*
X1328722Y880219D03*
X1326871Y877014D03*
X1321321Y873810D03*
X1315771Y877014D03*
X1317621Y873810D03*
X1321321Y880219D03*
X1319471Y877014D03*
X1315771Y883423D03*
X1326871D03*
X1323171D03*
X1328720Y899445D03*
X1315771Y896240D03*
Y889832D03*
X1328720Y893036D03*
Y886627D03*
X1325021D03*
X1321321Y893036D03*
X1319470Y896240D03*
X1321321Y899445D03*
X1328720Y905853D03*
X1325020D03*
X1317621Y912262D03*
X1317620Y905853D03*
X1328720Y912262D03*
X1323171Y909057D03*
Y902649D03*
X1321321Y912262D03*
X1315771Y915466D03*
X1319471D03*
X1328720Y925079D03*
Y918670D03*
X1325020Y925079D03*
X1317620D03*
X1323171Y928283D03*
Y921875D03*
X1321321Y918670D03*
X1317621Y931488D03*
X1328720D03*
X1321321D03*
X1323171Y941100D03*
X1325020Y944304D03*
X1323171Y947509D03*
X1317620Y944304D03*
X1328720D03*
Y937896D03*
X1315771Y934692D03*
X1321321Y937896D03*
X1319470Y934692D03*
X1321321Y957122D03*
X1323171Y966735D03*
X1325020Y963530D03*
X1323171Y960326D03*
X1321321Y950713D03*
X1315771Y953917D03*
Y966735D03*
X1319470Y953917D03*
X1319471Y966735D03*
X1319470Y960326D03*
X1317621Y950713D03*
X1328720Y957122D03*
Y963530D03*
Y950713D03*
X1321321Y969939D03*
X1325020Y982756D03*
X1323171Y979552D03*
X1321321Y976347D03*
X1315771Y973143D03*
X1319471D03*
X1328720Y969939D03*
X1330570Y973143D03*
X1326871D03*
X1328720Y982756D03*
X1328721Y976347D03*
X1315771Y979552D03*
X1318053Y1009297D03*
Y1002888D03*
X1327304Y1006093D03*
X1331003D03*
X1329153Y1009297D03*
Y1002888D03*
X1323603Y999684D03*
X1321753Y1009297D03*
X1319903Y1006093D03*
X1321753Y1002888D03*
X1323603Y1012501D03*
X1329153Y1028523D03*
Y1015705D03*
X1318053Y1022114D03*
Y1015705D03*
X1329153Y1022114D03*
X1325453Y1015705D03*
X1323603Y1018910D03*
X1321753Y1028523D03*
X1319903Y1018910D03*
X1321753Y1022114D03*
Y1015705D03*
X1319903Y1031727D03*
X1323603D03*
X1329153Y1034931D03*
Y1047749D03*
X1318053Y1041340D03*
X1319903Y1038136D03*
X1329153Y1041340D03*
X1325453Y1034931D03*
X1323603Y1038136D03*
X1321753Y1041340D03*
X1319903Y1044544D03*
X1321753Y1047749D03*
X1329153Y1060565D03*
Y1054157D03*
X1325453D03*
X1319903Y1057361D03*
Y1050952D03*
X1323603D03*
Y1057361D03*
X1321753Y1060565D03*
X1319903Y1063770D03*
X1329153Y1073383D03*
X1319903Y1076587D03*
Y1070178D03*
X1316204Y1076587D03*
X1329153Y1066974D03*
X1323603Y1076587D03*
Y1070178D03*
X1325454Y1073383D03*
X1321753Y1066974D03*
X1329153Y1079791D03*
X1321753D03*
X1318053D03*
X1329153Y1086200D03*
Y1092608D03*
X1325452Y1092609D03*
X1323603Y1089404D03*
X1321752Y1086200D03*
X1319902Y1082995D03*
X1316202D03*
X1316203Y1095813D03*
X1331003Y1108630D03*
X1329153Y1099017D03*
X1323603Y1108630D03*
X1316203D03*
Y1102221D03*
X1325453Y1099017D03*
X1323603Y1102221D03*
X1319903D03*
X1316203Y1115039D03*
X1331003D03*
X1327303Y1121447D03*
Y1115039D03*
X1325453Y1124651D03*
X1325454Y1118243D03*
X1321753D03*
X1319903Y1115039D03*
X1329152Y1137469D03*
X1329153Y1131060D03*
X1321752Y1137469D03*
X1325453Y1131060D03*
X1319903Y1134264D03*
X1344103Y155288D03*
X1342936Y159301D03*
X1335472Y161149D03*
X1346137Y168549D03*
X1342907Y166699D03*
X1332268D03*
X1346137Y164849D03*
X1339727D03*
X1335472Y168549D03*
X1339568Y176028D03*
X1339727Y179649D03*
X1342937Y181499D03*
Y185199D03*
X1346137Y172249D03*
X1335472D03*
X1339727Y190749D03*
X1342937Y188899D03*
X1334252Y195474D03*
X1346137Y194449D03*
Y190749D03*
X1346147Y209248D03*
X1332262Y218499D03*
Y214799D03*
X1332285Y226210D03*
X1342937Y222199D03*
X1332267D03*
X1343521Y841467D03*
X1336121D03*
X1345371Y851380D03*
X1341671D03*
X1337971D03*
X1334271D03*
X1345371Y864197D03*
X1343521Y854584D03*
X1341671Y864197D03*
X1337971D03*
X1336121Y854584D03*
X1334271Y864197D03*
X1343521Y867401D03*
X1336121D03*
X1345371Y877014D03*
X1343521Y880219D03*
X1341671Y877014D03*
X1337971D03*
X1334271D03*
X1332420Y886627D03*
X1345371Y896240D03*
Y889832D03*
X1341671Y896240D03*
Y889832D03*
X1337970Y896240D03*
X1337971Y889832D03*
X1336121Y893036D03*
X1334270Y889832D03*
X1332420Y905853D03*
X1341671Y909057D03*
Y902649D03*
X1336120Y912262D03*
X1334270Y909057D03*
X1334271Y902649D03*
X1347221Y912262D03*
X1345371Y915466D03*
X1341671D03*
X1337970D03*
X1332421Y925079D03*
X1341671Y928283D03*
Y921875D03*
X1334270Y928283D03*
X1334271Y921875D03*
X1347220Y918670D03*
X1336120Y931488D03*
X1347221D03*
X1341671Y947509D03*
X1334270D03*
X1334271Y941100D03*
X1332421Y944304D03*
X1345371Y934691D03*
X1341671D03*
X1337970D03*
X1337971Y953917D03*
X1345371D03*
X1341671D03*
Y960326D03*
X1347220Y957122D03*
X1343520Y963530D03*
X1339821D03*
X1341670Y966735D03*
X1347221Y950713D03*
X1334271Y960326D03*
X1336121Y957122D03*
X1332421Y963530D03*
X1334270Y966735D03*
X1336120Y950713D03*
X1347221Y969939D03*
X1337970Y973143D03*
X1347220Y976347D03*
X1345371Y973143D03*
X1341671Y979552D03*
Y973143D03*
X1336120Y969939D03*
X1336121Y976347D03*
X1334271Y979552D03*
X1332421Y982756D03*
X1342104Y999684D03*
Y1006093D03*
X1338403D03*
X1336553Y1009297D03*
X1336554Y1002888D03*
X1334704Y999684D03*
X1347654Y1009297D03*
X1342103Y1012501D03*
X1334703D03*
X1332854Y1015705D03*
X1345804Y1025318D03*
X1343953Y1015705D03*
X1342104Y1025318D03*
Y1018910D03*
X1340254Y1015705D03*
X1336553Y1028523D03*
X1338403Y1025318D03*
X1336554Y1022114D03*
X1334704Y1018910D03*
X1347653Y1028523D03*
Y1022114D03*
X1342104Y1031727D03*
X1334703D03*
X1332854Y1034931D03*
X1345804Y1044544D03*
X1342104D03*
Y1038136D03*
X1338403Y1044544D03*
X1336554Y1041340D03*
X1334704Y1038136D03*
X1347653Y1041340D03*
X1336553Y1047749D03*
X1347653D03*
X1332854Y1054157D03*
X1342104Y1057361D03*
Y1050952D03*
X1336554Y1060565D03*
X1334704Y1057361D03*
X1334703Y1050952D03*
X1347653Y1060565D03*
X1345804Y1063770D03*
X1342104D03*
X1338403D03*
X1332854Y1073383D03*
X1342104Y1070178D03*
X1336553Y1066974D03*
X1334703Y1070178D03*
X1334704Y1076587D03*
X1347654Y1066974D03*
X1336554Y1079791D03*
X1347653D03*
X1345804Y1082995D03*
X1342104Y1089404D03*
Y1082995D03*
X1338403D03*
X1336553Y1086200D03*
X1334703Y1089404D03*
X1332854Y1092608D03*
X1347654Y1086200D03*
X1342104Y1095813D03*
X1334703D03*
X1342104Y1102221D03*
X1338404D03*
X1336553Y1099017D03*
X1332853Y1105426D03*
Y1099017D03*
X1347654Y1105426D03*
Y1099017D03*
X1340254Y1111834D03*
X1332854D03*
X1347654D03*
X1343953Y1118243D03*
X1340253D03*
X1338403Y1115039D03*
X1336553Y1118243D03*
X1332853D03*
X1347653D03*
X1342104Y1127856D03*
X1334703D03*
X1343953Y1131060D03*
X1342103Y1140973D03*
X1340254Y1131060D03*
X1336554D03*
X1334703Y1140973D03*
X1332854Y1131060D03*
X1347653D03*
X1349351Y159298D03*
X1355758D03*
X1355761Y162998D03*
X1358865Y166732D03*
Y158854D03*
Y162793D03*
X1349351Y166698D03*
X1352557Y164848D03*
X1358865Y170671D03*
Y174603D03*
Y182484D03*
Y178544D03*
X1355761Y170398D03*
X1352557Y179648D03*
X1358371Y188778D03*
X1358865Y195240D03*
Y199180D03*
X1349351Y196298D03*
X1352561Y194448D03*
X1352551Y190748D03*
X1349345Y188898D03*
X1355761Y192598D03*
X1358865Y207060D03*
Y203120D03*
Y213994D03*
Y217934D03*
X1352560Y205549D03*
X1355765Y207399D03*
X1349351Y214798D03*
X1352561Y212948D03*
X1349351Y211098D03*
Y222198D03*
X1358321Y841467D03*
X1350921D03*
X1360171Y851380D03*
X1356471D03*
X1352771D03*
X1349071D03*
X1363871D03*
X1360171Y864197D03*
X1358321Y854584D03*
X1356471Y864197D03*
X1352771D03*
X1350921Y854584D03*
X1349071Y864197D03*
X1363871D03*
X1358321Y867401D03*
X1350921D03*
X1360171Y877014D03*
X1358321Y880219D03*
X1356471Y877014D03*
X1352771D03*
X1350921Y880219D03*
X1349071Y877014D03*
X1363871D03*
X1360171Y889832D03*
X1356471D03*
X1354621Y893036D03*
X1352771Y889832D03*
X1349071D03*
X1363871Y896240D03*
Y889832D03*
X1362021Y899445D03*
X1354620D03*
X1362020Y912262D03*
X1360170Y909057D03*
X1360171Y902649D03*
X1358321Y905853D03*
X1354620Y912262D03*
Y905853D03*
X1350920D03*
X1349071Y909057D03*
X1349070Y902649D03*
X1363870Y915466D03*
X1362021Y918670D03*
X1360170Y928283D03*
X1360171Y921875D03*
X1358321Y925079D03*
X1354620D03*
Y918670D03*
X1350920Y925079D03*
X1349071Y928283D03*
X1349070Y921875D03*
X1362020Y931488D03*
X1360171Y941100D03*
X1358321Y944304D03*
X1354620D03*
X1360170Y947509D03*
X1350920Y944304D03*
X1349071Y947509D03*
X1349070Y941100D03*
X1362021Y937896D03*
X1354620D03*
X1363870Y934691D03*
X1363871Y953917D03*
X1360171Y960326D03*
X1362021Y957122D03*
X1354620D03*
X1358321Y963530D03*
X1354620D03*
X1360170Y966735D03*
X1354620Y950713D03*
X1362020D03*
X1349070Y960326D03*
X1350920Y963530D03*
X1349071Y966735D03*
X1362020Y969939D03*
X1354620D03*
X1363870Y973143D03*
X1362021Y976347D03*
X1360171Y979552D03*
X1358321Y982756D03*
X1356470Y973143D03*
X1354620Y982756D03*
X1354621Y976347D03*
X1350920Y982756D03*
X1349070Y979552D03*
X1352771Y973143D03*
X1351352Y996480D03*
X1349503Y999684D03*
X1362453Y1009297D03*
X1362454Y1002888D03*
X1360604Y999684D03*
X1355053Y1009297D03*
Y1002888D03*
X1360603Y1012501D03*
X1349504D03*
X1362453Y1028523D03*
X1362454Y1022114D03*
X1360604Y1018910D03*
X1358754Y1015705D03*
X1355053Y1028523D03*
Y1022114D03*
Y1015705D03*
X1351353D03*
X1349503Y1018910D03*
X1360603Y1031727D03*
X1349504D03*
X1362454Y1041340D03*
X1360604Y1038136D03*
X1358754Y1034931D03*
X1355053Y1041340D03*
Y1034931D03*
X1351353D03*
X1349503Y1038136D03*
X1362453Y1047749D03*
X1355053D03*
X1362454Y1060565D03*
X1360604Y1057361D03*
X1360603Y1050952D03*
X1358754Y1054157D03*
X1355053D03*
X1351353D03*
X1349503Y1057361D03*
X1349504Y1050952D03*
X1362453Y1066974D03*
X1360604Y1076587D03*
X1360603Y1070178D03*
X1358754Y1073383D03*
X1355053D03*
Y1066974D03*
X1351353Y1073383D03*
X1349503Y1076587D03*
X1349504Y1070178D03*
X1362453Y1079791D03*
X1355053D03*
X1362453Y1086200D03*
X1360603Y1089404D03*
X1358753Y1092608D03*
X1355053D03*
Y1086200D03*
X1351353Y1092608D03*
X1349504Y1089404D03*
X1360604Y1095813D03*
X1349504D03*
X1362454Y1099017D03*
X1360604Y1102221D03*
X1356904Y1108630D03*
X1355053Y1099017D03*
X1353204Y1102221D03*
X1349503Y1108630D03*
Y1102221D03*
X1362453Y1118243D03*
X1360603Y1115039D03*
X1358753Y1118243D03*
X1355053D03*
X1353203Y1115039D03*
X1351353Y1118243D03*
X1349503Y1115039D03*
X1356903Y1127856D03*
X1349503D03*
X1362453Y1131060D03*
X1358753D03*
X1356903Y1140973D03*
X1355053Y1131060D03*
X1351353D03*
X1349503Y1140973D03*
X1373121Y841467D03*
X1365721D03*
X1378671Y851380D03*
X1374971D03*
X1371271D03*
X1367571D03*
X1378671Y864197D03*
X1374971D03*
X1373121Y854584D03*
X1371271Y864197D03*
X1367571D03*
X1365721Y854584D03*
X1373121Y867401D03*
X1365721D03*
X1378671Y877014D03*
X1374971D03*
X1373121Y880219D03*
X1371271Y877014D03*
X1367571D03*
X1365721Y880219D03*
X1378671Y889832D03*
X1374971D03*
X1371271Y896240D03*
Y889832D03*
X1367570Y896240D03*
X1367571Y889832D03*
X1365721Y893036D03*
X1374971Y909057D03*
X1374970Y902649D03*
X1373121Y912262D03*
X1367571Y909057D03*
Y902649D03*
X1371271Y915466D03*
X1367571D03*
X1376820Y925079D03*
X1374971Y928283D03*
X1374970Y921875D03*
X1373120Y918670D03*
X1367571Y928283D03*
Y921875D03*
X1376820Y937896D03*
X1374970Y941100D03*
X1371271Y934691D03*
X1367571Y941100D03*
Y934691D03*
X1374971Y947509D03*
X1367571D03*
X1376820Y957122D03*
X1374970Y960326D03*
X1373120Y957122D03*
X1373121Y950713D03*
X1371271Y953917D03*
X1367571Y960326D03*
Y953917D03*
X1376820Y963530D03*
X1374971Y966735D03*
X1367571D03*
X1376820Y982756D03*
Y969939D03*
X1374970Y979552D03*
X1373120Y976347D03*
X1373121Y969939D03*
X1371271Y973143D03*
X1367571Y979552D03*
Y973143D03*
X1364303Y1006093D03*
X1377253Y1002888D03*
X1373554Y1009297D03*
X1373553Y1002888D03*
X1371704Y1006093D03*
X1368004D03*
Y999684D03*
X1375404Y1012501D03*
X1368003D03*
X1364303Y1025318D03*
X1375403Y1018910D03*
X1373553Y1028523D03*
Y1022114D03*
X1371704Y1025318D03*
X1369853Y1015705D03*
X1368004Y1025318D03*
Y1018910D03*
X1366154Y1015705D03*
X1375404Y1031727D03*
X1368004D03*
X1364303Y1044544D03*
X1375403Y1038136D03*
X1373553Y1041340D03*
X1371704Y1044544D03*
X1368004D03*
Y1038136D03*
X1373553Y1047749D03*
X1375403Y1057361D03*
X1375404Y1050952D03*
X1373553Y1060565D03*
X1368004Y1057361D03*
Y1050952D03*
X1364303Y1063770D03*
X1371704D03*
X1368004D03*
X1377253Y1073383D03*
X1375403Y1076587D03*
X1375404Y1070178D03*
X1373554Y1066974D03*
X1368004Y1076587D03*
Y1070178D03*
X1377253Y1079791D03*
X1373553D03*
X1364303Y1082995D03*
X1377254Y1092608D03*
X1377253Y1086200D03*
X1375404Y1089404D03*
X1373554Y1086200D03*
X1371704Y1082995D03*
X1368004Y1089404D03*
Y1082995D03*
X1379104Y1095813D03*
X1375403D03*
X1368004D03*
X1364304Y1108630D03*
Y1102221D03*
X1377253Y1105426D03*
X1375404Y1102221D03*
X1373554Y1099017D03*
X1371704Y1102221D03*
X1366153Y1105426D03*
X1373553Y1111834D03*
X1366153D03*
X1364303Y1115039D03*
X1377253Y1118243D03*
X1373553D03*
X1371703Y1115039D03*
X1369853Y1118243D03*
X1366153D03*
X1364303Y1127856D03*
X1379103D03*
X1371703D03*
X1364303Y1140973D03*
X1379103D03*
X1377253Y1131060D03*
X1373553D03*
X1371703Y1140973D03*
X1369853Y1131060D03*
X1366153D03*
X1380521Y841467D03*
X1395321D03*
X1387921D03*
X1393471Y851380D03*
X1389771D03*
X1386071D03*
X1382371D03*
X1380521Y854584D03*
X1395321D03*
X1393471Y864197D03*
X1389771D03*
X1387921Y854584D03*
X1386071Y864197D03*
X1382371D03*
X1380521Y867401D03*
X1395321D03*
X1387921D03*
X1380521Y880219D03*
X1395321D03*
X1393471Y877014D03*
X1389771D03*
X1387921Y880219D03*
X1386071Y877014D03*
Y870606D03*
X1382371Y877014D03*
X1395321Y893036D03*
X1393471Y889832D03*
X1389771D03*
X1387921Y893036D03*
X1386071Y889832D03*
X1384221Y893036D03*
X1382371Y889832D03*
X1386071Y902649D03*
X1380520Y912262D03*
Y905853D03*
X1395320Y912262D03*
X1395321Y905853D03*
X1393471Y902649D03*
X1389771D03*
X1386071Y909057D03*
Y915466D03*
X1380520Y918670D03*
X1395187Y926265D03*
X1395320Y918670D03*
X1386071Y921875D03*
X1381189Y930811D03*
Y938045D03*
X1381287Y946239D03*
Y948539D03*
X1381189Y935745D03*
X1390234Y942097D03*
X1381264Y965896D03*
Y963596D03*
X1390506Y971139D03*
X1392896D03*
X1381003Y981269D03*
Y978969D03*
Y986421D03*
X1381243Y992971D03*
Y995271D03*
X1381003Y988721D03*
X1381369Y1007156D03*
X1381373Y1004848D03*
X1393716Y1000059D03*
X1391326D03*
X1381128Y1022427D03*
X1381140Y1026821D03*
X1384466Y1034270D03*
Y1031970D03*
X1393904Y1044544D03*
X1384653Y1041340D03*
X1380953Y1047749D03*
X1388353D03*
X1380953Y1060565D03*
X1393904Y1050952D03*
X1392053Y1060565D03*
Y1054157D03*
X1388353Y1060565D03*
X1386504Y1050952D03*
X1384653Y1054157D03*
X1380953Y1066974D03*
X1395753Y1073383D03*
X1392053Y1066974D03*
X1386504Y1076587D03*
Y1070178D03*
X1382803Y1076587D03*
X1380953Y1079791D03*
X1388353D03*
X1393903Y1089404D03*
Y1082995D03*
X1392053Y1092608D03*
X1392054Y1086200D03*
X1388353Y1092608D03*
X1384653Y1086200D03*
X1386504Y1095813D03*
X1382804D03*
X1380954Y1105426D03*
X1393904Y1102221D03*
X1392054Y1099017D03*
X1390204Y1108630D03*
X1388353Y1099017D03*
X1386504Y1102221D03*
X1382803Y1108630D03*
Y1102221D03*
X1380954Y1111834D03*
X1380953Y1118243D03*
X1386503Y1115039D03*
X1384653Y1118243D03*
X1382803Y1115039D03*
X1386503Y1127856D03*
X1380953Y1131060D03*
X1386503Y1140973D03*
X1384653Y1131060D03*
X1408269Y844971D03*
X1402721Y841467D03*
X1397171Y851380D03*
X1408271D03*
X1404571D03*
X1400871D03*
X1397171Y864197D03*
X1408271D03*
X1404571D03*
X1402721Y854584D03*
X1400871Y864197D03*
X1410121Y854584D03*
Y867401D03*
X1402721D03*
X1397171Y877014D03*
X1410121Y880219D03*
X1408271Y877014D03*
X1404571D03*
X1402721Y880219D03*
X1400871Y877014D03*
X1397171Y889832D03*
X1410121Y893036D03*
X1408271Y889832D03*
X1404571D03*
X1402721Y893036D03*
X1400871Y889832D03*
Y902649D03*
X1397171D03*
X1408271D03*
X1404571Y909057D03*
Y902649D03*
Y915466D03*
X1410121Y925079D03*
Y931488D03*
X1403016Y949498D03*
Y947198D03*
X1406420Y937896D03*
X1404016Y936469D03*
X1410120Y937896D03*
X1403046Y963634D03*
Y965934D03*
Y978035D03*
Y980335D03*
Y992421D03*
Y994721D03*
Y1009174D03*
Y1006874D03*
Y1021962D03*
Y1019662D03*
X1397604Y1063770D03*
Y1082995D03*
Y1095813D03*
X1428620Y848176D03*
X1415669Y844971D03*
X1421220Y848176D03*
X1417520D03*
X1423070Y851380D03*
X1419370D03*
X1415671D03*
X1413822Y860993D03*
X1426771Y864197D03*
X1424921Y854584D03*
X1423071Y864197D03*
X1419371D03*
X1417521Y854584D03*
X1415671Y864197D03*
Y857789D03*
X1424921Y867401D03*
X1417521D03*
X1424921Y880219D03*
X1423071Y877014D03*
X1419371D03*
X1417521Y880219D03*
X1415671Y877014D03*
X1413820Y886627D03*
X1426771Y889832D03*
X1424921Y893036D03*
X1423071Y889832D03*
X1419371D03*
X1417521Y893036D03*
X1415671Y896240D03*
Y889832D03*
X1413821Y899445D03*
Y905853D03*
X1426771Y902649D03*
X1423071Y909057D03*
Y902649D03*
X1419371D03*
X1415670D03*
X1423071Y915466D03*
Y928283D03*
X1417520Y925079D03*
Y931488D03*
X1413820Y918670D03*
X1423071Y921875D03*
X1424920Y937896D03*
X1421220D03*
X1417520D03*
X1413820D03*
X1427203Y1044544D03*
X1425353Y1047749D03*
X1429053Y1060565D03*
X1423503Y1057361D03*
Y1050952D03*
Y1063770D03*
X1425353Y1073383D03*
X1423503Y1076587D03*
Y1070178D03*
X1429053Y1079791D03*
X1425353D03*
X1425354Y1086200D03*
X1423503Y1082995D03*
X1437871Y851380D03*
X1434171D03*
X1430470D03*
X1432321Y841467D03*
X1439721D03*
X1445271Y851380D03*
X1441571D03*
X1439721Y854584D03*
X1432321D03*
X1437871Y864197D03*
X1434171D03*
X1430471D03*
X1445271D03*
X1441571D03*
X1432321Y867401D03*
X1439721D03*
X1437871Y877014D03*
X1434171D03*
X1432321Y880219D03*
X1430471Y877014D03*
X1445271D03*
X1441571D03*
X1439721Y880219D03*
X1437871Y889832D03*
X1434171D03*
X1432321Y893036D03*
X1430471Y889832D03*
X1445271Y896240D03*
X1439721Y893036D03*
X1445271Y889832D03*
X1441571D03*
X1437871Y902649D03*
X1434171D03*
X1432320Y905853D03*
X1430471Y902649D03*
X1441571D03*
Y909057D03*
Y915466D03*
X1430244Y931358D03*
Y933658D03*
X1432320Y918670D03*
X1430575Y1022185D03*
Y1019885D03*
X1443541Y1036914D03*
X1436453Y1041340D03*
X1442003Y1044544D03*
X1432753Y1047749D03*
X1440153D03*
X1432753Y1054157D03*
X1442004Y1057361D03*
X1438304Y1050952D03*
X1434604Y1063770D03*
X1442004D03*
X1432753Y1073383D03*
X1430903Y1076587D03*
X1430904Y1070178D03*
X1443853Y1073383D03*
Y1066974D03*
X1438304Y1070178D03*
X1432754Y1079791D03*
X1443853D03*
X1434603Y1082995D03*
X1432753Y1086200D03*
X1436453Y1092608D03*
X1443854Y1086200D03*
X1440153D03*
X1443854Y1092608D03*
X1442003Y1108630D03*
Y1102221D03*
X1440154Y1099017D03*
X1443853Y1105426D03*
Y1111834D03*
X1454521Y841467D03*
X1447121D03*
X1460071Y851380D03*
X1452671D03*
X1456371D03*
X1448971D03*
X1460071Y864197D03*
X1456371D03*
X1454521Y854584D03*
X1452671Y864197D03*
X1447121Y854584D03*
X1448971Y864197D03*
X1454521Y867401D03*
X1447121D03*
X1460071Y877014D03*
X1456371D03*
X1454521Y880219D03*
X1452671Y877014D03*
X1448971D03*
X1448970Y870606D03*
X1447121Y880219D03*
Y873810D03*
X1456370Y896240D03*
X1456371Y889832D03*
X1454521Y893036D03*
X1447121D03*
X1460071Y889832D03*
X1452671D03*
X1448971D03*
X1458220Y899445D03*
X1460071Y909057D03*
X1458221Y912262D03*
X1450820Y905853D03*
X1460070Y902649D03*
X1452426Y930125D03*
X1460071Y928283D03*
X1458220Y918670D03*
X1456371Y921875D03*
X1460070D03*
X1452670D03*
X1450820Y918670D03*
X1458220Y931488D03*
X1452426Y934725D03*
X1454520Y944304D03*
X1452321Y945354D03*
Y947654D03*
X1460070Y941100D03*
X1458221Y944304D03*
X1458220Y937896D03*
X1456371Y934691D03*
X1460070Y947509D03*
X1452426Y962325D03*
Y960025D03*
Y964625D03*
X1460070Y960326D03*
X1458220Y957122D03*
X1458221Y950713D03*
X1460071Y966735D03*
X1452426Y966925D03*
X1452333Y977669D03*
X1452476Y980736D03*
X1458221Y969939D03*
X1460070Y979552D03*
X1458220Y976347D03*
X1452426Y996825D03*
Y994525D03*
Y989925D03*
Y987625D03*
X1452436Y1010499D03*
X1452426Y1006025D03*
Y1003725D03*
Y1012925D03*
X1460503Y999684D03*
X1458654Y1009297D03*
X1458653Y1002888D03*
X1460504Y1012501D03*
X1452416Y1022635D03*
X1452426Y1017525D03*
X1458653Y1028523D03*
Y1022114D03*
X1460503Y1018910D03*
Y1031727D03*
X1447424Y1036526D03*
X1449649Y1035928D03*
X1458653Y1041340D03*
X1458654Y1034931D03*
X1451253Y1041340D03*
X1460503Y1038136D03*
X1458653Y1047749D03*
X1447553D03*
X1460503Y1057361D03*
X1458653Y1060565D03*
X1456804Y1050952D03*
X1451253Y1060565D03*
X1447553Y1054157D03*
X1460504Y1050952D03*
X1460503Y1076587D03*
X1451253Y1066974D03*
X1449404Y1070178D03*
X1460504D03*
X1458654Y1066974D03*
X1454953Y1073383D03*
X1458653Y1079791D03*
X1454954D03*
X1451253D03*
X1445703Y1089404D03*
X1458654Y1086200D03*
X1456804Y1082995D03*
X1453104Y1089404D03*
X1449404Y1082995D03*
X1460504Y1089404D03*
X1445704Y1095813D03*
X1460504D03*
X1456803D03*
X1445704Y1102221D03*
X1458653Y1105426D03*
X1456804Y1108630D03*
X1454953Y1099017D03*
X1449404Y1108630D03*
X1453104Y1102221D03*
X1451254Y1099017D03*
X1447553D03*
X1458653Y1111834D03*
X1460504Y1108630D03*
X1451253Y1111834D03*
X1447553D03*
X1454953Y1105426D03*
X1445704Y1108630D03*
X1449404Y1102221D03*
X1458653Y1099017D03*
X1454953Y1111834D03*
X1453104Y1108630D03*
X1447553Y1105426D03*
X1451253D03*
X1460504Y1102221D03*
X1458653Y1118243D03*
X1456803Y1115039D03*
X1454953Y1118243D03*
X1453103Y1115039D03*
X1451253Y1118243D03*
X1460503Y1127856D03*
X1453103D03*
X1460504Y1115039D03*
X1449404D03*
X1458653Y1131060D03*
X1454953D03*
X1453103Y1140973D03*
X1451253Y1131060D03*
X1449403Y1134264D03*
X1460503Y1140973D03*
X1469321Y841467D03*
X1461921D03*
X1476721D03*
X1474871Y851380D03*
X1471171D03*
X1467471D03*
X1463771D03*
X1461921Y854584D03*
X1474871Y864197D03*
X1471171D03*
X1469321Y854584D03*
X1467471Y864197D03*
X1463771D03*
X1476721Y854584D03*
X1461921Y867401D03*
X1476721D03*
X1469321D03*
X1461921Y880219D03*
X1471171Y877014D03*
X1476721Y880219D03*
X1474871Y877014D03*
X1469321Y880219D03*
X1467471Y877014D03*
X1463771D03*
X1474871Y889832D03*
X1465621Y893036D03*
X1476721D03*
X1474871Y896240D03*
X1471171Y889832D03*
X1467471D03*
X1463771D03*
X1473021Y899445D03*
X1465620D03*
X1461920Y905853D03*
X1473020Y912262D03*
X1471171Y909057D03*
X1465620Y905853D03*
X1471171Y902649D03*
X1469321Y905853D03*
X1474870Y915466D03*
X1461920Y925079D03*
X1471170Y928283D03*
X1469321Y925079D03*
X1465620D03*
Y918670D03*
X1473021D03*
X1471171Y921875D03*
X1473020Y931488D03*
X1465620D03*
X1461920Y944304D03*
X1474871Y934691D03*
X1473021Y937896D03*
X1471171Y941100D03*
X1469321Y944304D03*
X1465620D03*
Y937896D03*
X1471170Y947509D03*
X1474871Y953917D03*
X1473021Y957122D03*
X1471171Y960326D03*
X1465620Y957122D03*
Y950713D03*
X1473020D03*
X1461920Y963530D03*
X1476721D03*
X1471170Y966735D03*
X1469321Y963530D03*
X1465620D03*
X1473021Y976347D03*
X1473020Y969939D03*
X1465620Y976347D03*
Y969939D03*
X1474870Y973143D03*
X1471171Y979552D03*
X1461920Y982756D03*
X1469321D03*
X1465620D03*
X1475303Y1006093D03*
X1473453Y1009297D03*
X1473454Y1002888D03*
X1471604Y999684D03*
X1466053Y1009297D03*
X1466054Y1002888D03*
X1467903Y1006093D03*
X1464204D03*
X1471603Y1012501D03*
X1462353Y1015705D03*
X1473453Y1028523D03*
X1466053D03*
Y1022114D03*
Y1015705D03*
X1477154D03*
X1475303Y1025318D03*
X1473453Y1022114D03*
X1471604Y1018910D03*
X1469754Y1015705D03*
X1471603Y1031727D03*
X1462353Y1034931D03*
X1473454Y1041340D03*
X1466053D03*
Y1034931D03*
X1475303Y1044544D03*
X1471604Y1038136D03*
X1469754Y1034931D03*
X1466053Y1047749D03*
X1473453D03*
X1462353Y1054157D03*
X1473453Y1060565D03*
X1471604Y1057361D03*
X1466053Y1060565D03*
Y1054157D03*
X1471603Y1050952D03*
X1469753Y1054157D03*
X1475304Y1063770D03*
X1462353Y1073383D03*
X1471604Y1076587D03*
X1469754Y1073383D03*
X1466053Y1066974D03*
X1473453D03*
X1471603Y1070178D03*
X1466053Y1073383D03*
X1473454Y1079791D03*
X1466053D03*
X1462353Y1092608D03*
X1475303Y1082995D03*
X1473453Y1086200D03*
X1469754Y1092608D03*
X1466053D03*
Y1086200D03*
X1471603Y1089404D03*
X1475304Y1095813D03*
X1471604D03*
X1467904D03*
X1462353Y1105426D03*
X1462354Y1099017D03*
X1475303Y1108630D03*
Y1102221D03*
X1473454Y1105426D03*
X1469753D03*
X1467904Y1102221D03*
X1464203D03*
X1473454Y1111834D03*
X1466053D03*
Y1099017D03*
X1471604Y1102221D03*
X1477153Y1099017D03*
X1469753D03*
X1473453D03*
X1466053Y1105426D03*
X1462353Y1111834D03*
X1467904Y1108630D03*
X1464204D03*
X1462353Y1118243D03*
X1477153D03*
X1475303Y1115039D03*
X1473453Y1118243D03*
X1471604Y1121447D03*
X1469754Y1118243D03*
X1466053D03*
X1475303Y1127856D03*
X1467903D03*
X1467904Y1115039D03*
X1471604D03*
X1462353Y1131060D03*
X1477153D03*
X1475303Y1140973D03*
X1473453Y1131060D03*
X1469753D03*
X1466053D03*
X1467903Y1140973D03*
X1491521Y841467D03*
X1484121D03*
X1478571Y851380D03*
X1482271D03*
X1489671D03*
X1485971D03*
X1493371D03*
X1478571Y864197D03*
X1491521Y854584D03*
X1489671Y864197D03*
X1485971D03*
X1482271D03*
X1493371D03*
X1491521Y867401D03*
X1484121D03*
Y854584D03*
X1478571Y877014D03*
X1491521Y880219D03*
X1485971Y877014D03*
X1484121Y880219D03*
X1489671Y877014D03*
X1482271D03*
X1493371D03*
X1478570Y896240D03*
X1478571Y889832D03*
X1491521Y893036D03*
X1482271Y889832D03*
X1489671D03*
X1485971D03*
X1482270Y896240D03*
X1480421Y893036D03*
X1493371Y889832D03*
X1491520Y899445D03*
X1484120D03*
X1478571Y909057D03*
Y902649D03*
X1491520Y912262D03*
X1487820Y905853D03*
X1485971Y909057D03*
X1484121Y912262D03*
X1491520Y905853D03*
X1485970Y902649D03*
X1478571Y915466D03*
X1482271D03*
X1478571Y928283D03*
Y921875D03*
X1491520Y925079D03*
Y918670D03*
X1487820Y925079D03*
X1485971Y928283D03*
X1485970Y921875D03*
X1484120Y918670D03*
X1491520Y931488D03*
X1484121D03*
X1478571Y941100D03*
Y934691D03*
X1491520Y944304D03*
Y937896D03*
X1487820Y944304D03*
X1485970Y941100D03*
X1482271Y934691D03*
X1478571Y947509D03*
Y960326D03*
Y953917D03*
X1491520Y957122D03*
Y950713D03*
X1485970Y960326D03*
X1484120Y957122D03*
X1482271Y953917D03*
X1484121Y950713D03*
X1478570Y966735D03*
X1491520Y963530D03*
X1485971Y966735D03*
X1487820Y963530D03*
X1480420D03*
X1478571Y979552D03*
Y973143D03*
X1491521Y976347D03*
X1491520Y969939D03*
X1484120Y976347D03*
X1484121Y969939D03*
X1489671Y973143D03*
X1485970Y979552D03*
X1482271Y973143D03*
X1493370D03*
X1491520Y982756D03*
X1487820D03*
X1479004Y999684D03*
X1486403D03*
X1484553Y1002888D03*
X1482704Y1006093D03*
X1479003Y1012501D03*
X1486404D03*
X1491953Y1009297D03*
Y1002888D03*
X1484554Y1009297D03*
X1479004Y1025318D03*
Y1018910D03*
X1491953Y1028523D03*
Y1022114D03*
X1484553Y1028523D03*
X1486403Y1018910D03*
X1484553Y1022114D03*
X1482704Y1025318D03*
X1480853Y1015705D03*
X1479004Y1031727D03*
X1486404D03*
X1488253Y1015705D03*
X1491953D03*
X1479004Y1044544D03*
Y1038136D03*
X1491953Y1034931D03*
Y1041340D03*
X1488253Y1034931D03*
X1486403Y1038136D03*
X1484553Y1041340D03*
X1482704Y1044544D03*
X1491953Y1047749D03*
X1484553D03*
X1479004Y1057361D03*
Y1050952D03*
X1491953Y1054157D03*
X1486404Y1057361D03*
X1484553Y1060565D03*
X1488253Y1054157D03*
X1486404Y1050952D03*
X1491953Y1060565D03*
X1479004Y1063770D03*
X1482704D03*
X1479004Y1076587D03*
Y1070178D03*
X1486404Y1076587D03*
Y1070178D03*
X1488253Y1073383D03*
X1484553Y1066974D03*
X1491953Y1073383D03*
Y1066974D03*
X1484553Y1079791D03*
X1491953D03*
X1479004Y1089404D03*
Y1082995D03*
X1488254Y1092608D03*
X1486404Y1089404D03*
X1484554Y1086200D03*
X1482704Y1082995D03*
X1491954Y1092608D03*
X1479004Y1095813D03*
X1490103D03*
X1493804D03*
X1479004Y1102221D03*
X1490104Y1108630D03*
Y1102221D03*
X1488254Y1099017D03*
X1484553D03*
X1482704Y1108630D03*
X1480853Y1099017D03*
X1491953Y1105426D03*
Y1111834D03*
X1493804Y1108630D03*
X1490103Y1115039D03*
X1488253Y1118243D03*
X1484553D03*
X1480853D03*
X1486403Y1115039D03*
X1491953Y1118243D03*
X1490103Y1127856D03*
X1482703D03*
X1493804Y1115039D03*
X1490103Y1140973D03*
X1488253Y1131060D03*
X1484553D03*
X1480853D03*
X1482703Y1140973D03*
X1491953Y1131060D03*
X1504471Y844671D03*
X1498921Y841467D03*
X1508171Y851380D03*
X1504471D03*
X1500771D03*
X1497071D03*
X1504471Y864197D03*
X1500771D03*
X1508170Y857789D03*
X1497071Y864197D03*
X1506321Y860993D03*
Y854584D03*
X1498921D03*
X1510021Y860993D03*
X1506320Y867401D03*
X1498921D03*
X1510021D03*
X1504471Y877014D03*
X1498921Y880219D03*
X1508171Y877014D03*
X1497071D03*
X1506321Y880219D03*
X1500771Y877014D03*
X1510021Y880219D03*
Y873810D03*
X1508170Y883423D03*
X1508171Y889832D03*
X1504471Y896240D03*
Y889832D03*
X1500771D03*
X1508171Y896240D03*
X1502621Y893036D03*
X1500771Y896240D03*
X1497071Y889832D03*
X1510021Y893036D03*
X1498921Y899445D03*
X1510021D03*
X1495221Y905853D03*
X1504471Y902649D03*
X1498920Y912262D03*
X1497070Y909057D03*
X1497071Y902649D03*
X1508171Y915466D03*
X1504471D03*
X1500770D03*
X1504471Y909057D03*
X1510021Y912262D03*
X1495221Y925079D03*
X1504471Y921875D03*
X1497070Y928283D03*
X1498921Y918670D03*
X1497071Y921875D03*
X1498920Y931488D03*
X1504471Y928283D03*
X1510021Y918670D03*
X1510020Y931488D03*
X1495221Y944304D03*
X1504471Y941100D03*
Y934691D03*
X1500770D03*
X1498921Y937896D03*
X1497071Y941100D03*
X1497070Y947509D03*
X1508171Y934691D03*
X1510021Y937896D03*
X1504471Y947509D03*
Y960326D03*
Y953917D03*
X1500771D03*
X1498921Y957122D03*
X1497071Y960326D03*
X1498920Y950713D03*
X1495221Y963530D03*
X1497070Y966735D03*
X1502621Y963530D03*
X1510021Y957122D03*
X1508171Y953917D03*
X1510021Y950713D03*
X1506320Y963530D03*
X1504471Y966735D03*
Y979552D03*
Y973143D03*
X1498921Y976347D03*
X1498920Y969939D03*
X1500770Y973143D03*
X1497071Y979552D03*
X1510021Y976347D03*
X1495221Y982756D03*
X1510043Y980606D03*
X1510021Y969939D03*
X1508171Y973143D03*
X1497503Y1012501D03*
Y999684D03*
X1504904Y1006093D03*
Y999684D03*
X1501203Y1006093D03*
X1499353Y1009297D03*
X1499354Y1002888D03*
X1510453Y1009297D03*
Y1002888D03*
X1508603Y1006093D03*
X1504903Y1012501D03*
X1504904Y1025318D03*
X1499353Y1028523D03*
X1501203Y1025318D03*
X1504904Y1031727D03*
X1497503D03*
X1495654Y1015705D03*
X1497504Y1018910D03*
X1499353Y1022114D03*
X1503054Y1015705D03*
X1504904Y1018910D03*
X1506753Y1015705D03*
X1510453Y1028523D03*
X1510452Y1022114D03*
X1508603Y1025318D03*
X1504904Y1044544D03*
X1501203D03*
X1499354Y1041340D03*
X1497504Y1038136D03*
X1495654Y1034931D03*
X1508604Y1044544D03*
X1499353Y1047749D03*
X1504904Y1038136D03*
X1510453Y1041340D03*
Y1047749D03*
X1504904Y1057361D03*
Y1050952D03*
X1499354Y1060565D03*
X1497504Y1057361D03*
X1497503Y1050952D03*
X1495654Y1054157D03*
X1504904Y1063770D03*
X1501203D03*
X1510453Y1060565D03*
X1508604Y1063770D03*
X1504904Y1076587D03*
Y1070178D03*
X1497504Y1076587D03*
X1497503Y1070178D03*
X1495654Y1073383D03*
X1499353Y1066974D03*
X1499354Y1079791D03*
X1510453Y1066974D03*
Y1079791D03*
X1499353Y1086200D03*
X1497503Y1089404D03*
X1495653Y1092608D03*
X1504904Y1089404D03*
Y1082995D03*
X1501203D03*
X1508604Y1082996D03*
X1510453Y1086200D03*
X1504903Y1095813D03*
X1503053Y1105426D03*
X1497503Y1102221D03*
X1495653Y1105426D03*
X1495654Y1099017D03*
X1508603Y1108630D03*
X1506754Y1111834D03*
X1499353D03*
X1503053Y1099017D03*
X1510453D03*
X1508602Y1102221D03*
X1497504Y1108630D03*
X1501204D03*
X1510453Y1111834D03*
X1499353Y1105426D03*
X1510453D03*
X1504904Y1108630D03*
X1495653Y1111834D03*
X1503053D03*
X1506753Y1124651D03*
Y1118243D03*
X1504904Y1121447D03*
X1499353Y1118243D03*
X1497503Y1115039D03*
X1495653Y1118243D03*
X1508603Y1115039D03*
X1504904Y1127856D03*
X1497503D03*
X1501204Y1115039D03*
X1504904D03*
X1506754Y1137469D03*
X1506753Y1131060D03*
X1503053D03*
X1499353D03*
X1495653D03*
X1504904Y1134264D03*
X1497503Y1140973D03*
X1510453Y1131060D03*
X1511871Y844671D03*
X1513722Y848176D03*
X1511871Y851380D03*
X1521121Y860993D03*
Y854584D03*
X1515570Y864197D03*
X1513721Y854584D03*
Y860993D03*
X1521121Y867401D03*
X1517421D03*
X1513721D03*
X1511871Y870606D03*
X1522971D03*
X1517421Y873810D03*
X1511871Y883423D03*
X1517421Y880219D03*
X1522971Y883423D03*
X1511871Y889832D03*
X1513721Y893036D03*
X1517421Y886627D03*
X1521121D03*
X1513721D03*
X1526671Y889832D03*
X1513721Y899445D03*
X1524821Y912262D03*
X1511871Y909057D03*
Y902649D03*
X1513721Y912262D03*
X1515571Y909057D03*
X1524821Y905853D03*
X1513721D03*
X1519271Y909057D03*
X1511871Y921875D03*
X1513721Y918670D03*
X1524820Y931488D03*
X1513720D03*
X1511871Y941100D03*
X1513721Y937896D03*
X1511871Y947509D03*
X1519271D03*
X1515571D03*
X1511871Y960326D03*
X1513721Y957122D03*
Y950713D03*
X1511871Y966735D03*
X1513721Y963530D03*
X1515571Y979552D03*
X1513721Y982756D03*
X1511871Y973143D03*
X1517421Y969939D03*
X1515571Y973143D03*
X1516004Y1006092D03*
X1516003Y999684D03*
X1512303D03*
Y1006093D03*
X1519705Y1006092D03*
X1525396Y1000648D03*
X1512303Y1012501D03*
Y1025318D03*
X1516003Y1018910D03*
X1517854Y1015705D03*
X1525254D03*
X1521554D03*
X1514154D03*
X1512303Y1018910D03*
Y1031727D03*
X1525254Y1034931D03*
X1521554D03*
X1516004Y1044544D03*
X1516003Y1038136D03*
X1517853Y1034931D03*
X1514153D03*
X1512303Y1038136D03*
X1517853Y1054157D03*
X1514153D03*
X1512303Y1057361D03*
X1521553Y1054157D03*
X1514153Y1060565D03*
X1512303Y1050952D03*
X1525564Y1064850D03*
X1523404Y1070178D03*
X1514153Y1066974D03*
X1517853Y1073383D03*
X1521553Y1066974D03*
X1516003Y1076587D03*
X1512303D03*
X1512304Y1070178D03*
X1514153Y1073383D03*
X1523404Y1082996D03*
X1512304D03*
X1514153Y1092608D03*
X1512303Y1089404D03*
X1521553Y1092608D03*
X1523403Y1095813D03*
X1519703D03*
X1512303D03*
X1521554Y1105426D03*
X1517853D03*
X1516003Y1108630D03*
Y1102221D03*
X1512303D03*
X1517853Y1111834D03*
X1521553D03*
X1514153Y1105426D03*
X1512303Y1108630D03*
X1514153Y1111834D03*
X1519703Y1108630D03*
X1521553Y1124651D03*
Y1118243D03*
X1519704Y1115039D03*
X1516004D03*
X1514153Y1124651D03*
X1512303Y1115039D03*
X1517854Y1131560D03*
X1512304Y1134264D03*
X1527571Y979057D03*
X1526843Y972608D03*
X1527103Y1031726D03*
X1665141Y1051247D03*
X1724541D03*
G54D43*
X333834Y1062790D03*
X329632Y1092168D03*
X335344Y1097289D03*
X549719Y962436D03*
X548146Y965640D03*
X543729Y984866D03*
X1309976Y1062790D03*
X1305774Y1092168D03*
X1311486Y1097289D03*
X1337102Y206675D03*
X1525861Y962436D03*
X1524288Y965640D03*
X1519871Y984866D03*
X1879155Y468898D03*
Y716798D03*
X1889155Y468898D03*
Y716798D03*
X1900275Y840758D03*
X1910275D03*
X1921395Y-19332D03*
X1931395D03*
X1942395Y593048D03*
X1952395D03*
X1963362Y-19190D03*
X1973362D03*
X1984482Y593020D03*
X1994482D03*
X2005452Y-19180D03*
X2015452D03*
X2026452Y593200D03*
X2047419Y-19038D03*
X2036452Y593200D03*
X2057419Y-19038D03*
X2068539Y593172D03*
X2078539D03*
G54D52*
X717313Y-27626D03*
Y-21471D03*
Y-17597D03*
X717298Y-15082D03*
X717313Y-11442D03*
X717298Y-25111D03*
X717313Y-7568D03*
X717298Y-5053D03*
X834273Y2374D03*
X834258Y4889D03*
X834273Y22432D03*
Y8529D03*
Y12403D03*
X834258Y14918D03*
X834273Y18558D03*
X834258Y24947D03*
X1026705Y-27695D03*
Y-38224D03*
X1023437Y-38210D03*
X1026690Y-35709D03*
X1023422Y-35695D03*
X1026705Y-32069D03*
Y-17666D03*
X1026690Y-15151D03*
X1026705Y-11511D03*
X1026690Y-25180D03*
X1026705Y-21540D03*
X1026690Y4907D03*
X1026705Y2392D03*
X1026690Y-5122D03*
X1026705Y-7637D03*
Y-1482D03*
Y22450D03*
Y18576D03*
Y8547D03*
X1026690Y14936D03*
X1026705Y12421D03*
X1026690Y24965D03*
X1336024Y-27695D03*
Y-32069D03*
X1332741Y-35695D03*
X1336009Y-35709D03*
X1332756Y-38210D03*
X1336024Y-38224D03*
Y-11511D03*
X1336009Y-15151D03*
X1336024Y-17666D03*
Y-21540D03*
X1336009Y-25180D03*
X1336024Y2392D03*
X1336009Y4907D03*
X1336024Y-1482D03*
Y-7637D03*
X1336009Y-5122D03*
X1336024Y18576D03*
Y22450D03*
Y12421D03*
X1336009Y14936D03*
X1336024Y8547D03*
X1336009Y24965D03*
G54D62*
X918780Y1684890D03*
Y1694890D03*
Y1714890D03*
X928780Y1684890D03*
X938780D03*
X928780Y1694890D03*
X938780D03*
X928780Y1704890D03*
X938780D03*
X928780Y1714890D03*
X938780D03*
G54D72*
X1879155Y354948D03*
Y458898D03*
Y478898D03*
Y582848D03*
Y602848D03*
Y706798D03*
Y726798D03*
Y830748D03*
X1900275Y-9342D03*
X1889155Y354948D03*
Y458898D03*
Y478898D03*
X1900275Y582858D03*
X1889155Y582848D03*
Y602848D03*
Y706798D03*
X1900275Y726808D03*
X1889155Y726798D03*
X1900275Y830758D03*
X1889155Y830748D03*
X1900275Y850758D03*
Y954708D03*
X1910275Y-9342D03*
Y582858D03*
Y726808D03*
Y830758D03*
Y850758D03*
Y954708D03*
X1921395Y-9332D03*
X1931395D03*
Y582868D03*
X1921395D03*
X1931395Y602868D03*
X1921395D03*
Y1195068D03*
X1931395D03*
X1942395Y-9152D03*
Y583048D03*
Y603048D03*
Y1195248D03*
X1963362Y-9190D03*
X1952395Y-9152D03*
X1963362Y583010D03*
X1952395Y583048D03*
X1963362Y603010D03*
X1952395Y603048D03*
X1963362Y1195210D03*
X1952395Y1195248D03*
X1973362Y-9190D03*
Y583010D03*
Y603010D03*
Y1195210D03*
X1994482Y-9180D03*
X1984482D03*
Y583020D03*
X1994482D03*
X1984482Y603020D03*
X1994482D03*
Y1195220D03*
X1984482D03*
X2005452Y-9180D03*
X2015452D03*
Y583020D03*
X2005452D03*
X2015452Y603020D03*
X2005452D03*
Y1195220D03*
X2015452D03*
X2026452Y-9000D03*
Y583200D03*
Y603200D03*
Y1195400D03*
X2047419Y-9038D03*
X2036452Y-9000D03*
X2047419Y583162D03*
X2036452Y583200D03*
X2047419Y603162D03*
X2036452Y603200D03*
X2047419Y1195362D03*
X2036452Y1195400D03*
X2057419Y-9038D03*
Y583162D03*
Y603162D03*
Y1195362D03*
X2068539Y603172D03*
X2078539D03*
Y1195372D03*
X2068539D03*
G54D73*
X1879155Y468898D03*
Y716798D03*
X1889155Y468898D03*
X1900275Y592858D03*
X1889155Y716798D03*
X1900275Y840758D03*
X1910275Y592858D03*
Y840758D03*
X1921395Y1205068D03*
X1931395D03*
X1942395Y593048D03*
X1952395D03*
X1963362Y1205210D03*
X1984482Y593020D03*
X1973362Y1205210D03*
X1994482Y593020D03*
X2005452Y1205220D03*
X2015452D03*
X2026452Y593200D03*
X2036452D03*
X2047419Y1205362D03*
X2057419D03*
G54D49*
X676508Y224606D03*
G54D24*
X36399Y960892D03*
Y957546D03*
Y967585D03*
X52541Y964239D03*
X66099Y816995D03*
Y810302D03*
Y833727D03*
Y823688D03*
Y827034D03*
Y840420D03*
Y960892D03*
Y957546D03*
Y967585D03*
Y1221916D03*
Y1215223D03*
Y1238648D03*
Y1228609D03*
Y1231955D03*
Y1245341D03*
X82241Y813648D03*
Y806955D03*
Y820341D03*
Y830381D03*
Y823688D03*
Y837074D03*
Y964239D03*
Y1218570D03*
Y1211877D03*
Y1225263D03*
Y1241995D03*
Y1235302D03*
Y1228609D03*
X95799Y960892D03*
Y957546D03*
Y967585D03*
Y1054593D03*
X125499Y780184D03*
Y773491D03*
Y786877D03*
Y803609D03*
Y796916D03*
Y790223D03*
Y816995D03*
Y810302D03*
Y833727D03*
Y823688D03*
Y827034D03*
Y847113D03*
Y840420D03*
Y853806D03*
Y860499D03*
Y863845D03*
Y883924D03*
Y877231D03*
Y870538D03*
Y890617D03*
Y897310D03*
Y900656D03*
Y914042D03*
Y907349D03*
Y927428D03*
Y920735D03*
Y934121D03*
Y944160D03*
Y937467D03*
Y960892D03*
Y950853D03*
X111941Y964239D03*
X125499Y957546D03*
Y980971D03*
Y974278D03*
Y967585D03*
Y994357D03*
Y987664D03*
X111941Y1021129D03*
Y1024475D03*
X125499Y1027822D03*
Y1021129D03*
Y1047900D03*
Y1041207D03*
Y1034515D03*
X111941Y1051247D03*
X125499Y1054593D03*
Y1074672D03*
Y1067979D03*
Y1091404D03*
Y1081365D03*
Y1084711D03*
Y1098097D03*
Y1111483D03*
Y1104790D03*
Y1128215D03*
Y1118176D03*
Y1121522D03*
Y1141601D03*
Y1134908D03*
Y1148294D03*
Y1154987D03*
Y1158333D03*
Y1171719D03*
Y1165026D03*
Y1185105D03*
Y1178412D03*
Y1191798D03*
Y1208530D03*
Y1201837D03*
Y1195144D03*
Y1221916D03*
Y1215223D03*
Y1238648D03*
Y1228609D03*
Y1231955D03*
Y1245341D03*
X141641Y770144D03*
Y776837D03*
Y786877D03*
Y783530D03*
Y800263D03*
Y793570D03*
Y813648D03*
Y806955D03*
Y820341D03*
Y830381D03*
Y823688D03*
Y850459D03*
Y843766D03*
Y837074D03*
Y867192D03*
Y860499D03*
Y857152D03*
Y873885D03*
Y880577D03*
Y887270D03*
Y897310D03*
Y893963D03*
Y917389D03*
Y910696D03*
Y904003D03*
Y924081D03*
Y934121D03*
Y930774D03*
Y947507D03*
Y940814D03*
Y964239D03*
Y977625D03*
Y970932D03*
Y991011D03*
Y984318D03*
Y1021129D03*
Y1024475D03*
Y1031168D03*
Y1044554D03*
Y1037861D03*
Y1051247D03*
Y1071326D03*
Y1064633D03*
Y1078018D03*
Y1094751D03*
Y1088058D03*
Y1081365D03*
Y1108137D03*
Y1101444D03*
Y1124869D03*
Y1118176D03*
Y1114829D03*
Y1144948D03*
Y1138255D03*
Y1131562D03*
Y1161680D03*
Y1154987D03*
Y1151641D03*
Y1175066D03*
Y1168373D03*
Y1181759D03*
Y1191798D03*
Y1188452D03*
Y1205184D03*
Y1198491D03*
Y1218570D03*
Y1211877D03*
Y1225263D03*
Y1241995D03*
Y1235302D03*
Y1228609D03*
X155199Y960892D03*
Y957546D03*
Y967585D03*
Y1054593D03*
X171341Y964239D03*
Y1021129D03*
Y1024475D03*
Y1051247D03*
X184899Y780184D03*
Y773491D03*
Y786877D03*
Y803609D03*
Y796916D03*
Y790223D03*
Y816995D03*
Y810302D03*
Y833727D03*
Y823688D03*
Y827034D03*
Y847113D03*
Y840420D03*
Y853806D03*
Y860499D03*
Y863845D03*
Y883924D03*
Y877231D03*
Y870538D03*
Y890617D03*
Y897310D03*
Y900656D03*
Y914042D03*
Y907349D03*
Y927428D03*
Y920735D03*
Y934121D03*
Y944160D03*
Y937467D03*
Y960892D03*
Y950853D03*
Y957546D03*
Y980971D03*
Y974278D03*
Y967585D03*
Y994357D03*
Y987664D03*
Y1027822D03*
Y1021129D03*
Y1047900D03*
Y1041207D03*
Y1034515D03*
Y1054593D03*
Y1074672D03*
Y1067979D03*
Y1091404D03*
Y1081365D03*
Y1084711D03*
Y1098097D03*
Y1111483D03*
Y1104790D03*
Y1128215D03*
Y1118176D03*
Y1121522D03*
Y1141601D03*
Y1134908D03*
Y1148294D03*
Y1154987D03*
Y1158333D03*
Y1171719D03*
Y1165026D03*
Y1185105D03*
Y1178412D03*
Y1191798D03*
Y1208530D03*
Y1201837D03*
Y1195144D03*
Y1221916D03*
Y1215223D03*
Y1238648D03*
Y1228609D03*
Y1231955D03*
Y1245341D03*
X201041Y770144D03*
Y776837D03*
Y786877D03*
Y783530D03*
Y800263D03*
Y793570D03*
Y813648D03*
Y806955D03*
Y820341D03*
Y830381D03*
Y823688D03*
Y850459D03*
Y843766D03*
Y837074D03*
Y867192D03*
Y860499D03*
Y857152D03*
Y873885D03*
Y880577D03*
Y887270D03*
Y897310D03*
Y893963D03*
Y917389D03*
Y910696D03*
Y904003D03*
Y924081D03*
Y934121D03*
Y930774D03*
Y947507D03*
Y940814D03*
Y964239D03*
Y977625D03*
Y970932D03*
Y991011D03*
Y984318D03*
X201141Y1021129D03*
Y1024475D03*
Y1031168D03*
Y1044554D03*
Y1037861D03*
Y1051247D03*
Y1071326D03*
Y1064633D03*
Y1078018D03*
Y1094752D03*
Y1088059D03*
Y1081366D03*
Y1108137D03*
Y1101444D03*
X201041Y1124869D03*
X201141Y1118177D03*
Y1114830D03*
Y1144948D03*
Y1138255D03*
X201041Y1131562D03*
X201141Y1161680D03*
Y1154988D03*
Y1151641D03*
Y1175066D03*
Y1168373D03*
Y1181759D03*
Y1191799D03*
Y1188452D03*
Y1205184D03*
Y1198491D03*
Y1218570D03*
Y1211877D03*
Y1225263D03*
Y1241995D03*
Y1235302D03*
Y1228609D03*
X214599Y960892D03*
Y957546D03*
X244299Y883924D03*
Y890617D03*
Y897310D03*
Y900656D03*
Y914042D03*
Y907349D03*
Y960892D03*
Y957546D03*
Y1185105D03*
Y1178412D03*
Y1191798D03*
Y1208530D03*
Y1201837D03*
Y1195144D03*
X260441Y880577D03*
Y887270D03*
Y897310D03*
Y893963D03*
Y910696D03*
Y904003D03*
Y1175066D03*
Y1181759D03*
Y1191798D03*
Y1188452D03*
Y1205184D03*
Y1198491D03*
X337779Y880219D03*
X335928Y883423D03*
X337779Y893036D03*
X335928Y889832D03*
X334079Y886627D03*
X337779D03*
X350727Y851380D03*
X354427Y844971D03*
X348878Y848176D03*
X352578D03*
X350729Y857789D03*
X352578Y860993D03*
X354429Y857789D03*
X341479Y880219D03*
X343329Y883423D03*
X348878Y899445D03*
Y893036D03*
X350729Y889832D03*
X354429D03*
X341478Y893036D03*
X343328Y889832D03*
X347029Y896240D03*
X354429D03*
X341479Y886627D03*
X350729Y896240D03*
X345179Y886627D03*
X348878Y912262D03*
X350729Y909057D03*
X354429D03*
X350729Y902649D03*
X354429D03*
X347029Y915466D03*
X354429D03*
X350729D03*
X348879Y931488D03*
X350729Y928283D03*
X354429D03*
Y921875D03*
X350729D03*
X348878Y918670D03*
X350729Y941100D03*
X348878Y937896D03*
X354429Y941100D03*
X347029Y934691D03*
X354429D03*
X350729D03*
Y947509D03*
X354429D03*
X348878Y950713D03*
X350729Y960326D03*
X348878Y957122D03*
X354429Y960326D03*
X350729Y966735D03*
X354429D03*
X350729Y953917D03*
X354429D03*
X347030D03*
X350729Y979552D03*
X354429D03*
X348878Y976347D03*
X347029Y973143D03*
X348878Y969939D03*
X347461Y1006093D03*
X349311Y1002888D03*
X351161Y999684D03*
X354861D03*
X351161Y1012501D03*
X349311Y1009297D03*
X354861Y1012501D03*
X351162Y1031727D03*
X349311Y1028523D03*
X354861Y1031727D03*
X349311Y1022114D03*
X351161Y1018910D03*
X354861D03*
X347461Y1025318D03*
X354862D03*
X351162D03*
X349311Y1047749D03*
Y1041340D03*
X351161Y1038136D03*
X354861D03*
X347461Y1044544D03*
X354861D03*
X351161D03*
X349311Y1060565D03*
X351161Y1057361D03*
X354861D03*
X347461Y1063770D03*
X351161D03*
X354861D03*
X351161Y1050952D03*
X354861D03*
Y1070178D03*
X351162D03*
X349311Y1066974D03*
Y1079791D03*
X351161Y1076587D03*
X354861D03*
X351161Y1089404D03*
X349311Y1086200D03*
X354861Y1089404D03*
X347461Y1082995D03*
X354861D03*
X351161D03*
X341911Y1105426D03*
X343762Y1108630D03*
X345611Y1111834D03*
X351161Y1102221D03*
X349312Y1111834D03*
X353011Y1105426D03*
X345611D03*
X341912Y1111834D03*
X354861Y1102221D03*
X353012Y1111834D03*
X351162Y1108630D03*
X353011Y1124651D03*
X354861Y1127856D03*
X347461Y1115039D03*
X349312Y1137469D03*
X351161Y1134264D03*
X356279Y841467D03*
X361827Y844971D03*
X363679Y841467D03*
X369227Y844971D03*
X371079Y841467D03*
X358127Y844971D03*
X359978Y848176D03*
X365527Y844971D03*
X367378Y848176D03*
X356278Y854584D03*
X358129Y857789D03*
X363678Y854584D03*
X365529Y857789D03*
X371078Y854584D03*
X359978Y860993D03*
X361829Y857789D03*
X367378Y860993D03*
X369229Y857789D03*
X356278Y899445D03*
Y893036D03*
X358129Y896240D03*
X363678Y899445D03*
X367378D03*
X371078Y893036D03*
X356278Y912262D03*
X358129Y915466D03*
X363678Y912262D03*
X361829Y909057D03*
X367378Y912262D03*
X369229Y909057D03*
X361829Y902649D03*
X369229D03*
X359978Y905853D03*
X367378D03*
X363678D03*
X371078D03*
X356278Y931488D03*
X363678D03*
X356278Y918670D03*
X361829Y928283D03*
X367378Y931488D03*
X369229Y928283D03*
X361829Y921875D03*
X363678Y918670D03*
X369229Y921875D03*
X367378Y918670D03*
X359978Y925079D03*
X367378D03*
X363678D03*
X371078D03*
X356278Y937896D03*
X358129Y934691D03*
X361829Y941100D03*
X363678Y937896D03*
X369229Y941100D03*
X367378Y937896D03*
X361829Y947509D03*
X369229D03*
X367378Y944304D03*
X359978D03*
X371078D03*
X363678D03*
X356278Y950713D03*
Y957122D03*
X358129Y953917D03*
X361829Y966735D03*
X369229D03*
X359978Y963530D03*
X363678Y950713D03*
X367378D03*
X361829Y960326D03*
X363678Y957122D03*
X369229Y960326D03*
X367378Y957122D03*
X371078Y963530D03*
X359978Y982756D03*
X367378D03*
X363678D03*
X371078D03*
X369229Y979552D03*
X367378Y976347D03*
X361829Y979552D03*
X363678Y976347D03*
X356278D03*
Y969939D03*
X358129Y973143D03*
X363678Y969939D03*
X367378D03*
X358562Y1006093D03*
X356711Y1002888D03*
Y1009297D03*
X362262Y1012501D03*
X369662D03*
X364111Y1009297D03*
X367811D03*
X364111Y1002888D03*
X362262Y999684D03*
X371511Y1002888D03*
X369662Y999684D03*
X356711Y1028523D03*
Y1022114D03*
X362262Y1031727D03*
X364111Y1028523D03*
X369662Y1031727D03*
X367811Y1028523D03*
X358562Y1025318D03*
X360411Y1015705D03*
X371511D03*
X364111Y1022114D03*
X362262Y1018910D03*
X367811Y1022114D03*
X369662Y1018910D03*
X356711Y1047749D03*
Y1041340D03*
X364111D03*
X362262Y1038136D03*
X367811Y1041340D03*
X369662Y1038136D03*
X360411Y1034931D03*
X371511D03*
X364111D03*
X358562Y1044544D03*
X367811Y1034931D03*
X364111Y1047749D03*
X367811D03*
X356711Y1060565D03*
X358562Y1063770D03*
X364111Y1060565D03*
X362262Y1057361D03*
X367811Y1060565D03*
X369662Y1057361D03*
X362262Y1050952D03*
X369662D03*
X360411Y1054157D03*
X371511D03*
X364111D03*
X367811D03*
X356711Y1066974D03*
X367811Y1079791D03*
X369662Y1076587D03*
X362262Y1070178D03*
X364111Y1066974D03*
X369662Y1070178D03*
X367811Y1066974D03*
X356711Y1079791D03*
X364111D03*
X362262Y1076587D03*
X360411Y1073383D03*
X371511D03*
X364111D03*
X367811D03*
X356711Y1086200D03*
X358562Y1082995D03*
X362262Y1095813D03*
X369662D03*
X362262Y1089404D03*
X364111Y1086200D03*
X369662Y1089404D03*
X367811Y1086200D03*
X360411Y1092608D03*
X367811D03*
X364111D03*
X371511D03*
X364111Y1099017D03*
X367811D03*
X358561Y1121447D03*
X360412Y1124651D03*
X364111D03*
X367811D03*
X371511D03*
X356712D03*
X362262Y1127856D03*
X365962Y1121447D03*
X369662Y1127856D03*
X358561Y1134264D03*
X362261Y1140973D03*
X365962Y1134264D03*
X369661Y1140973D03*
X356712Y1137469D03*
X360412D03*
X364112D03*
X367812D03*
X371512D03*
X387727Y844971D03*
X376627D03*
X380327D03*
X384027D03*
X385879Y841467D03*
X372927Y844971D03*
X374778Y848176D03*
X378479Y841467D03*
X382178Y848176D03*
X387729Y857789D03*
X372929D03*
X378478Y854584D03*
X380329Y857789D03*
X384029D03*
X374778Y860993D03*
X376629Y857789D03*
X382178Y860993D03*
X385878Y854584D03*
X374778Y899445D03*
X382178D03*
Y893036D03*
X374778D03*
X385878D03*
X372929Y896240D03*
X380329D03*
X376629D03*
X384029D03*
X376629Y902649D03*
X380329D03*
X374778Y912262D03*
X376629Y909057D03*
X382178Y912262D03*
X380329Y909057D03*
X372929Y915466D03*
X380329D03*
X376629D03*
X384029D03*
X374778Y931488D03*
X376629Y928283D03*
X382178Y931488D03*
X380329Y928283D03*
X376629Y921875D03*
X374778Y918670D03*
X380329Y921875D03*
X382178Y918670D03*
X380329Y941100D03*
X382178Y937896D03*
X376629Y947509D03*
X380329D03*
X376629Y941100D03*
X374778Y937896D03*
X372929Y934691D03*
X380329D03*
X376629D03*
X384029D03*
X376629Y960326D03*
X374778Y957122D03*
X380329Y960326D03*
X382178Y957122D03*
X374778Y950713D03*
X382178D03*
X372929Y953917D03*
X380329D03*
X376629D03*
X384029D03*
X380329Y966735D03*
X376629D03*
X374778Y969939D03*
X382178D03*
X373362Y1006093D03*
X380762D03*
X377062D03*
X384462D03*
X375211Y1002888D03*
X377062Y999684D03*
X382611Y1002888D03*
X380762Y999684D03*
X377062Y1012501D03*
X375211Y1009297D03*
X380762Y1012501D03*
X382611Y1009297D03*
X377062Y1031727D03*
X375211Y1028523D03*
X380762Y1031727D03*
X382611Y1028523D03*
X375211Y1022114D03*
X377062Y1018910D03*
X382611Y1022114D03*
X380762Y1018910D03*
X377062Y1025318D03*
X384462D03*
X373360D03*
X380760D03*
X375211Y1047749D03*
X382611D03*
X375211Y1041340D03*
X377062Y1038136D03*
X382611Y1041340D03*
X380762Y1038136D03*
X373362Y1044544D03*
X380762D03*
X377062D03*
X384462D03*
X375211Y1060565D03*
X377062Y1057361D03*
X382611Y1060565D03*
X380762Y1057361D03*
X377062Y1050952D03*
X380762D03*
X373362Y1063770D03*
X384462D03*
X377062D03*
X380762D03*
Y1070178D03*
X382611Y1066974D03*
X377062Y1070178D03*
X375211Y1066974D03*
Y1079791D03*
X377062Y1076587D03*
X382611Y1079791D03*
X380762Y1076587D03*
X377062Y1089404D03*
X375211Y1086200D03*
X380762Y1089404D03*
X382611Y1086200D03*
X373362Y1082995D03*
X384462D03*
X377062D03*
X380762D03*
X386311Y1105426D03*
X382611Y1111834D03*
X375211Y1105426D03*
X377062Y1108630D03*
X380762Y1102221D03*
X378911Y1111834D03*
X384462Y1108630D03*
X386311Y1111834D03*
X378912Y1105426D03*
X375211Y1111834D03*
X382611Y1105426D03*
X375211Y1124651D03*
X378911D03*
X382611D03*
X386311D03*
X373362Y1121447D03*
X377062Y1127856D03*
X380762Y1121447D03*
X384462Y1127856D03*
X380762Y1115039D03*
X373362Y1134264D03*
X377061Y1140973D03*
X380762Y1134264D03*
X384461Y1140973D03*
X375212Y1137469D03*
X378912D03*
X382612D03*
X386312D03*
X391427Y844971D03*
X395127D03*
X398827D03*
X400679Y841467D03*
X389578Y848176D03*
X393279Y841467D03*
X396978Y848176D03*
X402527Y844971D03*
X393278Y854584D03*
X395129Y857789D03*
X400678Y854584D03*
X402529Y857789D03*
X389578Y860993D03*
X391429Y857789D03*
X396978Y860993D03*
X398829Y857789D03*
Y973143D03*
X400678Y976347D03*
X402529Y979552D03*
Y973143D03*
X390011Y1002888D03*
X388162Y999684D03*
X393711Y1002888D03*
X395562Y999684D03*
X402962Y1082995D03*
X402961Y1089404D03*
X390011Y1124651D03*
X395562Y1121447D03*
X397411Y1124651D03*
X401111D03*
X391862Y1127856D03*
X393711Y1124651D03*
X399262Y1127856D03*
X402962Y1121447D03*
X388162D03*
X391861Y1140973D03*
X395562Y1134264D03*
X399261Y1140973D03*
X402962Y1134264D03*
X388162D03*
X390012Y1137469D03*
X393712D03*
X397412D03*
X401112D03*
X406227Y844971D03*
X409927D03*
X413627D03*
X417327D03*
X404378Y848176D03*
X408079Y841467D03*
X411778Y848176D03*
X415479Y841467D03*
X419178Y848176D03*
X408078Y854584D03*
X409929Y857789D03*
X415478Y854584D03*
X417329Y857789D03*
X404378Y860993D03*
X406229Y857789D03*
X411778Y860993D03*
X413629Y857789D03*
X419178Y860993D03*
X417329Y883423D03*
X415478Y880219D03*
X413629Y883423D03*
X419178Y886627D03*
X408511Y1079791D03*
X406662Y1089404D03*
X410362D03*
X404811Y1086200D03*
X419611D03*
X414062Y1082995D03*
X410362D03*
X406662D03*
X408511Y1092608D03*
X414062Y1089404D03*
X419611Y1092608D03*
X412211Y1086200D03*
X404811Y1124651D03*
X408511D03*
X406662Y1127856D03*
X410362Y1121447D03*
X406661Y1140973D03*
X410362Y1134264D03*
X404812Y1137469D03*
X408512D03*
X421027Y844971D03*
X424727D03*
X428427D03*
X433978Y848176D03*
X435829Y844671D03*
X422879Y841467D03*
X426578Y848176D03*
X430278D03*
X422878Y854584D03*
X424729Y857789D03*
X430278Y854584D03*
X433979Y860993D03*
X421029Y857789D03*
X426578Y860993D03*
X428429Y857789D03*
X432129D03*
X435829D03*
X432129Y883423D03*
X430278Y880219D03*
X424729Y883423D03*
X422878Y880219D03*
X428429Y883423D03*
X421029D03*
X435829D03*
X433978Y886627D03*
X426578D03*
X421462Y1089404D03*
X423311Y1092608D03*
X427011D03*
X430710Y1086200D03*
X425162Y1082995D03*
Y1095813D03*
X430711Y1092608D03*
X423311Y1086200D03*
X428861Y1089404D03*
X427012Y1086200D03*
X450628Y844971D03*
X446927Y844671D03*
X452479Y841467D03*
X448778Y848176D03*
X443227Y844671D03*
X437678Y848176D03*
X437679Y854584D03*
X452478D03*
X450629Y857789D03*
X445078Y854584D03*
X443229Y857789D03*
X448779Y860993D03*
X446929Y857789D03*
X441378Y860993D03*
X452479Y880219D03*
X446929Y883423D03*
X445078Y880219D03*
X439529Y883423D03*
X437678Y880219D03*
X450629Y883423D03*
X443229D03*
X448778Y886627D03*
X441378D03*
X467279Y841467D03*
X463578Y848176D03*
X459879Y841467D03*
X458027Y844971D03*
X454327D03*
X469127D03*
X465427D03*
X461727D03*
X456178Y848176D03*
X467278Y854584D03*
X465429Y857789D03*
X459878Y854584D03*
X458029Y857789D03*
X469129D03*
X463578Y860993D03*
X461729Y857789D03*
X456178Y860993D03*
X454329Y857789D03*
X469129Y883423D03*
X467278Y880219D03*
X461729Y883423D03*
X459878Y880219D03*
X454329Y883423D03*
X465429D03*
X458029D03*
X463578Y886627D03*
X456178D03*
X483927Y844971D03*
X480227D03*
X476527D03*
X470978Y848176D03*
X482079Y841467D03*
X478378Y848176D03*
X474679Y841467D03*
X472827Y844971D03*
X482078Y854584D03*
X480229Y857789D03*
X474678Y854584D03*
X472829Y857789D03*
X483929D03*
X478378Y860993D03*
X476529Y857789D03*
X470978Y860993D03*
Y886627D03*
X484362Y1121447D03*
X480662Y1127856D03*
X476962Y1121447D03*
X473262Y1127856D03*
X469562Y1121447D03*
X482511Y1124651D03*
X478811D03*
X475111D03*
X471411D03*
X484362Y1134264D03*
X482512Y1137469D03*
X476962Y1134264D03*
X475112Y1137469D03*
X480661Y1140973D03*
X478812Y1137469D03*
X473261Y1140973D03*
X493178Y848176D03*
X489478Y841467D03*
X487627Y844971D03*
X500578Y848176D03*
X496878Y841467D03*
X495027Y844971D03*
X491327D03*
X485778Y848176D03*
X498727Y844971D03*
X489478Y854584D03*
X487629Y857789D03*
X500578Y860993D03*
X498729Y857789D03*
X495029D03*
X491329D03*
X485778Y860993D03*
X496878Y854584D03*
X493178Y860993D03*
X500578Y899445D03*
Y912262D03*
X498729Y909057D03*
Y902649D03*
X500578Y905853D03*
X496878D03*
X500578Y931488D03*
X498729Y921875D03*
X500578Y918670D03*
X498729Y928283D03*
X496878Y925079D03*
X500578D03*
X498729Y947509D03*
Y941100D03*
X500578Y937896D03*
X496878Y944304D03*
X500578D03*
Y950713D03*
Y957122D03*
X498729Y960326D03*
X487629Y979552D03*
X485778Y976347D03*
X491329Y979552D03*
X493178Y976347D03*
X500578Y982756D03*
X496878D03*
X498729Y979552D03*
X500578Y976347D03*
X501011Y1002888D03*
X499162Y999684D03*
Y1012501D03*
X501011Y1009297D03*
X497311Y1015705D03*
X499162Y1031727D03*
X501011Y1028523D03*
Y1022114D03*
X499162Y1018910D03*
X501011Y1041340D03*
X499162Y1038136D03*
X501011Y1047749D03*
Y1034931D03*
X497311D03*
X501011Y1060565D03*
X499162Y1057361D03*
Y1050952D03*
X501011Y1054157D03*
X497311D03*
X499162Y1070178D03*
X501011Y1066974D03*
Y1079791D03*
X499162Y1076587D03*
X497311Y1073383D03*
X501011D03*
X499162Y1089404D03*
X501011Y1086200D03*
X497311Y1092608D03*
X501011D03*
X488062Y1127856D03*
X499162Y1121447D03*
X495462Y1127856D03*
X491762Y1121447D03*
X489911Y1124651D03*
X486211D03*
X501011D03*
X497311D03*
X493611D03*
X493612Y1137469D03*
X488061Y1140973D03*
X501012Y1137469D03*
X495461Y1140973D03*
X491762Y1134264D03*
X489912Y1137469D03*
X486212D03*
X499162Y1134264D03*
X497312Y1137469D03*
X517227Y844971D03*
X511679Y841467D03*
X509827Y844971D03*
X504279Y841467D03*
X515378Y848176D03*
X513527Y844971D03*
X507978Y848176D03*
X506127Y844971D03*
X502427D03*
X517229Y857789D03*
X513529D03*
X509829D03*
X506129D03*
X515378Y860993D03*
X511678Y854584D03*
X507978Y860993D03*
X504278Y854584D03*
X502429Y857789D03*
X511678Y899445D03*
Y893036D03*
X507978D03*
X509829Y896240D03*
X517229D03*
X513529D03*
X504278Y899445D03*
X513529Y902649D03*
X517229D03*
X511678Y912262D03*
X513529Y909057D03*
X517229D03*
X513529Y915466D03*
X509829D03*
X517229D03*
X504278Y912262D03*
X506129Y909057D03*
Y902649D03*
X507978Y905853D03*
X504278D03*
X511678Y931488D03*
X513529Y928283D03*
X517229D03*
X506129D03*
Y921875D03*
X504278Y918670D03*
X513529Y921875D03*
X511678Y918670D03*
X517229Y921875D03*
X504278Y931488D03*
Y925079D03*
X507978D03*
X513529Y941100D03*
X511678Y937896D03*
X517229Y941100D03*
X513529Y934691D03*
X509829D03*
X517229D03*
X513529Y947509D03*
X517229D03*
X506129D03*
Y941100D03*
X504278Y937896D03*
X507978Y944304D03*
X504278D03*
X511678Y950713D03*
X513529Y960326D03*
X511678Y957122D03*
X517229Y960326D03*
Y966735D03*
X513529D03*
X504278Y950713D03*
X513529Y953917D03*
X517229D03*
X509829D03*
X504278Y957122D03*
X506129Y960326D03*
X507978Y982756D03*
X504278D03*
Y976347D03*
X506129Y979552D03*
X513529D03*
X517229D03*
X511678Y976347D03*
X509829Y973143D03*
X511678Y969939D03*
X517662Y1006093D03*
X513962D03*
X510262D03*
X517662Y1012501D03*
X504711Y1002888D03*
X506561Y999684D03*
X513962Y1012501D03*
X512111Y1009297D03*
X506562Y1012501D03*
X504711Y1009297D03*
X517661Y999684D03*
X512111Y1002888D03*
X513962Y999684D03*
Y1031727D03*
X512111Y1028523D03*
X517662Y1031727D03*
X512111Y1022114D03*
X513962Y1018910D03*
X517662D03*
X513962Y1025318D03*
X510262D03*
X517662D03*
X508411Y1015705D03*
X506562Y1031727D03*
X504711Y1028523D03*
Y1022114D03*
X506562Y1018910D03*
X504711Y1041340D03*
X506562Y1038136D03*
X512111Y1047749D03*
Y1041340D03*
X513962Y1038136D03*
X517662D03*
X504711Y1047749D03*
X510262Y1044544D03*
X508411Y1034931D03*
X513962Y1044544D03*
X517662D03*
X504711Y1034931D03*
X512111Y1060565D03*
X513962Y1057361D03*
X517662D03*
X510262Y1063770D03*
X513962D03*
X517662D03*
X513962Y1050952D03*
X517662D03*
X504711Y1060565D03*
X506562Y1057361D03*
Y1050952D03*
X508411Y1054157D03*
X504711D03*
X517662Y1070178D03*
X513962D03*
X512111Y1066974D03*
X504711Y1079791D03*
X506562Y1076587D03*
Y1070178D03*
X504711Y1066974D03*
X512111Y1079791D03*
X513962Y1076587D03*
X517662D03*
X508411Y1073383D03*
X504711D03*
X513962Y1089404D03*
X512111Y1086200D03*
X517662Y1089404D03*
X513962Y1082995D03*
X510262D03*
X517662D03*
X510262Y1095813D03*
X506561D03*
X506562Y1089404D03*
X504711Y1086200D03*
X508411Y1092608D03*
X504711D03*
X517662Y1102221D03*
X515811Y1099017D03*
X517662Y1127856D03*
X513962Y1121447D03*
X510262Y1127856D03*
X506562Y1121447D03*
X502862Y1127856D03*
X515811Y1124651D03*
X512111D03*
X508411D03*
X504711D03*
X517661Y1140973D03*
X513962Y1134264D03*
X512112Y1137469D03*
X506562Y1134264D03*
X504712Y1137469D03*
X515812D03*
X510261Y1140973D03*
X508412Y1137469D03*
X502861Y1140973D03*
X532028Y844671D03*
X526478Y848176D03*
X524627Y844971D03*
X519079Y841467D03*
X533878Y848176D03*
X530178D03*
X522778D03*
X520927Y844971D03*
X532029Y864197D03*
X533879Y854584D03*
X528329Y857789D03*
X522778Y860993D03*
X520929Y857789D03*
X526478Y854584D03*
X524629Y857789D03*
X519078Y854584D03*
X526479Y899445D03*
X530178D03*
X519078D03*
Y893036D03*
X522778D03*
X520929Y896240D03*
X530179Y912262D03*
X532029Y909057D03*
X524629Y902649D03*
X532029D03*
X526479Y912262D03*
X524629Y909057D03*
X526479Y905853D03*
X533879D03*
X522778D03*
X530179D03*
X519078Y912262D03*
X520929Y915466D03*
X526479Y931488D03*
X524629Y928283D03*
X530179Y931488D03*
X532029Y928283D03*
X524629Y921875D03*
X526479Y918670D03*
X532029Y921875D03*
X530179Y918670D03*
X526479Y925079D03*
X533879D03*
X522778D03*
X530179D03*
X519078Y931488D03*
Y918670D03*
X524629Y941100D03*
X526479Y937896D03*
X532029Y941100D03*
X530179Y937896D03*
X524629Y947509D03*
X532029D03*
X519078Y937896D03*
X533879Y944304D03*
X520929Y934691D03*
X526479Y944304D03*
X530178D03*
X522778D03*
X524629Y966735D03*
X532029D03*
X522778Y963530D03*
X526479Y950713D03*
X530178D03*
X532029Y960326D03*
X530178Y957122D03*
X524629Y960326D03*
X526479Y957122D03*
X533879Y963530D03*
X519078Y950713D03*
Y957122D03*
X520929Y953917D03*
X526479Y969939D03*
X530179D03*
X519078Y976347D03*
Y969939D03*
X520929Y973143D03*
X521362Y1006093D03*
X525062Y1012501D03*
X532461D03*
X526911Y1009297D03*
X530611D03*
X519511D03*
X519513Y1002888D03*
X530611D03*
X532461Y999684D03*
X526911Y1002888D03*
X525062Y999684D03*
X523211Y1015705D03*
X534311D03*
X525062Y1031727D03*
X526911Y1028523D03*
X532461Y1031727D03*
X530611Y1028523D03*
Y1022114D03*
X532461Y1018910D03*
X526911Y1022114D03*
X525062Y1018910D03*
X519511Y1028523D03*
Y1022114D03*
X521362Y1025318D03*
X526911Y1041340D03*
X525062Y1038136D03*
X530611Y1041340D03*
X532461Y1038136D03*
X526911Y1047749D03*
X530611D03*
X526911Y1034931D03*
X534311D03*
X523211D03*
X530611D03*
X519511Y1047749D03*
Y1041340D03*
X521362Y1044544D03*
X519511Y1060565D03*
X526911D03*
X525062Y1057361D03*
X530611Y1060565D03*
X532462Y1057361D03*
X525061Y1050952D03*
X532462Y1050953D03*
X523211Y1054157D03*
X521362Y1063770D03*
X534311Y1054157D03*
X526911D03*
X530611D03*
Y1079791D03*
X532462Y1076587D03*
X525062Y1070178D03*
X526911Y1066974D03*
X532462Y1070178D03*
X530611Y1066974D03*
X526911Y1079791D03*
X525062Y1076587D03*
X523211Y1073383D03*
X534311D03*
X526911D03*
X530611D03*
X519511Y1066974D03*
Y1079791D03*
X521362Y1095813D03*
X532461D03*
X525062D03*
Y1089404D03*
X526911Y1086200D03*
X532462Y1089404D03*
X530611Y1086200D03*
X526911Y1092608D03*
X534310D03*
X523211D03*
X530611D03*
X519511Y1086200D03*
X521362Y1082995D03*
X530611Y1099017D03*
X526911Y1124651D03*
X521362Y1121447D03*
X525062Y1127856D03*
X523211Y1124651D03*
X519511D03*
X532462Y1134264D03*
X525061Y1140973D03*
X523212Y1137469D03*
X534312D03*
X526912D03*
X521362Y1134264D03*
X519512Y1137469D03*
X543129Y851380D03*
X539429D03*
X535729Y864197D03*
X543128D03*
X546828D03*
X535729Y857789D03*
X543130D03*
X539429D03*
X541279Y860993D03*
Y854584D03*
X539429Y883423D03*
X537578Y880219D03*
X543129Y883423D03*
X544979Y880219D03*
X537578Y873810D03*
X539429Y870606D03*
X544979Y873810D03*
X543129Y870606D03*
X539428Y877014D03*
X546828D03*
X535729D03*
X543129D03*
X620799Y883924D03*
Y890617D03*
Y897310D03*
Y900656D03*
Y914042D03*
Y907349D03*
Y960892D03*
Y957546D03*
Y1185105D03*
Y1178412D03*
Y1191798D03*
Y1208530D03*
Y1201837D03*
Y1195144D03*
X636941Y880577D03*
Y887270D03*
Y897310D03*
Y893963D03*
Y910696D03*
Y904003D03*
Y1175066D03*
Y1181759D03*
Y1191798D03*
Y1188451D03*
Y1205184D03*
Y1198491D03*
X650499Y960892D03*
Y957546D03*
X680299Y780184D03*
Y773491D03*
Y786877D03*
Y803609D03*
Y796916D03*
Y790223D03*
Y816995D03*
Y810302D03*
Y833727D03*
Y823688D03*
Y827034D03*
Y847113D03*
Y840420D03*
Y853806D03*
Y860499D03*
Y863845D03*
Y883924D03*
Y877231D03*
Y870538D03*
Y890617D03*
Y897310D03*
Y900656D03*
Y914042D03*
Y907349D03*
Y927428D03*
Y920735D03*
Y934121D03*
Y944160D03*
Y937467D03*
Y960892D03*
Y950853D03*
Y957546D03*
Y980971D03*
Y974278D03*
Y967585D03*
Y994357D03*
Y987664D03*
X679999Y1027822D03*
X680299Y1021129D03*
X679999Y1047900D03*
Y1041207D03*
Y1034514D03*
Y1054593D03*
X680299Y1074672D03*
Y1067979D03*
Y1091404D03*
Y1081365D03*
Y1084711D03*
Y1098097D03*
Y1111483D03*
Y1104790D03*
Y1128215D03*
Y1118176D03*
Y1121522D03*
Y1141601D03*
Y1134908D03*
Y1148294D03*
Y1154987D03*
Y1158333D03*
Y1171719D03*
Y1165026D03*
Y1185105D03*
Y1178412D03*
Y1191798D03*
Y1208530D03*
Y1201837D03*
Y1195144D03*
Y1221916D03*
Y1215223D03*
Y1238648D03*
Y1228609D03*
Y1231955D03*
Y1245341D03*
X696441Y770144D03*
Y776837D03*
Y786877D03*
Y783530D03*
Y800263D03*
Y793570D03*
Y813648D03*
Y806955D03*
Y820341D03*
Y830381D03*
Y823688D03*
Y850459D03*
Y843766D03*
Y837074D03*
Y867192D03*
Y860499D03*
Y857152D03*
Y873885D03*
Y880577D03*
Y887270D03*
Y897310D03*
Y893963D03*
Y917389D03*
Y910696D03*
Y904003D03*
Y924081D03*
Y934121D03*
Y930774D03*
Y947507D03*
Y940814D03*
Y964239D03*
Y977625D03*
Y970932D03*
Y991011D03*
Y984318D03*
Y1021129D03*
Y1024475D03*
Y1031168D03*
X696141Y1044554D03*
Y1037861D03*
X696441Y1051247D03*
Y1071325D03*
Y1064633D03*
Y1078018D03*
Y1094751D03*
Y1088058D03*
Y1081365D03*
Y1108136D03*
Y1101444D03*
Y1124869D03*
Y1118176D03*
Y1114829D03*
Y1144947D03*
Y1138255D03*
Y1131562D03*
Y1161680D03*
Y1154987D03*
Y1151640D03*
Y1175066D03*
Y1168373D03*
Y1181758D03*
Y1191798D03*
Y1188451D03*
Y1205184D03*
Y1198491D03*
Y1218569D03*
Y1211877D03*
Y1225262D03*
Y1241995D03*
Y1235302D03*
Y1228609D03*
X709899Y960892D03*
Y957546D03*
X709999Y967585D03*
Y1054593D03*
X726141Y964239D03*
Y1021129D03*
Y1024475D03*
Y1051247D03*
X739699Y780184D03*
Y773491D03*
Y786877D03*
Y803609D03*
Y796916D03*
Y790223D03*
Y816995D03*
Y810302D03*
Y833727D03*
Y823688D03*
Y827034D03*
Y847113D03*
Y840420D03*
Y853806D03*
Y860499D03*
Y863845D03*
Y883924D03*
Y877231D03*
Y870538D03*
Y890617D03*
Y897310D03*
Y900656D03*
Y914042D03*
Y907349D03*
Y927428D03*
Y920735D03*
Y934121D03*
Y944160D03*
Y937467D03*
Y960892D03*
Y950853D03*
Y957546D03*
Y980971D03*
Y974278D03*
Y967585D03*
Y994357D03*
Y987664D03*
Y1027822D03*
Y1021129D03*
Y1047900D03*
Y1041207D03*
Y1034514D03*
Y1054593D03*
Y1074672D03*
Y1067979D03*
Y1091404D03*
Y1081365D03*
Y1084711D03*
Y1098097D03*
Y1111483D03*
Y1104790D03*
Y1128215D03*
Y1118176D03*
Y1121522D03*
Y1141601D03*
Y1134908D03*
Y1148294D03*
Y1154987D03*
Y1158333D03*
Y1171719D03*
Y1165026D03*
Y1185105D03*
Y1178412D03*
Y1191798D03*
Y1208530D03*
Y1201837D03*
Y1195144D03*
Y1221916D03*
Y1215223D03*
Y1238648D03*
Y1228609D03*
Y1231955D03*
Y1245341D03*
X755841Y770144D03*
Y776837D03*
Y786877D03*
Y783530D03*
Y800263D03*
Y793570D03*
Y813648D03*
Y806955D03*
Y820341D03*
Y830381D03*
Y823688D03*
Y850459D03*
Y843766D03*
Y837074D03*
Y867192D03*
Y860499D03*
Y857152D03*
Y873885D03*
Y880577D03*
Y887270D03*
Y897310D03*
Y893963D03*
Y917389D03*
Y910696D03*
Y904003D03*
Y924081D03*
Y934121D03*
Y930774D03*
Y947507D03*
Y940814D03*
Y964239D03*
Y977625D03*
X755741Y970932D03*
X755841Y991011D03*
Y984318D03*
Y1021129D03*
Y1024475D03*
Y1031168D03*
X755541Y1044554D03*
Y1037861D03*
X755841Y1051247D03*
X755676Y1071326D03*
X755741Y1064633D03*
X755841Y1078018D03*
Y1094751D03*
Y1088058D03*
Y1081365D03*
X755676Y1108137D03*
X755841Y1101444D03*
Y1124869D03*
Y1118176D03*
Y1114829D03*
Y1144947D03*
Y1138255D03*
Y1131562D03*
Y1161680D03*
Y1154987D03*
Y1151640D03*
Y1175066D03*
Y1168373D03*
X755676Y1181759D03*
X755841Y1191798D03*
X755676Y1188452D03*
X755841Y1205184D03*
Y1198491D03*
Y1218569D03*
Y1211877D03*
Y1225262D03*
Y1241995D03*
Y1235302D03*
Y1228609D03*
X769399Y960892D03*
Y957546D03*
Y967585D03*
Y1054593D03*
X785541Y964239D03*
Y1021129D03*
Y1024475D03*
Y1051247D03*
X799099Y816995D03*
Y810302D03*
Y833727D03*
Y823688D03*
Y827034D03*
Y840420D03*
Y960892D03*
Y957546D03*
Y967585D03*
Y1221916D03*
Y1215223D03*
Y1238648D03*
Y1228609D03*
Y1231955D03*
Y1245341D03*
X815241Y813648D03*
Y806955D03*
Y820341D03*
Y830381D03*
Y823688D03*
Y837074D03*
Y964239D03*
Y1218570D03*
Y1211877D03*
Y1225263D03*
Y1241995D03*
Y1235302D03*
Y1228609D03*
X828799Y960892D03*
Y957546D03*
Y967585D03*
X844941Y964239D03*
X1012541Y960892D03*
Y957546D03*
Y967585D03*
X1028683Y964239D03*
X1042241Y816995D03*
Y810302D03*
Y833727D03*
Y823688D03*
Y827034D03*
Y840420D03*
Y960892D03*
Y957546D03*
Y967585D03*
Y1221916D03*
Y1215223D03*
Y1238648D03*
Y1228609D03*
Y1231955D03*
Y1245341D03*
X1058383Y813648D03*
Y806955D03*
Y820341D03*
Y830381D03*
Y823688D03*
Y837074D03*
Y964239D03*
Y1218570D03*
Y1211877D03*
Y1225263D03*
Y1241995D03*
Y1235302D03*
Y1228609D03*
X1071941Y960892D03*
Y957546D03*
Y967585D03*
Y1054593D03*
X1101641Y780184D03*
Y773491D03*
Y786877D03*
Y803609D03*
Y796916D03*
Y790223D03*
Y816995D03*
Y810302D03*
Y833727D03*
Y823688D03*
Y827034D03*
Y847113D03*
Y840420D03*
Y853806D03*
Y860499D03*
Y863845D03*
Y883924D03*
Y877231D03*
Y870538D03*
Y890617D03*
Y897310D03*
Y900656D03*
Y914042D03*
Y907349D03*
Y927428D03*
Y920735D03*
Y934121D03*
Y944160D03*
Y937467D03*
Y960892D03*
Y950853D03*
X1088083Y964239D03*
X1101641Y957546D03*
Y980971D03*
Y974278D03*
Y967585D03*
Y994357D03*
Y987664D03*
X1088083Y1021129D03*
Y1024475D03*
X1101641Y1027822D03*
Y1021129D03*
Y1047900D03*
Y1041207D03*
Y1034515D03*
X1088083Y1051247D03*
X1101641Y1054593D03*
Y1074672D03*
Y1067979D03*
Y1091404D03*
Y1081365D03*
Y1084711D03*
Y1098097D03*
Y1111483D03*
Y1104790D03*
Y1128215D03*
Y1118176D03*
Y1121522D03*
Y1141601D03*
Y1134908D03*
Y1148294D03*
Y1154987D03*
Y1158333D03*
Y1171719D03*
Y1165026D03*
Y1185105D03*
Y1178412D03*
Y1191798D03*
Y1208530D03*
Y1201837D03*
Y1195144D03*
Y1221916D03*
Y1215223D03*
Y1238648D03*
Y1228609D03*
Y1231955D03*
Y1245341D03*
X1117783Y770144D03*
Y776837D03*
Y786877D03*
Y783530D03*
Y800263D03*
Y793570D03*
Y813648D03*
Y806955D03*
Y820341D03*
Y830381D03*
Y823688D03*
Y850459D03*
Y843766D03*
Y837074D03*
Y867192D03*
Y860499D03*
Y857152D03*
Y873885D03*
Y880577D03*
Y887270D03*
Y897310D03*
Y893963D03*
Y917389D03*
Y910696D03*
Y904003D03*
Y924081D03*
Y934121D03*
Y930774D03*
Y947507D03*
Y940814D03*
Y964239D03*
Y977625D03*
Y970932D03*
Y991011D03*
Y984318D03*
Y1021129D03*
Y1024475D03*
Y1031168D03*
Y1044554D03*
Y1037861D03*
Y1051247D03*
Y1071326D03*
Y1064633D03*
Y1078018D03*
Y1094751D03*
Y1088058D03*
Y1081365D03*
Y1108137D03*
Y1101444D03*
Y1124869D03*
Y1118176D03*
Y1114829D03*
Y1144948D03*
Y1138255D03*
Y1131562D03*
Y1161680D03*
Y1154987D03*
Y1151641D03*
Y1175066D03*
Y1168373D03*
Y1181759D03*
Y1191798D03*
Y1188452D03*
Y1205184D03*
Y1198491D03*
Y1218570D03*
Y1211877D03*
Y1225263D03*
Y1241995D03*
Y1235302D03*
Y1228609D03*
X1131341Y960892D03*
Y957546D03*
Y967585D03*
Y1054593D03*
X1147483Y964239D03*
Y1021129D03*
Y1024475D03*
Y1051247D03*
X1161041Y780184D03*
Y773491D03*
Y786877D03*
Y803609D03*
Y796916D03*
Y790223D03*
Y816995D03*
Y810302D03*
Y833727D03*
Y823688D03*
Y827034D03*
Y847113D03*
Y840420D03*
Y853806D03*
Y860499D03*
Y863845D03*
Y883924D03*
Y877231D03*
Y870538D03*
Y890617D03*
Y897310D03*
Y900656D03*
Y914042D03*
Y907349D03*
Y927428D03*
Y920735D03*
Y934121D03*
Y944160D03*
Y937467D03*
Y960892D03*
Y950853D03*
Y957546D03*
Y980971D03*
Y974278D03*
Y967585D03*
Y994357D03*
Y987664D03*
Y1027822D03*
Y1021129D03*
Y1047900D03*
Y1041207D03*
Y1034515D03*
Y1054593D03*
Y1074672D03*
Y1067979D03*
Y1091404D03*
Y1081365D03*
Y1084711D03*
Y1098097D03*
Y1111483D03*
Y1104790D03*
Y1128215D03*
Y1118176D03*
Y1121522D03*
Y1141601D03*
Y1134908D03*
Y1148294D03*
Y1154987D03*
Y1158333D03*
Y1171719D03*
Y1165026D03*
Y1185105D03*
Y1178412D03*
Y1191798D03*
Y1208530D03*
Y1201837D03*
Y1195144D03*
Y1221916D03*
Y1215223D03*
Y1238648D03*
Y1228609D03*
Y1231955D03*
Y1245341D03*
X1177183Y770144D03*
Y776837D03*
Y786877D03*
Y783530D03*
Y800263D03*
Y793570D03*
Y813648D03*
Y806955D03*
Y820341D03*
Y830381D03*
Y823688D03*
Y850459D03*
Y843766D03*
Y837074D03*
Y867192D03*
Y860499D03*
Y857152D03*
Y873885D03*
Y880577D03*
Y887270D03*
Y897310D03*
Y893963D03*
Y917389D03*
Y910696D03*
Y904003D03*
Y924081D03*
Y934121D03*
Y930774D03*
Y947507D03*
Y940814D03*
Y964239D03*
Y977625D03*
Y970932D03*
Y991011D03*
Y984318D03*
X1177283Y1021129D03*
Y1024475D03*
Y1031168D03*
Y1044554D03*
Y1037861D03*
Y1051247D03*
Y1071326D03*
Y1064633D03*
Y1078018D03*
Y1094752D03*
Y1088059D03*
Y1081366D03*
Y1108137D03*
Y1101444D03*
X1177183Y1124869D03*
X1177283Y1118177D03*
Y1114830D03*
Y1144948D03*
Y1138255D03*
X1177183Y1131562D03*
X1177283Y1161680D03*
Y1154988D03*
Y1151641D03*
Y1175066D03*
Y1168373D03*
Y1181759D03*
Y1191799D03*
Y1188452D03*
Y1205184D03*
Y1198491D03*
Y1218570D03*
Y1211877D03*
Y1225263D03*
X1177250Y1241995D03*
X1177283Y1235302D03*
Y1228609D03*
X1190741Y960892D03*
Y957546D03*
X1220441Y883924D03*
Y890617D03*
Y897310D03*
Y900656D03*
Y914042D03*
Y907349D03*
Y960892D03*
Y957546D03*
Y1185105D03*
Y1178412D03*
Y1191798D03*
Y1208530D03*
Y1201837D03*
Y1195144D03*
X1236583Y880577D03*
Y887270D03*
Y897310D03*
Y893963D03*
Y910696D03*
Y904003D03*
Y1175066D03*
Y1181759D03*
Y1191798D03*
Y1188452D03*
Y1205184D03*
Y1198491D03*
X1313921Y880219D03*
X1312070Y883423D03*
X1313921Y893036D03*
X1312070Y889832D03*
X1310221Y886627D03*
X1313921D03*
X1312503Y1121447D03*
X1326869Y851380D03*
X1330569Y844971D03*
X1325020Y848176D03*
X1328720D03*
X1326871Y857789D03*
X1328720Y860993D03*
X1330571Y857789D03*
X1317621Y880219D03*
X1319471Y883423D03*
X1325020Y899445D03*
Y893036D03*
X1326871Y889832D03*
X1330571D03*
X1317620Y893036D03*
X1319470Y889832D03*
X1323171Y896240D03*
X1330571D03*
X1317621Y886627D03*
X1326871Y896240D03*
X1321321Y886627D03*
X1325020Y912262D03*
X1326871Y909057D03*
X1330571D03*
X1326871Y902649D03*
X1330571D03*
X1323171Y915466D03*
X1330571D03*
X1326871D03*
X1325021Y931488D03*
X1326871Y928283D03*
X1330571D03*
Y921875D03*
X1326871D03*
X1325020Y918670D03*
X1326871Y941100D03*
X1325020Y937896D03*
X1330571Y941100D03*
X1323171Y934691D03*
X1330571D03*
X1326871D03*
Y947509D03*
X1330571D03*
X1325020Y950713D03*
X1326871Y960326D03*
X1325020Y957122D03*
X1330571Y960326D03*
X1326871Y966735D03*
X1330571D03*
X1326871Y953917D03*
X1330571D03*
X1323172D03*
X1326871Y979552D03*
X1330571D03*
X1325020Y976347D03*
X1323171Y973143D03*
X1325020Y969939D03*
X1323603Y1006093D03*
X1325453Y1002888D03*
X1327303Y999684D03*
X1331003D03*
X1327303Y1012501D03*
X1325453Y1009297D03*
X1331003Y1012501D03*
X1327304Y1031727D03*
X1325453Y1028523D03*
X1331003Y1031727D03*
X1325453Y1022114D03*
X1327303Y1018910D03*
X1331003D03*
X1323603Y1025318D03*
X1331004D03*
X1327304D03*
X1325453Y1047749D03*
Y1041340D03*
X1327303Y1038136D03*
X1331003D03*
X1323603Y1044544D03*
X1331003D03*
X1327303D03*
X1325453Y1060565D03*
X1327303Y1057361D03*
X1331003D03*
X1323603Y1063770D03*
X1327303D03*
X1331003D03*
X1327303Y1050952D03*
X1331003D03*
Y1070178D03*
X1327304D03*
X1325453Y1066974D03*
Y1079791D03*
X1327303Y1076587D03*
X1331003D03*
X1327303Y1089404D03*
X1325453Y1086200D03*
X1331003Y1089404D03*
X1323603Y1082995D03*
X1331003D03*
X1327303D03*
X1329153Y1124651D03*
X1331003Y1127856D03*
X1323603Y1121447D03*
X1319903Y1127856D03*
X1316203D03*
X1318054Y1118243D03*
X1321753Y1124651D03*
X1323603Y1127856D03*
X1319903Y1121447D03*
X1316203D03*
X1325452Y1137469D03*
X1327303Y1134264D03*
X1318053Y1131060D03*
X1346137Y179649D03*
X1332421Y841467D03*
X1337969Y844971D03*
X1339821Y841467D03*
X1345369Y844971D03*
X1347221Y841467D03*
X1334269Y844971D03*
X1336120Y848176D03*
X1341669Y844971D03*
X1343520Y848176D03*
X1332420Y854584D03*
X1334271Y857789D03*
X1337971D03*
X1341671D03*
X1345371D03*
X1336120Y860993D03*
X1339820Y854584D03*
X1343520Y860993D03*
X1347220Y854584D03*
X1332420Y899445D03*
Y893036D03*
X1334271Y896240D03*
X1339820Y899445D03*
X1343520D03*
X1347220Y893036D03*
X1332420Y912262D03*
X1334271Y915466D03*
X1339820Y912262D03*
X1337971Y909057D03*
X1343520Y912262D03*
X1345371Y909057D03*
X1337971Y902649D03*
X1345371D03*
X1336120Y905853D03*
X1343520D03*
X1339820D03*
X1347220D03*
X1332420Y931488D03*
X1339820D03*
X1332420Y918670D03*
X1337971Y928283D03*
X1343520Y931488D03*
X1345371Y928283D03*
X1337971Y921875D03*
X1339820Y918670D03*
X1345371Y921875D03*
X1343520Y918670D03*
X1336120Y925079D03*
X1343520D03*
X1339820D03*
X1347220D03*
X1332420Y937896D03*
X1334271Y934691D03*
X1337971Y941100D03*
X1339820Y937896D03*
X1345371Y941100D03*
X1343520Y937896D03*
X1337971Y947509D03*
X1345371D03*
X1343520Y944304D03*
X1336120D03*
X1347220D03*
X1339820D03*
X1332420Y950713D03*
Y957122D03*
X1334271Y953917D03*
X1337971Y966735D03*
X1345371D03*
X1336120Y963530D03*
X1339820Y950713D03*
X1343520D03*
X1337971Y960326D03*
X1339820Y957122D03*
X1345371Y960326D03*
X1343520Y957122D03*
X1347220Y963530D03*
X1336120Y982756D03*
X1343520D03*
X1339820D03*
X1347220D03*
X1345371Y979552D03*
X1343520Y976347D03*
X1337971Y979552D03*
X1339820Y976347D03*
X1332420D03*
Y969939D03*
X1334271Y973143D03*
X1339820Y969939D03*
X1343520D03*
X1334704Y1006093D03*
X1332853Y1002888D03*
Y1009297D03*
X1338404Y1012501D03*
X1345804D03*
X1340253Y1009297D03*
X1343953D03*
X1340253Y1002888D03*
X1338404Y999684D03*
X1347653Y1002888D03*
X1345804Y999684D03*
X1332853Y1028523D03*
Y1022114D03*
X1338404Y1031727D03*
X1340253Y1028523D03*
X1345804Y1031727D03*
X1343953Y1028523D03*
X1334704Y1025318D03*
X1336553Y1015705D03*
X1347653D03*
X1340253Y1022114D03*
X1338404Y1018910D03*
X1343953Y1022114D03*
X1345804Y1018910D03*
X1332853Y1047749D03*
Y1041340D03*
X1340253D03*
X1338404Y1038136D03*
X1343953Y1041340D03*
X1345804Y1038136D03*
X1336553Y1034931D03*
X1347653D03*
X1340253D03*
X1334704Y1044544D03*
X1343953Y1034931D03*
X1340253Y1047749D03*
X1343953D03*
X1332853Y1060565D03*
X1334704Y1063770D03*
X1340253Y1060565D03*
X1338404Y1057361D03*
X1343953Y1060565D03*
X1345804Y1057361D03*
X1338404Y1050952D03*
X1345804D03*
X1336553Y1054157D03*
X1347653D03*
X1340253D03*
X1343953D03*
X1332853Y1066974D03*
X1343953Y1079791D03*
X1345804Y1076587D03*
X1338404Y1070178D03*
X1340253Y1066974D03*
X1345804Y1070178D03*
X1343953Y1066974D03*
X1332853Y1079791D03*
X1340253D03*
X1338404Y1076587D03*
X1336553Y1073383D03*
X1347653D03*
X1340253D03*
X1343953D03*
X1332853Y1086200D03*
X1334704Y1082995D03*
X1338404Y1095813D03*
X1345804D03*
X1338404Y1089404D03*
X1340253Y1086200D03*
X1345804Y1089404D03*
X1343953Y1086200D03*
X1336553Y1092608D03*
X1343953D03*
X1340253D03*
X1347653D03*
X1340253Y1099017D03*
X1343953D03*
X1345803Y1108630D03*
X1340254Y1105426D03*
X1336554Y1111834D03*
X1334703Y1108630D03*
X1343954Y1111834D03*
X1342103Y1108630D03*
X1338403D03*
X1334703Y1121447D03*
X1336554Y1124651D03*
X1340253D03*
X1343953D03*
X1347653D03*
X1332854D03*
X1338404Y1127856D03*
X1342104Y1121447D03*
X1345804Y1127856D03*
X1342103Y1115039D03*
X1345803D03*
X1334703D03*
Y1134264D03*
X1338403Y1140973D03*
X1342104Y1134264D03*
X1345803Y1140973D03*
X1332854Y1137469D03*
X1336554D03*
X1340254D03*
X1343954D03*
X1347654D03*
X1352557Y175948D03*
X1349351Y181498D03*
X1355761Y185198D03*
X1349351D03*
X1355761Y174098D03*
Y181498D03*
X1352557Y183348D03*
X1352561Y198148D03*
X1355771Y196298D03*
X1355765Y199999D03*
Y203699D03*
X1363869Y844971D03*
X1352769D03*
X1356469D03*
X1360169D03*
X1362021Y841467D03*
X1349069Y844971D03*
X1350920Y848176D03*
X1354621Y841467D03*
X1358320Y848176D03*
X1349071Y857789D03*
X1354620Y854584D03*
X1356471Y857789D03*
X1360171D03*
X1363871D03*
X1350920Y860993D03*
X1352771Y857789D03*
X1358320Y860993D03*
X1362020Y854584D03*
X1350920Y899445D03*
X1358320D03*
Y893036D03*
X1350920D03*
X1362020D03*
X1349071Y896240D03*
X1356471D03*
X1352771D03*
X1360171D03*
X1352771Y902649D03*
X1356471D03*
X1350920Y912262D03*
X1352771Y909057D03*
X1358320Y912262D03*
X1356471Y909057D03*
X1349071Y915466D03*
X1356471D03*
X1352771D03*
X1360171D03*
X1350920Y931488D03*
X1352771Y928283D03*
X1358320Y931488D03*
X1356471Y928283D03*
X1352771Y921875D03*
X1350920Y918670D03*
X1356471Y921875D03*
X1358320Y918670D03*
X1356471Y941100D03*
X1358320Y937896D03*
X1352771Y947509D03*
X1356471D03*
X1352771Y941100D03*
X1350920Y937896D03*
X1349071Y934691D03*
X1356471D03*
X1352771D03*
X1360171D03*
X1352771Y960326D03*
X1350920Y957122D03*
X1356471Y960326D03*
X1358320Y957122D03*
X1350920Y950713D03*
X1358320D03*
X1349071Y953917D03*
X1356471D03*
X1352771D03*
X1360171D03*
X1356471Y966735D03*
X1352771D03*
X1350920Y969939D03*
X1358320D03*
X1349504Y1006093D03*
X1356904D03*
X1353204D03*
X1360604D03*
X1351353Y1002888D03*
X1353204Y999684D03*
X1358753Y1002888D03*
X1356904Y999684D03*
X1353204Y1012501D03*
X1351353Y1009297D03*
X1356904Y1012501D03*
X1358753Y1009297D03*
X1353204Y1031727D03*
X1351353Y1028523D03*
X1356904Y1031727D03*
X1358753Y1028523D03*
X1351353Y1022114D03*
X1353204Y1018910D03*
X1358753Y1022114D03*
X1356904Y1018910D03*
X1353204Y1025318D03*
X1360604D03*
X1349502D03*
X1356902D03*
X1351353Y1047749D03*
X1358753D03*
X1351353Y1041340D03*
X1353204Y1038136D03*
X1358753Y1041340D03*
X1356904Y1038136D03*
X1349504Y1044544D03*
X1356904D03*
X1353204D03*
X1360604D03*
X1351353Y1060565D03*
X1353204Y1057361D03*
X1358753Y1060565D03*
X1356904Y1057361D03*
X1353204Y1050952D03*
X1356904D03*
X1349504Y1063770D03*
X1360604D03*
X1353204D03*
X1356904D03*
Y1070178D03*
X1358753Y1066974D03*
X1353204Y1070178D03*
X1351353Y1066974D03*
Y1079791D03*
X1353204Y1076587D03*
X1358753Y1079791D03*
X1356904Y1076587D03*
X1353204Y1089404D03*
X1351353Y1086200D03*
X1356904Y1089404D03*
X1358753Y1086200D03*
X1349504Y1082995D03*
X1360604D03*
X1353204D03*
X1356904D03*
X1351353Y1124651D03*
X1355053D03*
X1358753D03*
X1362453D03*
X1349504Y1121447D03*
X1353204Y1127856D03*
X1356904Y1121447D03*
X1360604Y1127856D03*
X1349504Y1134264D03*
X1353203Y1140973D03*
X1356904Y1134264D03*
X1360603Y1140973D03*
X1351354Y1137469D03*
X1355054D03*
X1358754D03*
X1362454D03*
X1367569Y844971D03*
X1369421Y841467D03*
X1373120Y848176D03*
X1376821Y841467D03*
X1365720Y848176D03*
X1371269Y844971D03*
X1374969D03*
X1378669D03*
X1365720Y860993D03*
X1367571Y857789D03*
X1373120Y860993D03*
X1374971Y857789D03*
X1369420Y854584D03*
X1371271Y857789D03*
X1376820Y854584D03*
X1378671Y857789D03*
X1374971Y973143D03*
X1376820Y976347D03*
X1378671Y979552D03*
Y973143D03*
X1366153Y1002888D03*
X1364304Y999684D03*
X1369853Y1002888D03*
X1371704Y999684D03*
X1369853Y1111834D03*
X1368004Y1108630D03*
X1377253Y1099017D03*
X1379104Y1108630D03*
X1373553Y1105426D03*
X1371704Y1108630D03*
X1379104Y1102221D03*
X1377253Y1111834D03*
X1375404Y1108630D03*
X1366153Y1124651D03*
X1371704Y1121447D03*
X1373553Y1124651D03*
X1377253D03*
X1368004Y1127856D03*
X1369853Y1124651D03*
X1375404Y1127856D03*
X1379104Y1121447D03*
X1364304D03*
X1375404Y1115039D03*
X1368004D03*
X1379104D03*
X1368003Y1140973D03*
X1371704Y1134264D03*
X1375403Y1140973D03*
X1379104Y1134264D03*
X1364304D03*
X1366154Y1137469D03*
X1369854D03*
X1373554D03*
X1377254D03*
X1380520Y848176D03*
X1386069Y844971D03*
X1389769D03*
X1393469D03*
X1382369D03*
X1384221Y841467D03*
X1387920Y848176D03*
X1391621Y841467D03*
X1395320Y848176D03*
X1380520Y860993D03*
X1382371Y857789D03*
X1387920Y860993D03*
X1389771Y857789D03*
X1395320Y860993D03*
X1384220Y854584D03*
X1386071Y857789D03*
X1391620Y854584D03*
X1393471Y857789D03*
Y883423D03*
X1391620Y880219D03*
X1389771Y883423D03*
X1386071Y896240D03*
X1389771D03*
X1393471D03*
X1387920Y899445D03*
X1391620Y893036D03*
X1395320Y899445D03*
Y886627D03*
X1380953Y1099017D03*
X1395753Y1105426D03*
X1393904Y1108630D03*
X1390204Y1102221D03*
X1392053Y1111834D03*
X1388353D03*
X1384653Y1105426D03*
Y1099017D03*
X1392053Y1105426D03*
X1395753Y1111834D03*
X1388353Y1105426D03*
X1384653Y1111834D03*
X1386504Y1108630D03*
X1380953Y1124651D03*
X1384653D03*
X1382804Y1127856D03*
X1386504Y1121447D03*
X1390204Y1115039D03*
X1382803Y1140973D03*
X1386504Y1134264D03*
X1380954Y1137469D03*
X1384654D03*
X1397169Y844971D03*
X1399021Y841467D03*
X1402720Y848176D03*
X1406420D03*
X1411969Y844971D03*
X1400869D03*
X1404569D03*
X1410120Y848176D03*
X1397171Y857789D03*
X1402720Y860993D03*
X1404571Y857789D03*
X1410121Y860993D03*
X1411971Y857789D03*
X1399020Y854584D03*
X1400871Y857789D03*
X1406420Y854584D03*
X1408271Y857789D03*
Y883423D03*
X1406420Y880219D03*
X1400871Y883423D03*
X1399020Y880219D03*
X1404571Y883423D03*
X1397171D03*
X1411971D03*
X1397171Y896240D03*
X1402720Y899445D03*
X1404571Y896240D03*
X1410120Y899445D03*
X1399020Y893036D03*
X1400871Y896240D03*
X1406420Y893036D03*
X1408271Y896240D03*
X1411971D03*
X1410120Y886627D03*
X1402720D03*
X1405003Y1076587D03*
X1406853Y1079791D03*
X1413820Y848176D03*
X1424921Y860993D03*
X1421220Y854584D03*
X1417520Y860993D03*
X1428620Y854584D03*
X1426771Y857789D03*
X1423071D03*
X1419371D03*
X1413821Y854584D03*
X1428621Y880219D03*
X1423071Y883423D03*
X1421220Y880219D03*
X1415671Y883423D03*
X1413820Y880219D03*
X1426771Y883423D03*
X1419371D03*
X1413820Y893036D03*
X1421220Y899445D03*
X1419371Y896240D03*
X1424920Y899445D03*
X1426772Y896240D03*
X1417520Y899445D03*
X1421220Y893036D03*
X1423071Y896240D03*
X1428621Y893036D03*
X1424920Y886627D03*
X1417520D03*
X1445271Y857789D03*
X1439720Y860993D03*
X1437871Y857789D03*
X1432320Y860993D03*
X1430471Y857789D03*
X1443420Y854584D03*
X1441571Y857789D03*
X1436020Y854584D03*
X1434171Y857789D03*
X1445271Y883423D03*
X1443420Y880219D03*
X1437871Y883423D03*
X1436020Y880219D03*
X1430471Y883423D03*
X1441571D03*
X1434171D03*
X1430471Y896240D03*
X1436020Y893036D03*
X1437871Y896240D03*
X1441571D03*
X1432320Y899445D03*
X1434171Y896240D03*
X1439720Y899445D03*
X1443420Y893036D03*
X1439720Y886627D03*
X1432320D03*
X1460071Y857789D03*
X1454520Y860993D03*
X1452671Y857789D03*
X1447120Y860993D03*
X1458220Y854584D03*
X1456371Y857789D03*
X1450820Y854584D03*
X1448971Y857789D03*
X1447120Y886627D03*
X1460504Y1121447D03*
X1456804Y1127856D03*
X1453104Y1121447D03*
X1449404Y1127856D03*
X1445704Y1121447D03*
X1458653Y1124651D03*
X1454953D03*
X1451253D03*
X1447553D03*
X1460504Y1134264D03*
X1458654Y1137469D03*
X1453104Y1134264D03*
X1451254Y1137469D03*
X1456803Y1140973D03*
X1454954Y1137469D03*
X1449403Y1140973D03*
X1467471Y857789D03*
X1461920Y860993D03*
X1476720D03*
X1474871Y857789D03*
X1471171D03*
X1465620Y854584D03*
X1463771Y857789D03*
X1473020Y854584D03*
X1469320Y860993D03*
X1476720Y899445D03*
Y912262D03*
X1474871Y909057D03*
Y902649D03*
X1476720Y905853D03*
X1473020D03*
X1476720Y931488D03*
X1474871Y921875D03*
X1476720Y918670D03*
X1474871Y928283D03*
X1473020Y925079D03*
X1476720D03*
X1474871Y947509D03*
Y941100D03*
X1476720Y937896D03*
X1473020Y944304D03*
X1476720D03*
Y950713D03*
Y957122D03*
X1474871Y960326D03*
X1463771Y979552D03*
X1461920Y976347D03*
X1467471Y979552D03*
X1469320Y976347D03*
X1476720Y982756D03*
X1473020D03*
X1474871Y979552D03*
X1476720Y976347D03*
X1477153Y1002888D03*
X1475304Y999684D03*
Y1012501D03*
X1477153Y1009297D03*
X1473453Y1015705D03*
X1475304Y1031727D03*
X1477153Y1028523D03*
Y1022114D03*
X1475304Y1018910D03*
X1477153Y1041340D03*
X1475304Y1038136D03*
X1477153Y1047749D03*
Y1034931D03*
X1473453D03*
X1477153Y1060565D03*
X1475304Y1057361D03*
Y1050952D03*
X1477153Y1054157D03*
X1473453D03*
X1475304Y1070178D03*
X1477153Y1066974D03*
Y1079791D03*
X1475304Y1076587D03*
X1473453Y1073383D03*
X1477153D03*
X1475304Y1089404D03*
X1477153Y1086200D03*
X1473453Y1092608D03*
X1477153D03*
X1464204Y1127856D03*
X1475304Y1121447D03*
X1471604Y1127856D03*
X1467904Y1121447D03*
X1466053Y1124651D03*
X1462353D03*
X1477153D03*
X1473453D03*
X1469753D03*
X1469754Y1137469D03*
X1464203Y1140973D03*
X1477154Y1137469D03*
X1471603Y1140973D03*
X1467904Y1134264D03*
X1466054Y1137469D03*
X1462354D03*
X1475304Y1134264D03*
X1473454Y1137469D03*
X1491520Y860993D03*
X1489671Y857789D03*
X1484120Y860993D03*
X1482271Y857789D03*
X1493371D03*
X1487820Y854584D03*
X1485971Y857789D03*
X1480420Y854584D03*
X1478571Y857789D03*
X1487820Y899445D03*
Y893036D03*
X1484120D03*
X1485971Y896240D03*
X1493371D03*
X1489671D03*
X1480420Y899445D03*
X1489671Y902649D03*
X1493371D03*
X1487820Y912262D03*
X1489671Y909057D03*
X1493371D03*
X1489671Y915466D03*
X1485971D03*
X1493371D03*
X1480420Y912262D03*
X1482271Y909057D03*
Y902649D03*
X1484120Y905853D03*
X1480420D03*
X1487820Y931488D03*
X1489671Y928283D03*
X1493371D03*
X1482271D03*
Y921875D03*
X1480420Y918670D03*
X1489671Y921875D03*
X1487820Y918670D03*
X1493371Y921875D03*
X1480420Y931488D03*
Y925079D03*
X1484120D03*
X1489671Y941100D03*
X1487820Y937896D03*
X1493371Y941100D03*
X1489671Y934691D03*
X1485971D03*
X1493371D03*
X1489671Y947509D03*
X1493371D03*
X1482271D03*
Y941100D03*
X1480420Y937896D03*
X1484120Y944304D03*
X1480420D03*
X1487820Y950713D03*
X1489671Y960326D03*
X1487820Y957122D03*
X1493371Y960326D03*
Y966735D03*
X1489671D03*
X1480420Y950713D03*
X1489671Y953917D03*
X1493371D03*
X1485971D03*
X1480420Y957122D03*
X1482271Y960326D03*
X1484120Y982756D03*
X1480420D03*
Y976347D03*
X1482271Y979552D03*
X1489671D03*
X1493371D03*
X1487820Y976347D03*
X1485971Y973143D03*
X1487820Y969939D03*
X1493804Y1006093D03*
X1490104D03*
X1486404D03*
X1493804Y1012501D03*
X1480853Y1002888D03*
X1482703Y999684D03*
X1490104Y1012501D03*
X1488253Y1009297D03*
X1482704Y1012501D03*
X1480853Y1009297D03*
X1493803Y999684D03*
X1488253Y1002888D03*
X1490104Y999684D03*
Y1031727D03*
X1488253Y1028523D03*
X1493804Y1031727D03*
X1488253Y1022114D03*
X1490104Y1018910D03*
X1493804D03*
X1490104Y1025318D03*
X1486404D03*
X1493804D03*
X1484553Y1015705D03*
X1482704Y1031727D03*
X1480853Y1028523D03*
Y1022114D03*
X1482704Y1018910D03*
X1480853Y1041340D03*
X1482704Y1038136D03*
X1488253Y1047749D03*
Y1041340D03*
X1490104Y1038136D03*
X1493804D03*
X1480853Y1047749D03*
X1486404Y1044544D03*
X1484553Y1034931D03*
X1490104Y1044544D03*
X1493804D03*
X1480853Y1034931D03*
X1488253Y1060565D03*
X1490104Y1057361D03*
X1493804D03*
X1486404Y1063770D03*
X1490104D03*
X1493804D03*
X1490104Y1050952D03*
X1493804D03*
X1480853Y1060565D03*
X1482704Y1057361D03*
Y1050952D03*
X1484553Y1054157D03*
X1480853D03*
X1493804Y1070178D03*
X1490104D03*
X1488253Y1066974D03*
X1480853Y1079791D03*
X1482704Y1076587D03*
Y1070178D03*
X1480853Y1066974D03*
X1488253Y1079791D03*
X1490104Y1076587D03*
X1493804D03*
X1484553Y1073383D03*
X1480853D03*
X1490104Y1089404D03*
X1488253Y1086200D03*
X1493804Y1089404D03*
X1490104Y1082995D03*
X1486404D03*
X1493804D03*
X1486404Y1095813D03*
X1482703D03*
X1482704Y1089404D03*
X1480853Y1086200D03*
X1484553Y1092608D03*
X1480853D03*
X1493804Y1102221D03*
X1491953Y1099017D03*
X1493804Y1127856D03*
X1490104Y1121447D03*
X1486404Y1127856D03*
X1482704Y1121447D03*
X1479004Y1127856D03*
X1491953Y1124651D03*
X1488253D03*
X1484553D03*
X1480853D03*
X1493803Y1140973D03*
X1490104Y1134264D03*
X1488254Y1137469D03*
X1482704Y1134264D03*
X1480854Y1137469D03*
X1491954D03*
X1486403Y1140973D03*
X1484554Y1137469D03*
X1479003Y1140973D03*
X1508171Y864197D03*
X1510021Y854584D03*
X1504471Y857789D03*
X1498920Y860993D03*
X1497071Y857789D03*
X1502620Y854584D03*
X1500771Y857789D03*
X1495220Y854584D03*
X1502621Y899445D03*
X1506320D03*
X1495220D03*
Y893036D03*
X1498920D03*
X1497071Y896240D03*
X1506321Y912262D03*
X1508171Y909057D03*
X1500771Y902649D03*
X1508171D03*
X1502621Y912262D03*
X1500771Y909057D03*
X1502621Y905853D03*
X1510021D03*
X1498920D03*
X1506321D03*
X1495220Y912262D03*
X1497071Y915466D03*
X1502621Y931488D03*
X1500771Y928283D03*
X1506321Y931488D03*
X1508171Y928283D03*
X1500771Y921875D03*
X1502621Y918670D03*
X1508171Y921875D03*
X1506321Y918670D03*
X1502621Y925079D03*
X1510021D03*
X1498920D03*
X1506321D03*
X1495220Y931488D03*
Y918670D03*
X1500771Y941100D03*
X1502621Y937896D03*
X1508171Y941100D03*
X1506321Y937896D03*
X1500771Y947509D03*
X1508171D03*
X1495220Y937896D03*
X1510021Y944304D03*
X1497071Y934691D03*
X1502621Y944304D03*
X1506320D03*
X1498920D03*
X1500771Y966735D03*
X1508171D03*
X1498920Y963530D03*
X1502621Y950713D03*
X1506320D03*
X1508171Y960326D03*
X1506320Y957122D03*
X1500771Y960326D03*
X1502621Y957122D03*
X1510021Y963530D03*
X1495220Y950713D03*
Y957122D03*
X1497071Y953917D03*
X1502621Y969939D03*
X1506321D03*
X1495220Y976347D03*
Y969939D03*
X1497071Y973143D03*
X1497504Y1006093D03*
X1501204Y1012501D03*
X1508603D03*
X1503053Y1009297D03*
X1506753D03*
X1495653D03*
X1495655Y1002888D03*
X1506753D03*
X1508603Y999684D03*
X1503053Y1002888D03*
X1501204Y999684D03*
X1499353Y1015705D03*
X1510453D03*
X1501204Y1031727D03*
X1503053Y1028523D03*
X1508603Y1031727D03*
X1506753Y1028523D03*
Y1022114D03*
X1508603Y1018910D03*
X1503053Y1022114D03*
X1501204Y1018910D03*
X1495653Y1028523D03*
Y1022114D03*
X1497504Y1025318D03*
X1503053Y1041340D03*
X1501204Y1038136D03*
X1506753Y1041340D03*
X1508603Y1038136D03*
X1503053Y1047749D03*
X1506753D03*
X1503053Y1034931D03*
X1510453D03*
X1499353D03*
X1506753D03*
X1495653Y1047749D03*
Y1041340D03*
X1497504Y1044544D03*
X1495653Y1060565D03*
X1503053D03*
X1501204Y1057361D03*
X1506753Y1060565D03*
X1508604Y1057361D03*
X1501203Y1050952D03*
X1508604Y1050953D03*
X1499353Y1054157D03*
X1497504Y1063770D03*
X1510453Y1054157D03*
X1503053D03*
X1506753D03*
Y1079791D03*
X1508604Y1076587D03*
X1501204Y1070178D03*
X1503053Y1066974D03*
X1508604Y1070178D03*
X1506753Y1066974D03*
X1503053Y1079791D03*
X1501204Y1076587D03*
X1499353Y1073383D03*
X1510453D03*
X1503053D03*
X1506753D03*
X1495653Y1066974D03*
Y1079791D03*
X1497504Y1095813D03*
X1508603D03*
X1501204D03*
Y1089404D03*
X1503053Y1086200D03*
X1508604Y1089404D03*
X1506753Y1086200D03*
X1503053Y1092608D03*
X1510452D03*
X1499353D03*
X1506753D03*
X1495653Y1086200D03*
X1497504Y1082995D03*
X1506753Y1099017D03*
X1503053Y1124651D03*
X1497504Y1121447D03*
X1501204Y1127856D03*
X1499353Y1124651D03*
X1495653D03*
X1508604Y1134264D03*
X1501203Y1140973D03*
X1499354Y1137469D03*
X1510454D03*
X1503054D03*
X1497504Y1134264D03*
X1495654Y1137469D03*
X1519271Y851380D03*
X1515571D03*
X1511871Y864197D03*
X1519270D03*
X1522970D03*
X1511871Y857789D03*
X1519271D03*
X1515571D03*
X1517421Y860993D03*
Y854584D03*
X1515571Y883423D03*
X1513720Y880219D03*
X1519271Y883423D03*
X1521121Y880219D03*
X1513720Y873810D03*
X1515571Y870606D03*
X1521121Y873810D03*
X1519271Y870606D03*
X1515570Y877014D03*
X1522970D03*
X1511871D03*
X1519271D03*
X1596941Y883924D03*
Y890617D03*
Y897310D03*
Y900656D03*
Y914042D03*
Y907349D03*
Y960892D03*
Y957546D03*
Y1185105D03*
Y1178412D03*
Y1191798D03*
Y1208530D03*
Y1201837D03*
Y1195144D03*
X1613083Y880577D03*
Y887270D03*
Y897310D03*
Y893963D03*
Y910696D03*
Y904003D03*
Y1175066D03*
Y1181759D03*
Y1191798D03*
Y1188451D03*
Y1205184D03*
Y1198491D03*
X1626641Y960892D03*
Y957546D03*
X1656441Y780184D03*
Y773491D03*
Y786877D03*
Y803609D03*
Y796916D03*
Y790223D03*
Y816995D03*
Y810302D03*
Y833727D03*
Y823688D03*
Y827034D03*
Y847113D03*
Y840420D03*
Y853806D03*
Y860499D03*
Y863845D03*
Y883924D03*
Y877231D03*
Y870538D03*
Y890617D03*
Y897310D03*
Y900656D03*
Y914042D03*
Y907349D03*
Y927428D03*
Y920735D03*
Y934121D03*
Y944160D03*
Y937467D03*
Y960892D03*
Y950853D03*
Y957546D03*
Y980971D03*
Y974278D03*
Y967585D03*
Y994357D03*
Y987664D03*
X1656141Y1027822D03*
X1656441Y1021129D03*
X1656141Y1047900D03*
Y1041207D03*
Y1034514D03*
Y1054593D03*
X1656441Y1074672D03*
Y1067979D03*
Y1091404D03*
Y1081365D03*
Y1084711D03*
Y1098097D03*
Y1111483D03*
Y1104790D03*
Y1128215D03*
Y1118176D03*
Y1121522D03*
Y1141601D03*
Y1134908D03*
Y1148294D03*
Y1154987D03*
Y1158333D03*
Y1171719D03*
Y1165026D03*
Y1185105D03*
Y1178412D03*
Y1191798D03*
Y1208530D03*
Y1201837D03*
Y1195144D03*
Y1221916D03*
Y1215223D03*
Y1238648D03*
Y1228609D03*
Y1231955D03*
Y1245341D03*
X1672583Y770144D03*
Y776837D03*
Y786877D03*
Y783530D03*
Y800263D03*
Y793570D03*
Y813648D03*
Y806955D03*
Y820341D03*
Y830381D03*
Y823688D03*
Y850459D03*
Y843766D03*
Y837074D03*
Y867192D03*
Y860499D03*
Y857152D03*
Y873885D03*
Y880577D03*
Y887270D03*
Y897310D03*
Y893963D03*
Y917389D03*
Y910696D03*
Y904003D03*
Y924081D03*
Y934121D03*
Y930774D03*
Y947507D03*
Y940814D03*
Y964239D03*
Y977625D03*
Y970932D03*
Y991011D03*
Y984318D03*
Y1021129D03*
Y1024475D03*
Y1031168D03*
X1672283Y1044554D03*
Y1037861D03*
X1672583Y1051247D03*
Y1071325D03*
Y1064633D03*
Y1078018D03*
Y1094751D03*
Y1088058D03*
Y1081365D03*
Y1108136D03*
Y1101444D03*
Y1124869D03*
Y1118176D03*
Y1114829D03*
Y1144947D03*
Y1138255D03*
Y1131562D03*
Y1161680D03*
Y1154987D03*
Y1151640D03*
Y1175066D03*
Y1168373D03*
Y1181758D03*
Y1191798D03*
Y1188451D03*
Y1205184D03*
Y1198491D03*
Y1218569D03*
Y1211877D03*
Y1225262D03*
Y1241995D03*
Y1235302D03*
Y1228609D03*
X1686041Y960892D03*
Y957546D03*
X1686141Y967585D03*
Y1054593D03*
X1702283Y964239D03*
Y1021129D03*
Y1024475D03*
Y1051247D03*
X1715841Y780184D03*
Y773491D03*
Y786877D03*
Y803609D03*
Y796916D03*
Y790223D03*
Y816995D03*
Y810302D03*
Y833727D03*
Y823688D03*
Y827034D03*
Y847113D03*
Y840420D03*
Y853806D03*
Y860499D03*
Y863845D03*
Y883924D03*
Y877231D03*
Y870538D03*
Y890617D03*
Y897310D03*
Y900656D03*
Y914042D03*
Y907349D03*
Y927428D03*
Y920735D03*
Y934121D03*
Y944160D03*
Y937467D03*
Y960892D03*
Y950853D03*
Y957546D03*
Y980971D03*
Y974278D03*
Y967585D03*
Y994357D03*
Y987664D03*
Y1027822D03*
Y1021129D03*
Y1047900D03*
Y1041207D03*
Y1034514D03*
Y1054593D03*
Y1074672D03*
Y1067979D03*
Y1091404D03*
Y1081365D03*
Y1084711D03*
Y1098097D03*
Y1111483D03*
Y1104790D03*
Y1128215D03*
Y1118176D03*
Y1121522D03*
Y1141601D03*
Y1134908D03*
Y1148294D03*
Y1154987D03*
Y1158333D03*
Y1171719D03*
Y1165026D03*
Y1185105D03*
Y1178412D03*
Y1191798D03*
Y1208530D03*
Y1201837D03*
Y1195144D03*
Y1221916D03*
Y1215223D03*
Y1238648D03*
Y1228609D03*
Y1231955D03*
Y1245341D03*
X1731983Y770144D03*
Y776837D03*
Y786877D03*
Y783530D03*
Y800263D03*
Y793570D03*
Y813648D03*
Y806955D03*
Y820341D03*
Y830381D03*
Y823688D03*
Y850459D03*
Y843766D03*
Y837074D03*
Y867192D03*
Y860499D03*
Y857152D03*
Y873885D03*
Y880577D03*
Y887270D03*
Y897310D03*
Y893963D03*
Y917389D03*
Y910696D03*
Y904003D03*
Y924081D03*
Y934121D03*
Y930774D03*
Y947507D03*
Y940814D03*
Y964239D03*
Y977625D03*
X1731883Y970932D03*
X1731983Y991011D03*
Y984318D03*
Y1021129D03*
Y1024475D03*
Y1031168D03*
X1731683Y1044554D03*
Y1037861D03*
X1731983Y1051247D03*
X1731818Y1071326D03*
X1731883Y1064633D03*
X1731983Y1078018D03*
Y1094751D03*
Y1088058D03*
Y1081365D03*
X1731818Y1108137D03*
X1731983Y1101444D03*
Y1124869D03*
Y1118176D03*
Y1114829D03*
Y1144947D03*
Y1138255D03*
Y1131562D03*
Y1161680D03*
Y1154987D03*
Y1151640D03*
Y1175066D03*
Y1168373D03*
X1731818Y1181759D03*
X1731983Y1191798D03*
X1731818Y1188452D03*
X1731983Y1205184D03*
Y1198491D03*
Y1218569D03*
Y1211877D03*
Y1225262D03*
Y1241995D03*
Y1235302D03*
Y1228609D03*
X1745541Y960892D03*
Y957546D03*
Y967585D03*
Y1054593D03*
X1761683Y964239D03*
Y1021129D03*
Y1024475D03*
Y1051247D03*
X1775241Y816995D03*
Y810302D03*
Y833727D03*
Y823688D03*
Y827034D03*
Y840420D03*
Y960892D03*
Y957546D03*
Y967585D03*
Y1221916D03*
Y1215223D03*
Y1238648D03*
Y1228609D03*
Y1231955D03*
Y1245341D03*
X1791383Y813648D03*
Y806955D03*
Y820341D03*
Y830381D03*
Y823688D03*
Y837074D03*
Y964239D03*
Y1218570D03*
Y1211877D03*
Y1225263D03*
Y1241995D03*
Y1235302D03*
Y1228609D03*
X1804941Y960892D03*
Y957546D03*
Y967585D03*
X1821083Y964239D03*
G54D48*
X676508Y145866D03*
G54D35*
X238780Y1643661D03*
X230906Y1649173D03*
X238780Y1653110D03*
Y1657834D03*
X230906Y1653897D03*
Y1663346D03*
X238780Y1667283D03*
Y1672007D03*
Y1681456D03*
X230906Y1668070D03*
Y1677519D03*
Y1682244D03*
X238780Y1686180D03*
Y1695629D03*
X230906Y1691692D03*
Y1696417D03*
X238780Y1700354D03*
Y1709803D03*
Y1714527D03*
X230906Y1705866D03*
Y1710590D03*
X238780Y1723976D03*
Y1728700D03*
X230906Y1720039D03*
Y1724763D03*
Y1734212D03*
X254528Y1643661D03*
X246654Y1649173D03*
X254528Y1653110D03*
Y1657834D03*
X246654Y1653897D03*
Y1663346D03*
X254528Y1667283D03*
Y1672007D03*
Y1681456D03*
X246654Y1668070D03*
Y1677519D03*
Y1682244D03*
X254528Y1686180D03*
Y1695629D03*
X246654Y1691692D03*
Y1696417D03*
X254528Y1700354D03*
Y1709803D03*
Y1714527D03*
X246654Y1705866D03*
Y1710590D03*
X254528Y1723976D03*
Y1728700D03*
X246654Y1720039D03*
Y1724763D03*
Y1734212D03*
X270276Y1643661D03*
X262402Y1649173D03*
X270276Y1653110D03*
Y1657834D03*
X262402Y1653897D03*
Y1663346D03*
X270276Y1667283D03*
Y1672007D03*
Y1681456D03*
X262402Y1668070D03*
Y1677519D03*
Y1682244D03*
X270276Y1686180D03*
Y1695629D03*
X262402Y1691692D03*
Y1696417D03*
X270276Y1700354D03*
Y1709803D03*
Y1714527D03*
X262402Y1705866D03*
Y1710590D03*
X270276Y1723976D03*
Y1728700D03*
X262402Y1720039D03*
Y1724763D03*
Y1734212D03*
X286024Y1643661D03*
X278150Y1649173D03*
X286024Y1653110D03*
Y1657834D03*
X278150Y1653897D03*
Y1663346D03*
X286024Y1667283D03*
Y1672007D03*
Y1681456D03*
X278150Y1668070D03*
Y1677519D03*
Y1682244D03*
X286024Y1686180D03*
Y1695629D03*
X278150Y1691692D03*
Y1696417D03*
X286024Y1700354D03*
Y1709803D03*
Y1714527D03*
X278150Y1705866D03*
Y1710590D03*
X286024Y1723976D03*
Y1728700D03*
X278150Y1720039D03*
Y1724763D03*
Y1734212D03*
X305709Y1672007D03*
X297835Y1677519D03*
Y1682244D03*
X305709Y1681456D03*
Y1686180D03*
X297835Y1691692D03*
Y1696417D03*
X305709Y1695629D03*
Y1700354D03*
X297835Y1705866D03*
Y1710590D03*
X305709Y1709803D03*
Y1714527D03*
X297835Y1720039D03*
Y1724763D03*
X305709Y1723976D03*
Y1728700D03*
X297835Y1734212D03*
X321457Y1672007D03*
X313583Y1677519D03*
Y1682244D03*
X321457Y1681456D03*
Y1686180D03*
X313583Y1691692D03*
Y1696417D03*
X321457Y1695629D03*
Y1700354D03*
X313583Y1705866D03*
Y1710590D03*
X321457Y1709803D03*
Y1714527D03*
X313583Y1720039D03*
Y1724763D03*
X321457Y1723976D03*
Y1728700D03*
X313583Y1734212D03*
X337205Y1672007D03*
X329331Y1677519D03*
Y1682244D03*
X337205Y1681456D03*
Y1686180D03*
X329331Y1691692D03*
Y1696417D03*
X337205Y1695629D03*
Y1700354D03*
X329331Y1705866D03*
Y1710590D03*
X337205Y1709803D03*
Y1714527D03*
X329331Y1720039D03*
Y1724763D03*
X337205Y1723976D03*
Y1728700D03*
X329331Y1734212D03*
X352953Y1672007D03*
X345079Y1677519D03*
Y1682244D03*
X352953Y1681456D03*
Y1686180D03*
X345079Y1691692D03*
Y1696417D03*
X352953Y1695629D03*
Y1700354D03*
X345079Y1705866D03*
Y1710590D03*
X352953Y1709803D03*
Y1714527D03*
X345079Y1720039D03*
Y1724763D03*
X352953Y1723976D03*
Y1728700D03*
X345079Y1734212D03*
X495079Y1677519D03*
Y1682244D03*
Y1691692D03*
Y1696417D03*
Y1705866D03*
Y1710590D03*
Y1720039D03*
Y1724763D03*
Y1734212D03*
X502953Y1672007D03*
X510827Y1677519D03*
X502953Y1681456D03*
X510827Y1682244D03*
X502953Y1686180D03*
X510827Y1691692D03*
X502953Y1695629D03*
X510827Y1696417D03*
X502953Y1700354D03*
X510827Y1705866D03*
X502953Y1709803D03*
X510827Y1710590D03*
X502953Y1714527D03*
X510827Y1720039D03*
X502953Y1723976D03*
X510827Y1724763D03*
X502953Y1728700D03*
X510827Y1734212D03*
X518701Y1672007D03*
X534449D03*
X526575Y1677519D03*
X518701Y1681456D03*
X526575Y1682244D03*
X534449Y1681456D03*
X518701Y1686180D03*
X534449D03*
X526575Y1691692D03*
X518701Y1695629D03*
X526575Y1696417D03*
X534449Y1695629D03*
X518701Y1700354D03*
X534449D03*
X526575Y1705866D03*
X518701Y1709803D03*
X526575Y1710590D03*
X534449Y1709803D03*
X518701Y1714527D03*
X534449D03*
X526575Y1720039D03*
X518701Y1723976D03*
X526575Y1724763D03*
X534449Y1723976D03*
X518701Y1728700D03*
X534449D03*
X526575Y1734212D03*
X550197Y1672007D03*
X542323Y1677519D03*
Y1682244D03*
X550197Y1681456D03*
Y1686180D03*
X542323Y1691692D03*
Y1696417D03*
X550197Y1695629D03*
Y1700354D03*
X542323Y1705866D03*
Y1710590D03*
X550197Y1709803D03*
Y1714527D03*
X542323Y1720039D03*
Y1724763D03*
X550197Y1723976D03*
Y1728700D03*
X542323Y1734212D03*
X562008Y1677519D03*
Y1682244D03*
Y1691692D03*
Y1696417D03*
Y1705866D03*
Y1710590D03*
Y1720039D03*
Y1724763D03*
Y1734212D03*
X569882Y1672007D03*
X577756Y1677519D03*
X569882Y1681456D03*
X577756Y1682244D03*
X569882Y1686180D03*
X577756Y1691692D03*
X569882Y1695629D03*
X577756Y1696417D03*
X569882Y1700354D03*
X577756Y1705866D03*
X569882Y1709803D03*
X577756Y1710590D03*
X569882Y1714527D03*
X577756Y1720039D03*
X569882Y1723976D03*
X577756Y1724763D03*
X569882Y1728700D03*
X577756Y1734212D03*
X585630Y1672007D03*
X593504Y1677519D03*
X585630Y1681456D03*
X593504Y1682244D03*
X585630Y1686180D03*
X593504Y1691692D03*
X585630Y1695629D03*
X593504Y1696417D03*
X585630Y1700354D03*
X593504Y1705866D03*
X585630Y1709803D03*
X593504Y1710590D03*
X585630Y1714527D03*
X593504Y1720039D03*
X585630Y1723976D03*
X593504Y1724763D03*
X585630Y1728700D03*
X593504Y1734212D03*
X601378Y1672007D03*
X609252Y1677519D03*
X601378Y1681456D03*
X609252Y1682244D03*
X601378Y1686180D03*
X609252Y1691692D03*
X601378Y1695629D03*
X609252Y1696417D03*
X601378Y1700354D03*
X609252Y1705866D03*
X601378Y1709803D03*
X609252Y1710590D03*
X601378Y1714527D03*
X609252Y1720039D03*
X601378Y1723976D03*
X609252Y1724763D03*
X601378Y1728700D03*
X609252Y1734212D03*
X617126Y1672007D03*
Y1681456D03*
Y1686180D03*
Y1695629D03*
Y1700354D03*
Y1709803D03*
Y1714527D03*
Y1723976D03*
Y1728700D03*
X1246654Y1672007D03*
X1238780Y1677519D03*
Y1682244D03*
X1246654Y1681456D03*
Y1686180D03*
X1238780Y1691692D03*
Y1696417D03*
X1246654Y1695629D03*
Y1700354D03*
X1238780Y1705866D03*
Y1710590D03*
X1246654Y1709803D03*
Y1714527D03*
X1238780Y1720039D03*
Y1724763D03*
X1246654Y1723976D03*
Y1728700D03*
X1238780Y1734212D03*
X1262402Y1672007D03*
X1254528Y1677519D03*
Y1682244D03*
X1262402Y1681456D03*
Y1686180D03*
X1254528Y1691692D03*
Y1696417D03*
X1262402Y1695629D03*
Y1700354D03*
X1254528Y1705866D03*
Y1710590D03*
X1262402Y1709803D03*
Y1714527D03*
X1254528Y1720039D03*
Y1724763D03*
X1262402Y1723976D03*
Y1728700D03*
X1254528Y1734212D03*
X1278150Y1672007D03*
X1270276Y1677519D03*
Y1682244D03*
X1278150Y1681456D03*
Y1686180D03*
X1270276Y1691692D03*
Y1696417D03*
X1278150Y1695629D03*
Y1700354D03*
X1270276Y1705866D03*
Y1710590D03*
X1278150Y1709803D03*
Y1714527D03*
X1270276Y1720039D03*
Y1724763D03*
X1278150Y1723976D03*
Y1728700D03*
X1270276Y1734212D03*
X1293898Y1672007D03*
X1286024Y1677519D03*
Y1682244D03*
X1293898Y1681456D03*
Y1686180D03*
X1286024Y1691692D03*
Y1696417D03*
X1293898Y1695629D03*
Y1700354D03*
X1286024Y1705866D03*
Y1710590D03*
X1293898Y1709803D03*
Y1714527D03*
X1286024Y1720039D03*
Y1724763D03*
X1293898Y1723976D03*
Y1728700D03*
X1286024Y1734212D03*
X1313583Y1672007D03*
X1305709Y1677519D03*
Y1682244D03*
X1313583Y1681456D03*
Y1686180D03*
X1305709Y1691692D03*
Y1696417D03*
X1313583Y1695629D03*
Y1700354D03*
X1305709Y1705866D03*
Y1710590D03*
X1313583Y1709803D03*
Y1714527D03*
X1305709Y1720039D03*
Y1724763D03*
X1313583Y1723976D03*
Y1728700D03*
X1305709Y1734212D03*
X1329331Y1672007D03*
X1321457Y1677519D03*
Y1682244D03*
X1329331Y1681456D03*
Y1686180D03*
X1321457Y1691692D03*
Y1696417D03*
X1329331Y1695629D03*
Y1700354D03*
X1321457Y1705866D03*
Y1710590D03*
X1329331Y1709803D03*
Y1714527D03*
X1321457Y1720039D03*
Y1724763D03*
X1329331Y1723976D03*
Y1728700D03*
X1321457Y1734212D03*
X1345079Y1672007D03*
X1337205Y1677519D03*
Y1682244D03*
X1345079Y1681456D03*
Y1686180D03*
X1337205Y1691692D03*
Y1696417D03*
X1345079Y1695629D03*
Y1700354D03*
X1337205Y1705866D03*
Y1710590D03*
X1345079Y1709803D03*
Y1714527D03*
X1337205Y1720039D03*
Y1724763D03*
X1345079Y1723976D03*
Y1728700D03*
X1337205Y1734212D03*
X1360827Y1672007D03*
X1352953Y1677519D03*
Y1682244D03*
X1360827Y1681456D03*
Y1686180D03*
X1352953Y1691692D03*
Y1696417D03*
X1360827Y1695629D03*
Y1700354D03*
X1352953Y1705866D03*
Y1710590D03*
X1360827Y1709803D03*
Y1714527D03*
X1352953Y1720039D03*
Y1724763D03*
X1360827Y1723976D03*
Y1728700D03*
X1352953Y1734212D03*
X1510827Y1672007D03*
X1502953Y1677519D03*
Y1682244D03*
X1510827Y1681456D03*
Y1686180D03*
X1502953Y1691692D03*
Y1696417D03*
X1510827Y1695629D03*
Y1700354D03*
X1502953Y1705866D03*
Y1710590D03*
X1510827Y1709803D03*
Y1714527D03*
X1502953Y1720039D03*
Y1724763D03*
X1510827Y1723976D03*
Y1728700D03*
X1502953Y1734212D03*
X1526575Y1672007D03*
X1518701Y1677519D03*
Y1682244D03*
X1526575Y1681456D03*
Y1686180D03*
X1518701Y1691692D03*
Y1696417D03*
X1526575Y1695629D03*
Y1700354D03*
X1518701Y1705866D03*
Y1710590D03*
X1526575Y1709803D03*
Y1714527D03*
X1518701Y1720039D03*
Y1724763D03*
X1526575Y1723976D03*
Y1728700D03*
X1518701Y1734212D03*
X1542323Y1672007D03*
X1534449Y1677519D03*
Y1682244D03*
X1542323Y1681456D03*
Y1686180D03*
X1534449Y1691692D03*
Y1696417D03*
X1542323Y1695629D03*
Y1700354D03*
X1534449Y1705866D03*
Y1710590D03*
X1542323Y1709803D03*
Y1714527D03*
X1534449Y1720039D03*
Y1724763D03*
X1542323Y1723976D03*
Y1728700D03*
X1534449Y1734212D03*
X1558071Y1672007D03*
X1550197Y1677519D03*
Y1682244D03*
X1558071Y1681456D03*
Y1686180D03*
X1550197Y1691692D03*
Y1696417D03*
X1558071Y1695629D03*
Y1700354D03*
X1550197Y1705866D03*
Y1710590D03*
X1558071Y1709803D03*
Y1714527D03*
X1550197Y1720039D03*
Y1724763D03*
X1558071Y1723976D03*
Y1728700D03*
X1550197Y1734212D03*
X1569882Y1677519D03*
Y1682244D03*
Y1691692D03*
Y1696417D03*
Y1705866D03*
Y1710590D03*
Y1720039D03*
Y1724763D03*
Y1734212D03*
X1577756Y1672007D03*
X1585630Y1677519D03*
X1577756Y1681456D03*
X1585630Y1682244D03*
X1577756Y1686180D03*
X1585630Y1691692D03*
X1577756Y1695629D03*
X1585630Y1696417D03*
X1577756Y1700354D03*
X1585630Y1705866D03*
X1577756Y1709803D03*
X1585630Y1710590D03*
X1577756Y1714527D03*
X1585630Y1720039D03*
X1577756Y1723976D03*
X1585630Y1724763D03*
X1577756Y1728700D03*
X1585630Y1734212D03*
X1593504Y1672007D03*
X1601378Y1677519D03*
X1593504Y1681456D03*
X1601378Y1682244D03*
X1593504Y1686180D03*
X1601378Y1691692D03*
X1593504Y1695629D03*
X1601378Y1696417D03*
X1593504Y1700354D03*
X1601378Y1705866D03*
X1593504Y1709803D03*
X1601378Y1710590D03*
X1593504Y1714527D03*
X1601378Y1720039D03*
X1593504Y1723976D03*
X1601378Y1724763D03*
X1593504Y1728700D03*
X1601378Y1734212D03*
X1609252Y1672007D03*
X1617126Y1677519D03*
X1609252Y1681456D03*
X1617126Y1682244D03*
X1609252Y1686180D03*
X1617126Y1691692D03*
X1609252Y1695629D03*
X1617126Y1696417D03*
X1609252Y1700354D03*
X1617126Y1705866D03*
X1609252Y1709803D03*
X1617126Y1710590D03*
X1609252Y1714527D03*
X1617126Y1720039D03*
X1609252Y1723976D03*
X1617126Y1724763D03*
X1609252Y1728700D03*
X1617126Y1734212D03*
X1625000Y1672007D03*
Y1681456D03*
Y1686180D03*
Y1695629D03*
Y1700354D03*
Y1709803D03*
Y1714527D03*
Y1723976D03*
Y1728700D03*
G54D75*
X1886720Y1001463D03*
X1876720D03*
X1875836Y1303980D03*
X1885836D03*
X1886211Y1364167D03*
X1876211D03*
X1876165Y1669023D03*
X1886165D03*
X1897608Y1001506D03*
X1898086Y1305044D03*
X1897682Y1364479D03*
X1897402Y1670072D03*
X1907608Y1001506D03*
X1908086Y1305044D03*
X1907682Y1364479D03*
X1907402Y1670072D03*
X1935200Y1362732D03*
X1925200D03*
X1924695Y1670036D03*
X1934695D03*
X1946178Y1362781D03*
X1945484Y1670313D03*
X1967697Y1362790D03*
X1956178Y1362781D03*
X1966555Y1669946D03*
X1955484Y1670313D03*
X1977697Y1362790D03*
X1976555Y1669946D03*
X1988618Y1363081D03*
X1998618D03*
X1998147Y1669691D03*
X1988147D03*
G54D22*
X45812Y451602D03*
X61157Y69340D03*
X61470Y84622D03*
X62812Y412708D03*
X62813Y415750D03*
X49212Y451602D03*
X64557Y69340D03*
X72157Y75340D03*
X75557D03*
X64870Y84622D03*
X78120Y1515436D03*
Y1518836D03*
X64410Y1599102D03*
Y1602502D03*
X86557Y69340D03*
X83157D03*
X94157Y75340D03*
X90998Y1518937D03*
Y1515537D03*
X108557Y69340D03*
X105157D03*
X97557Y75340D03*
X127157Y69340D03*
X116157Y75340D03*
X119557D03*
X130557Y69340D03*
X138157Y75340D03*
X141557D03*
X152557Y69340D03*
X149157D03*
X175761D03*
X172361D03*
X161361Y75340D03*
X164761D03*
X183361D03*
X186761D03*
X197761Y69340D03*
X194361D03*
X205495Y75340D03*
X208895D03*
X194197Y1614292D03*
X197597D03*
X206257D03*
X194197Y1602380D03*
X197597D03*
X206257D03*
X219895Y69340D03*
X216495D03*
X209657Y1614292D03*
X218317D03*
X221717D03*
X209657Y1602380D03*
X218317D03*
X221717D03*
X227495Y75340D03*
X230895D03*
X230377Y1614292D03*
X233777D03*
X230377Y1602380D03*
X233777D03*
X242437Y1614292D03*
X254497D03*
X245837D03*
X242437Y1602380D03*
X254497D03*
X245837D03*
X266557Y1614292D03*
X257897D03*
X269957D03*
X266557Y1602380D03*
X257897D03*
X269957D03*
X278617Y1614292D03*
X282017D03*
X278617Y1602380D03*
X282017D03*
X290677Y1614292D03*
X302737D03*
X294077D03*
X306137D03*
X290677Y1602380D03*
X302737D03*
X294077D03*
X306137D03*
X314797Y1614292D03*
X318197D03*
X314797Y1602380D03*
X318197D03*
X330257Y1614292D03*
X338917D03*
X326857D03*
X330257Y1602380D03*
X338917D03*
X326857D03*
X350977Y1614292D03*
X342317D03*
X354377D03*
X350977Y1602380D03*
X342317D03*
X354377D03*
X363037Y1614292D03*
X366437D03*
X363037Y1602380D03*
X366437D03*
X375097Y1614292D03*
X378497D03*
X375097Y1602380D03*
X378497D03*
X478351Y1614292D03*
X481751D03*
X478351Y1602380D03*
X481751D03*
X490411Y1614292D03*
X493811D03*
X490411Y1602380D03*
X493811D03*
X514531Y1614292D03*
X502471D03*
X517931D03*
X505871D03*
X514531Y1602380D03*
X502471D03*
X517931D03*
X505871D03*
X519764Y40328D03*
X523164D03*
X519742Y71436D03*
X523142D03*
X526591Y1614292D03*
X529991D03*
X526591Y1602380D03*
X529991D03*
X538651Y1614292D03*
X542051D03*
X538651Y1602380D03*
X542051D03*
X555175Y71436D03*
X558575D03*
X562771Y1614292D03*
X550711D03*
X566171D03*
X554111D03*
X562771Y1602380D03*
X550711D03*
X566171D03*
X554111D03*
X574831Y1614292D03*
X578231D03*
X574831Y1602380D03*
X578231D03*
X598951Y1614292D03*
X586891D03*
X590291D03*
X598951Y1602380D03*
X586891D03*
X590291D03*
X613970Y188752D03*
X611011Y1614292D03*
X614411D03*
X602351D03*
X611011Y1602380D03*
X614411D03*
X602351D03*
X617370Y188752D03*
X630040D03*
X626640D03*
X623071Y1614292D03*
X626471D03*
X623071Y1602380D03*
X626471D03*
X647191Y1614292D03*
X635131D03*
X638531D03*
X647191Y1602380D03*
X635131D03*
X638531D03*
X656439Y47264D03*
X659839D03*
X662651Y1614292D03*
X659251D03*
X650591D03*
X662651Y1602380D03*
X659251D03*
X650591D03*
X723041Y-13200D03*
Y-9800D03*
Y-19800D03*
Y-23200D03*
X840001Y6800D03*
Y20200D03*
Y16800D03*
Y10200D03*
X902350Y208294D03*
X907470Y211980D03*
X902350Y204894D03*
X907470Y215380D03*
X902350Y219068D03*
X907470Y226154D03*
X902350Y222468D03*
X907470Y229554D03*
X953970Y208275D03*
X947496Y215397D03*
X953970Y204875D03*
X947496Y211997D03*
X957156Y227163D03*
X947496Y226135D03*
X957156Y230563D03*
X947496Y229535D03*
X980899Y-13200D03*
Y-9800D03*
Y-19800D03*
Y-23200D03*
Y6800D03*
Y20200D03*
Y16800D03*
Y10200D03*
X1032433Y-29811D03*
Y-33211D03*
Y-23211D03*
Y-19811D03*
Y-13211D03*
Y-9811D03*
Y-3211D03*
Y189D03*
X1156770Y638192D03*
X1153370D03*
X1161860Y642112D03*
X1165260D03*
X1173220Y636052D03*
X1169820D03*
X1183360Y642062D03*
X1186760D03*
X1196772Y1578182D03*
X1200172D03*
X1196772Y1590094D03*
X1200172D03*
X1212232Y1578182D03*
X1208832D03*
X1212232Y1590094D03*
X1208832D03*
X1220892Y1578182D03*
X1232952D03*
X1224292D03*
X1220892Y1590094D03*
X1232952D03*
X1224292D03*
X1245012Y1578182D03*
X1236352D03*
X1248412D03*
X1245012Y1590094D03*
X1236352D03*
X1248412D03*
X1257072Y1578182D03*
X1260472D03*
X1257072Y1590094D03*
X1260472D03*
X1269132Y1578182D03*
X1281192D03*
X1272532D03*
X1269132Y1590094D03*
X1281192D03*
X1272532D03*
X1290291Y-29811D03*
Y-33211D03*
Y-23211D03*
Y-19811D03*
Y-13211D03*
Y-9811D03*
Y-3211D03*
Y189D03*
X1293252Y1578182D03*
X1284592D03*
X1296652D03*
X1293252Y1590094D03*
X1284592D03*
X1296652D03*
X1305312Y1578182D03*
X1308712D03*
X1305312Y1590094D03*
X1308712D03*
X1317372Y1578182D03*
X1320772D03*
X1329432D03*
X1317372Y1590094D03*
X1320772D03*
X1329432D03*
X1341752Y-29811D03*
Y-33211D03*
Y-19811D03*
Y-23211D03*
Y-9811D03*
Y-13211D03*
Y189D03*
Y-3211D03*
X1344684Y280259D03*
X1332832Y1578182D03*
X1341492D03*
X1344892D03*
X1332832Y1590094D03*
X1341492D03*
X1344892D03*
X1348084Y280259D03*
X1358624Y284644D03*
X1355224D03*
X1353552Y1578182D03*
X1356952D03*
X1353552Y1590094D03*
X1356952D03*
X1380522Y260236D03*
Y263636D03*
X1368524Y282744D03*
X1365124D03*
X1378306Y657608D03*
X1374668Y659708D03*
X1378306Y669608D03*
X1374668Y671708D03*
Y683708D03*
X1378306Y681608D03*
X1374668Y695708D03*
X1378306Y693608D03*
Y705608D03*
X1374668Y707708D03*
Y719708D03*
X1378306Y717608D03*
X1365612Y1578182D03*
X1377672D03*
X1369012D03*
X1365612Y1590094D03*
X1377672D03*
X1369012D03*
X1384002Y197668D03*
X1389256D03*
X1380602D03*
X1392656D03*
X1380638Y245694D03*
X1386630Y238651D03*
X1380638Y249094D03*
X1386630Y242051D03*
X1388754Y253803D03*
Y257203D03*
X1386273Y268670D03*
Y272070D03*
X1393206Y664708D03*
X1389568Y662608D03*
X1393206Y679208D03*
X1389568Y677108D03*
X1393206Y693708D03*
X1389568Y691608D03*
Y706108D03*
X1393206Y708208D03*
X1393199Y722708D03*
X1389561Y720608D03*
X1385338Y735098D03*
X1388976Y737198D03*
X1381072Y1578182D03*
Y1590094D03*
X1412284Y171696D03*
X1398006Y197668D03*
X1406786D03*
X1401406D03*
X1410186D03*
X1407420Y220018D03*
X1410820D03*
X1404385Y240929D03*
X1400985D03*
X1415684Y171696D03*
X1436060Y220018D03*
X1432660D03*
X1457176Y656992D03*
X1460814Y654892D03*
Y666892D03*
X1457176Y668992D03*
X1460814Y678892D03*
X1457176Y680992D03*
X1460814Y690892D03*
X1457176Y704992D03*
Y692992D03*
X1460814Y702892D03*
X1457176Y716992D03*
X1460814Y714892D03*
X1472076Y657392D03*
Y671892D03*
X1475714Y659492D03*
Y673992D03*
X1472076Y686392D03*
X1475714Y688492D03*
X1472076Y700892D03*
X1475714Y702992D03*
X1472076Y715392D03*
X1475714Y717492D03*
X1468876Y728392D03*
X1472514Y730492D03*
X1467595Y1614292D03*
X1470995D03*
X1467595Y1602380D03*
X1470995D03*
X1482650Y-29811D03*
Y-33211D03*
Y-19811D03*
Y-23211D03*
Y-9811D03*
Y-13211D03*
Y189D03*
Y-3211D03*
X1491715Y1614292D03*
X1479655D03*
X1483055D03*
X1491715Y1602380D03*
X1479655D03*
X1483055D03*
X1503775Y1614292D03*
X1507175D03*
X1495115D03*
X1503775Y1602380D03*
X1507175D03*
X1495115D03*
X1515835Y1614292D03*
X1519235D03*
X1515835Y1602380D03*
X1519235D03*
X1538996Y69297D03*
X1535596D03*
X1527895Y1614292D03*
X1539955D03*
X1531295D03*
X1527895Y1602380D03*
X1539955D03*
X1531295D03*
X1557596Y69297D03*
X1546596Y75297D03*
X1549996D03*
X1552015Y1614292D03*
X1555415D03*
X1543355D03*
X1552015Y1602380D03*
X1555415D03*
X1543355D03*
X1560996Y69297D03*
X1568596Y75297D03*
X1571996D03*
X1564075Y1614292D03*
X1567475D03*
X1564075Y1602380D03*
X1567475D03*
X1582996Y69297D03*
X1579596D03*
X1590596Y75297D03*
X1588195Y1614292D03*
X1576135D03*
X1591595D03*
X1579535D03*
X1588195Y1602380D03*
X1576135D03*
X1591595D03*
X1579535D03*
X1604996Y69297D03*
X1601596D03*
X1593996Y75297D03*
X1600255Y1614292D03*
X1603655D03*
X1600255Y1602380D03*
X1603655D03*
X1623596Y69297D03*
X1612596Y75297D03*
X1615996D03*
X1612315Y1614292D03*
X1615715D03*
X1612315Y1602380D03*
X1615715D03*
X1626996Y69297D03*
X1635800Y75297D03*
X1639200D03*
X1636435Y1614292D03*
X1624375D03*
X1639835D03*
X1627775D03*
X1636435Y1602380D03*
X1624375D03*
X1639835D03*
X1627775D03*
X1650200Y69297D03*
X1646800D03*
X1651895Y1614292D03*
X1648495D03*
X1651895Y1602380D03*
X1648495D03*
X1672200Y69297D03*
X1668800D03*
X1657800Y75297D03*
X1661200D03*
X1679934D03*
X1683334D03*
X1694334Y69297D03*
X1690934D03*
X1705334Y75297D03*
X1701934D03*
G54D40*
X338042Y849978D03*
X331284Y978814D03*
X338211Y1118243D03*
X336361Y1121447D03*
X338211Y1131060D03*
X345178Y854584D03*
X348879Y860993D03*
X350729Y870606D03*
X354429D03*
X352578Y873810D03*
X354429Y883423D03*
X348879Y873810D03*
X347029Y877014D03*
X348878Y880219D03*
X343761Y999684D03*
X349311Y1105426D03*
X351162Y1127856D03*
X353011Y1118243D03*
X354861Y1121447D03*
X341912Y1118243D03*
X340061Y1127856D03*
X343761D03*
X347461Y1121447D03*
X340061D03*
X343761D03*
X347461Y1127856D03*
X345611Y1124651D03*
X347461Y1134264D03*
X354861D03*
X341911Y1131060D03*
X356278Y848176D03*
X371078D03*
X363678D03*
X371078Y867401D03*
X356278D03*
X363678D03*
X356278Y860993D03*
X371078D03*
X363678D03*
X358129Y870606D03*
X361829D03*
X365529D03*
X359978Y873810D03*
X367378D03*
X369229Y870606D03*
X356278Y880219D03*
X358129Y883423D03*
X363678Y880219D03*
X365529Y883423D03*
X371078Y880219D03*
X361829Y883423D03*
X369229D03*
X371078Y873810D03*
X356278D03*
X363678D03*
X363679Y893036D03*
X367379D03*
X359978Y886627D03*
X367378D03*
X363678D03*
X371078D03*
X367811Y1002888D03*
Y1105426D03*
X369661Y1102221D03*
X358562D03*
X360412Y1105426D03*
X358561Y1108630D03*
X360412Y1111834D03*
X364112Y1105426D03*
X369661Y1108630D03*
X362261D03*
X365961D03*
X367812Y1111834D03*
X369662Y1121447D03*
X362261D03*
X365961Y1115039D03*
X358561D03*
X369661D03*
X369662Y1134264D03*
X362262D03*
X385878Y848176D03*
X378478D03*
Y867401D03*
X385878D03*
X378478Y860993D03*
X385878D03*
X387729Y870606D03*
X372929D03*
X380329D03*
X374778Y873810D03*
X376629Y870606D03*
X382178Y873810D03*
X384029Y870606D03*
X372929Y883423D03*
X378478Y880219D03*
X380329Y883423D03*
X385878Y880219D03*
X387729Y883423D03*
X376629D03*
X384029D03*
X378478Y873810D03*
X385878D03*
X374778Y886627D03*
X382178D03*
X378478D03*
X385878D03*
X387729Y909057D03*
Y902649D03*
X385878Y905853D03*
X387729Y921875D03*
Y928283D03*
X385878Y925079D03*
X387729Y947509D03*
Y941100D03*
X385878Y944304D03*
X387729Y960326D03*
Y966735D03*
X385878Y963530D03*
Y982756D03*
X387729Y979552D03*
X376629D03*
X380329D03*
X374778Y976347D03*
X382178D03*
X372929Y973143D03*
X384029D03*
X386311Y1015705D03*
Y1034931D03*
Y1054157D03*
Y1073383D03*
Y1092608D03*
X375211Y1099017D03*
X380762Y1095813D03*
X382611Y1099017D03*
X384462Y1121447D03*
X377062D03*
X384462Y1134264D03*
X377062D03*
X400678Y848176D03*
X393278D03*
X400678Y867401D03*
X393278D03*
X400678Y860993D03*
X393278D03*
X391429Y870606D03*
X395129D03*
X402529D03*
X389578Y873810D03*
X396978D03*
X398829Y870606D03*
X393278Y880219D03*
X395129Y883423D03*
X400678Y880219D03*
X402529Y883423D03*
X391429D03*
X398829D03*
X393278Y873810D03*
X400678D03*
X402529Y896240D03*
X400678Y899445D03*
X389578D03*
X393278D03*
X393279Y893036D03*
X396979D03*
X396978Y886627D03*
X389578D03*
X398829Y896240D03*
X400678Y893036D03*
X393278Y886627D03*
X400678D03*
X404378Y899445D03*
X400678Y905853D03*
X402529Y915466D03*
Y909057D03*
X389578Y912262D03*
X393278D03*
X395129Y909057D03*
Y902649D03*
X393278Y905853D03*
X389578D03*
X396978D03*
X406229Y915466D03*
X400678Y912262D03*
X402529Y902649D03*
X400678Y931488D03*
X402529Y928283D03*
Y921875D03*
X393278Y931488D03*
X395129Y928283D03*
X389578Y918670D03*
X395129Y921875D03*
X393278Y918670D03*
X389578Y931488D03*
X393278Y925079D03*
X389578D03*
X396978D03*
X398829Y934691D03*
X402529D03*
X395129Y947509D03*
X389578Y937896D03*
X395129Y941100D03*
X393278Y937896D03*
Y944304D03*
X389578D03*
X396978D03*
X402529Y941100D03*
X400679Y944304D03*
X402529Y947509D03*
X389578Y957122D03*
X395129Y960326D03*
X393278Y957122D03*
X395129Y966735D03*
X389578Y950713D03*
X393278D03*
X396978Y963530D03*
X393278D03*
X389578D03*
X402529Y966735D03*
Y960326D03*
X398829Y953917D03*
X402529D03*
X400680Y950713D03*
X393278Y982756D03*
X389578D03*
X396978D03*
X393278Y976347D03*
X395129Y979552D03*
X389579Y976347D03*
X389578Y969939D03*
X393278D03*
X399262Y1006093D03*
X402962D03*
X399262Y999684D03*
X402962D03*
X388162Y1012501D03*
X395562D03*
X390011Y1009297D03*
X393711D03*
X401111D03*
X402962Y1012501D03*
Y1031727D03*
X397411Y1015705D03*
X388162Y1031727D03*
X390011Y1028523D03*
X395562Y1031727D03*
X393711Y1028523D03*
X390011Y1022114D03*
X388162Y1018910D03*
X393711Y1022114D03*
X395562Y1018910D03*
X401111Y1028523D03*
Y1022114D03*
X402960Y1018910D03*
X402962Y1025318D03*
X399262D03*
X401111Y1015705D03*
X390011Y1041340D03*
X388162Y1038136D03*
X393711Y1041340D03*
X395562Y1038136D03*
X390011Y1047749D03*
X393711D03*
Y1034931D03*
X390011D03*
X397411D03*
X401111Y1047749D03*
X399262Y1044544D03*
X402962D03*
X401111Y1041340D03*
X402962Y1038136D03*
X406662Y1057361D03*
X390011Y1060565D03*
X388162Y1057361D03*
X393711Y1060565D03*
X395562Y1057361D03*
X388162Y1050952D03*
X395562D03*
X393711Y1054157D03*
X390011D03*
X397411D03*
X402962Y1057361D03*
Y1063770D03*
X401113Y1060565D03*
X399262Y1063770D03*
X401111Y1054157D03*
X402962Y1050952D03*
Y1076587D03*
Y1070178D03*
X390011Y1079791D03*
X388162Y1076587D03*
X393711Y1079791D03*
X395562Y1076587D03*
X388162Y1070178D03*
X390011Y1066974D03*
X395562Y1070178D03*
X393711Y1066974D03*
Y1073383D03*
X390011D03*
X397411D03*
X401112Y1066974D03*
X395562Y1095813D03*
X388162Y1089404D03*
X390011Y1086200D03*
X395562Y1089404D03*
X393711Y1086200D03*
X388162Y1095813D03*
X393711Y1092608D03*
X390011D03*
X397411D03*
X399262Y1082995D03*
X393711Y1099017D03*
X390011D03*
X391862Y1102221D03*
X393711Y1105426D03*
X401111Y1099017D03*
X391862Y1108630D03*
X393711Y1111834D03*
X397411Y1105426D03*
X402962Y1108630D03*
Y1102221D03*
X395562Y1108630D03*
X399262D03*
X401111Y1111834D03*
X391862Y1121447D03*
X399262Y1115039D03*
X391862D03*
X402962D03*
X399262Y1121447D03*
X391862Y1134264D03*
X399262D03*
X408078Y848176D03*
X415478D03*
X408078Y867401D03*
X415478D03*
Y860993D03*
X408078D03*
X404378Y873810D03*
X406229Y870606D03*
X408078Y880219D03*
X409929Y883423D03*
X406229D03*
X419178Y873810D03*
X417329Y870606D03*
X411778Y873810D03*
X413629Y870606D03*
X415478Y873810D03*
X408078D03*
X404378Y886627D03*
X411778D03*
X404378Y893036D03*
X415478Y886627D03*
X408078D03*
X406229Y896240D03*
X408078Y899445D03*
X415478D03*
X409929Y896240D03*
X415478Y893036D03*
X417329Y896240D03*
X422878Y893036D03*
X411778Y899445D03*
X413629Y896240D03*
X419178Y899445D03*
X422878Y912262D03*
X417329Y909057D03*
X406229D03*
X413629D03*
Y915466D03*
X411778Y905853D03*
X408078D03*
Y912262D03*
X406229Y902649D03*
X415478Y905853D03*
X411778Y912262D03*
X415478D03*
X417329Y915466D03*
X411779Y918670D03*
X406229Y921875D03*
X408078Y918670D03*
X408569Y929108D03*
X406308Y928626D03*
X417329Y921875D03*
X411872Y925264D03*
X415479Y918670D03*
X407589Y942164D03*
X405289D03*
X409889D03*
X415185Y956620D03*
X411685D03*
X409385D03*
X417685D03*
X404785Y971100D03*
X407085D03*
X409385D03*
X411685D03*
X420205D03*
X412365Y985610D03*
X410065D03*
X420145Y985550D03*
X409385Y1014540D03*
X407085D03*
X411685D03*
X412385Y1000080D03*
X410085D03*
X420215Y1000040D03*
X420405Y1014470D03*
X414461Y1028855D03*
X411961D03*
X416961D03*
X419461D03*
X415911Y1047749D03*
X419611D03*
X406662Y1044544D03*
X410362D03*
X408511Y1047749D03*
X414062Y1044544D03*
X404811Y1041340D03*
X412211D03*
X415911D03*
X419611D03*
X406662Y1050952D03*
X414060D03*
X417762Y1057361D03*
X421462Y1050952D03*
X419611Y1054157D03*
X406662Y1063770D03*
X408511Y1060565D03*
X410362Y1063770D03*
X412211Y1054157D03*
X404811D03*
X414062Y1057361D03*
X410362D03*
X417762Y1063770D03*
X414062D03*
X419611Y1060565D03*
Y1079791D03*
X408511Y1073383D03*
X406662Y1070178D03*
X404811Y1073383D03*
X417762Y1076587D03*
X408511Y1066974D03*
X415911Y1079791D03*
X412211Y1073383D03*
X415911D03*
X414062Y1070178D03*
X417762D03*
X412211Y1066974D03*
X419611D03*
X419612Y1099017D03*
X404811Y1092608D03*
X417762Y1095813D03*
X414061D03*
X404811Y1099017D03*
X408511Y1105426D03*
X412211Y1111834D03*
X415911D03*
X414062Y1102221D03*
X417762Y1108630D03*
X419611Y1105426D03*
X408511Y1099017D03*
X410362Y1108630D03*
X408511Y1111834D03*
X412211Y1105426D03*
X419611Y1111834D03*
X415911Y1105426D03*
X415912Y1124651D03*
X419612D03*
Y1118243D03*
X417761Y1121447D03*
Y1127856D03*
X414062Y1115039D03*
X406661Y1121447D03*
X414062Y1127856D03*
X406662Y1134264D03*
X415912Y1137469D03*
Y1131060D03*
X414061Y1140973D03*
X419612Y1137469D03*
Y1131060D03*
X417761Y1134264D03*
Y1140973D03*
X412212Y1137469D03*
X422878Y848176D03*
X430278Y867401D03*
X422878D03*
X430278Y860993D03*
X422878D03*
X432129Y870606D03*
X426578Y873810D03*
X424729Y870606D03*
X433979Y873810D03*
X428429Y870606D03*
X421029D03*
X435829D03*
X422878Y873810D03*
X430278D03*
X422878Y886627D03*
X430278D03*
Y899445D03*
X422878D03*
X424729Y896240D03*
X430278Y893036D03*
X432129Y896240D03*
X437678Y893036D03*
X421029Y896240D03*
X426578Y899445D03*
X428429Y896240D03*
X433978Y899445D03*
X435829Y896240D03*
X424729Y915466D03*
X426578Y912262D03*
X430278D03*
X432129Y915466D03*
X421029Y909057D03*
X435829D03*
Y915466D03*
X432128Y909057D03*
X433978Y905853D03*
X424728Y909057D03*
X422878Y905853D03*
X430278D03*
X426578D03*
X421029Y915466D03*
X433979Y912262D03*
X430278Y918670D03*
X432129Y921875D03*
X433979Y918670D03*
X435829Y921875D03*
X424927Y927255D03*
X423176Y929465D03*
X422427Y927255D03*
X425676Y929465D03*
X424729Y921875D03*
X422878Y918670D03*
X421029Y921875D03*
X426578Y918670D03*
X430279Y925079D03*
X432130Y928283D03*
X430279Y931487D03*
X432130Y934692D03*
X435830Y928283D03*
X427875Y941930D03*
Y944230D03*
X430280Y944305D03*
X432130Y941101D03*
X435830D03*
X432129Y947510D03*
X435830D03*
Y934692D03*
X427875Y956373D03*
Y954073D03*
X422685Y956620D03*
X425185D03*
X430280Y957123D03*
X432129Y960327D03*
Y953918D03*
X430280Y950714D03*
X435830Y960327D03*
Y953918D03*
X432129Y966736D03*
X430280Y963531D03*
X435830Y966736D03*
X430268Y976348D03*
X432129Y973144D03*
X430280Y969940D03*
X427875Y971267D03*
X422685Y971100D03*
X427875Y968967D03*
X435830Y973144D03*
X430280Y982757D03*
X432129Y979553D03*
X427875Y983111D03*
X435830Y979553D03*
X422685Y985580D03*
X427875Y985411D03*
Y997521D03*
X430712Y1009298D03*
X427875Y1012152D03*
X430712Y1002889D03*
X427875Y999821D03*
X422685Y1000060D03*
X436263Y1006094D03*
Y999685D03*
X432562Y1006094D03*
Y999685D03*
X427875Y1014452D03*
X423015Y1014470D03*
X436263Y1012502D03*
X432562D03*
X421961Y1028855D03*
X430712Y1022115D03*
Y1015706D03*
X427875Y1026704D03*
X430712Y1028524D03*
X436263Y1018911D03*
X432562D03*
Y1025319D03*
X436263D03*
X427875Y1029004D03*
Y1031304D03*
X436263Y1031728D03*
X432562D03*
X427011Y1047749D03*
X427012Y1041340D03*
X423312D03*
X425162Y1044544D03*
X423285Y1036884D03*
X430711Y1041340D03*
X430712Y1034932D03*
X427875Y1033604D03*
X423285Y1032284D03*
Y1034584D03*
X436262Y1038137D03*
X436261Y1044544D03*
X432562Y1038137D03*
X434412Y1041340D03*
X432561Y1044544D03*
X434412Y1047749D03*
X421462Y1044544D03*
X427011Y1054157D03*
X430711D03*
X428861Y1057361D03*
X432561D03*
X421462D03*
X425162Y1050952D03*
X423311Y1054157D03*
X428862Y1050952D03*
X436262Y1057361D03*
Y1050952D03*
Y1063770D03*
X425162D03*
X423311Y1060565D03*
X427011D03*
X428861Y1063770D03*
X430711Y1060565D03*
X423311Y1073383D03*
X432560Y1070178D03*
X421462Y1076587D03*
X423311Y1079791D03*
X436262Y1070178D03*
Y1076587D03*
X421462Y1070178D03*
X425162D03*
X428862D03*
X430711Y1066974D03*
X428861Y1076587D03*
X430711Y1079791D03*
X436262Y1082995D03*
Y1089404D03*
X436261Y1095813D03*
X421462Y1102221D03*
X423311Y1099017D03*
X428861Y1108630D03*
X427012Y1105426D03*
X425162Y1108630D03*
X430711Y1105426D03*
Y1099017D03*
X428861Y1102221D03*
X436262Y1108630D03*
Y1102221D03*
X432561Y1108630D03*
Y1102221D03*
X434412Y1099017D03*
X430711Y1111834D03*
X427012D03*
X430711Y1124651D03*
X428861Y1121447D03*
X427012Y1124651D03*
X425162Y1121447D03*
X421461D03*
X430711Y1118243D03*
X428861Y1115039D03*
X427012Y1118243D03*
X425162Y1115039D03*
X436262Y1121447D03*
Y1115039D03*
X432561Y1121447D03*
Y1115039D03*
X428861Y1127856D03*
X425162D03*
X421461D03*
X436262D03*
X432561D03*
X430711Y1137769D03*
X427012Y1137569D03*
X430711Y1131060D03*
X428861Y1134264D03*
X427012Y1131060D03*
X425162Y1134264D03*
X421461D03*
X428861Y1140973D03*
X425161D03*
X421461D03*
X436261Y1134264D03*
X432561D03*
X452478Y867401D03*
X445078D03*
X437678D03*
X445078Y860993D03*
X452479D03*
X448779Y873810D03*
X446929Y870606D03*
X441378Y873810D03*
X439529Y870606D03*
X450629D03*
X443229D03*
X437679Y873810D03*
X452479D03*
X445078D03*
X452478Y886627D03*
X445078D03*
X452478Y899445D03*
X441378D03*
X445078Y893036D03*
X446929Y896240D03*
X452479Y893036D03*
X445078Y899445D03*
X443229Y896240D03*
X448778Y899445D03*
X450630Y896240D03*
X443229Y909057D03*
X439529Y915466D03*
X445079Y905853D03*
X441379D03*
X450630Y909057D03*
X452479Y905853D03*
X448779D03*
X448780Y912262D03*
X441380D03*
X439529Y909057D03*
X445080Y912262D03*
X443229Y915466D03*
X450629D03*
X452478Y912262D03*
X448779Y918670D03*
X454329Y915466D03*
X439529Y921875D03*
X441378Y918670D03*
X450629Y921875D03*
X445078Y918670D03*
X443229Y921875D03*
X452478Y918670D03*
X446930Y934692D03*
X443230Y928283D03*
X448780Y931487D03*
X437679D03*
X450630Y928283D03*
X448780Y925079D03*
X445079Y931487D03*
X439530Y934692D03*
X445079Y925079D03*
X439530Y928283D03*
X437679Y925079D03*
X437680Y944305D03*
X441380D03*
X443230Y941101D03*
X445079Y944305D03*
X439530Y941101D03*
X450630D03*
X448780Y944305D03*
X443229Y947510D03*
X439529D03*
X450630D03*
X443230Y934692D03*
X445079Y957123D03*
X437680D03*
X441380D03*
X439529Y960327D03*
X443229D03*
Y953918D03*
X439529D03*
X437680Y950714D03*
X441380D03*
X445079D03*
X448780Y957123D03*
X450630Y953918D03*
Y960327D03*
X448780Y950714D03*
X445079Y963531D03*
X437680D03*
X441380D03*
X439529Y966736D03*
X443229D03*
X448780Y963531D03*
X450630Y966736D03*
X445079Y976348D03*
Y969940D03*
X439529Y973144D03*
X443229D03*
X437680Y976348D03*
X441380D03*
X437680Y969940D03*
X441380D03*
X450630Y973144D03*
X448780Y976348D03*
Y969940D03*
X445079Y982757D03*
X437680D03*
X441380D03*
X439529Y979553D03*
X443229D03*
X448780Y982757D03*
X450630Y979553D03*
X439962Y1006094D03*
X443662D03*
X445511Y1009298D03*
X438113D03*
X441813D03*
X445512Y1002889D03*
X438113D03*
X441813D03*
X439962Y999685D03*
X443662D03*
X451062Y1006094D03*
X449213Y1009298D03*
Y1002889D03*
X451062Y999685D03*
X439962Y1012502D03*
X443662D03*
X451062D03*
X445511Y1022115D03*
X438113D03*
X441813D03*
X445512Y1015706D03*
X438113D03*
X439962Y1018911D03*
X441813Y1015706D03*
X443662Y1018911D03*
Y1025319D03*
X439962D03*
X445511Y1028524D03*
X441813D03*
X438113D03*
X449213Y1022115D03*
X451062Y1018911D03*
X449213Y1015706D03*
X451062Y1025319D03*
X449213Y1028524D03*
X439962Y1031728D03*
X443662D03*
X451062D03*
X452911Y1047749D03*
X439962Y1038137D03*
X443662D03*
X438112Y1041340D03*
X439961Y1044544D03*
X441812Y1041340D03*
X443661Y1044544D03*
X447361D03*
X445511Y1041340D03*
X445512Y1034932D03*
X438113D03*
X441813D03*
X451062Y1038137D03*
X449211Y1041340D03*
X449213Y1034932D03*
X445510Y1047749D03*
X441812D03*
X438112D03*
X449211Y1054157D03*
X449213Y1060565D03*
X438112D03*
Y1054157D03*
X439961Y1057361D03*
X441812Y1054157D03*
Y1060565D03*
X443661Y1057361D03*
X445511Y1060565D03*
Y1054157D03*
X439961Y1050952D03*
X443661D03*
X439961Y1063770D03*
X443661D03*
X451061D03*
X452911Y1054157D03*
X451062Y1050952D03*
X454762D03*
Y1057361D03*
X451062D03*
X451061Y1076587D03*
X452911Y1073383D03*
X439961Y1076587D03*
Y1070178D03*
X441812Y1073383D03*
X438112D03*
X443661Y1070178D03*
Y1076587D03*
X445511Y1073383D03*
X441812Y1066974D03*
X438112D03*
X445511D03*
X441812Y1079791D03*
X438112D03*
X445511D03*
X452911Y1066974D03*
X449211D03*
X451062Y1070178D03*
X452911Y1086200D03*
X443661Y1082995D03*
X439961D03*
X441812Y1086200D03*
X445511D03*
X439961Y1089404D03*
X441812Y1092608D03*
X438112D03*
X443661Y1089404D03*
X445511Y1092608D03*
X447361Y1089404D03*
X438112Y1086200D03*
X449211Y1092608D03*
X439961Y1095813D03*
X443661D03*
X447361D03*
X451060Y1082995D03*
X441812Y1105426D03*
X438112D03*
X439961Y1108630D03*
X443661D03*
X445511Y1105426D03*
X439961Y1102221D03*
X441812Y1099017D03*
X438112D03*
X443661Y1102221D03*
X445511Y1099017D03*
X452912Y1105426D03*
X451061Y1108630D03*
X449212Y1105426D03*
X451061Y1102221D03*
X449212Y1099017D03*
X441812Y1111834D03*
X438112D03*
X445511D03*
X452912D03*
X449212D03*
X438112Y1124651D03*
X439961Y1121447D03*
X441812Y1124651D03*
X445511D03*
X443661Y1121447D03*
X438112Y1118243D03*
X441812D03*
X439961Y1115039D03*
X445511Y1118243D03*
X443661Y1115039D03*
X452912Y1124651D03*
Y1118243D03*
X451061Y1121447D03*
X449212Y1124651D03*
Y1118243D03*
X451061Y1115039D03*
X439961Y1127856D03*
X443661D03*
X451061D03*
X441812Y1137769D03*
X438112D03*
X445511D03*
X443661Y1134264D03*
X441812Y1131060D03*
X439961Y1134264D03*
X438112Y1131060D03*
X445511D03*
X452912Y1137769D03*
Y1131060D03*
X449212Y1137769D03*
Y1131060D03*
X451061Y1134264D03*
X459878Y848176D03*
X467278D03*
Y867401D03*
X459878D03*
Y860993D03*
X467278D03*
X469129Y870606D03*
X463578Y873810D03*
X461729Y870606D03*
X456178Y873810D03*
X454329Y870606D03*
X465429D03*
X458029D03*
X467278Y873810D03*
X459878D03*
Y886627D03*
X467278D03*
X459878Y899445D03*
X467278D03*
X454329Y896240D03*
X459878Y893036D03*
X461729Y896240D03*
X467278Y893036D03*
X456178Y899445D03*
X458029Y896240D03*
X463578Y899445D03*
X465429Y896240D03*
X470978Y899445D03*
X463578Y905853D03*
X470980Y912262D03*
X469129Y902649D03*
X454329Y909057D03*
X470978Y918670D03*
X467278Y912262D03*
X469129Y915466D03*
X458029Y909057D03*
X459878Y905853D03*
X461729Y915466D03*
X467278Y905853D03*
X461729Y909057D03*
X458029Y915466D03*
X459878Y918670D03*
X463578Y912262D03*
X459878D03*
X469129Y909057D03*
X467278Y918670D03*
X454329Y921875D03*
X468236Y928349D03*
X465936D03*
X463636D03*
X461336D03*
X459036D03*
X469129Y921875D03*
X463578Y918670D03*
X465429Y921875D03*
X458029D03*
X469251Y942246D03*
X453585Y942238D03*
Y939938D03*
Y944538D03*
X453403Y956999D03*
X461424Y956620D03*
X458404D03*
X453403Y959299D03*
X468904Y956620D03*
Y971100D03*
X458404D03*
X461424Y971140D03*
X453403Y973099D03*
Y970799D03*
Y986899D03*
X461424Y985580D03*
X458404D03*
X453403Y984599D03*
X468904Y985580D03*
X453403Y998399D03*
Y1012199D03*
X458404Y1000080D03*
X461424D03*
X453403Y1000699D03*
X468904Y1000080D03*
X458404Y1014540D03*
X461295Y1014510D03*
X453403Y1014499D03*
X465680Y1028855D03*
X463180D03*
X460680D03*
X458180D03*
X457942Y1031909D03*
X467711Y1047750D03*
X460311D03*
X471411Y1041340D03*
X467711D03*
X454762Y1044544D03*
Y1038136D03*
X460971Y1037069D03*
X463271D03*
X458671D03*
X457942Y1034409D03*
X456611Y1041340D03*
X464011D03*
X462162Y1044544D03*
X458462D03*
X464011Y1054157D03*
X465860Y1050952D03*
X456611Y1060565D03*
X462161Y1057361D03*
Y1063770D03*
X460312Y1054157D03*
X458462Y1057361D03*
X467712Y1054157D03*
Y1060565D03*
X454761Y1063770D03*
X464012Y1060565D03*
X458460Y1050952D03*
X460311Y1060565D03*
Y1073383D03*
X458460Y1070178D03*
X460311Y1066974D03*
X464011D03*
X465860Y1070178D03*
X469560D03*
X464012Y1079791D03*
X460312D03*
X462162Y1076587D03*
X456611Y1066974D03*
X465862Y1076587D03*
X464011Y1073383D03*
X458462Y1076587D03*
X465862Y1082995D03*
X462162D03*
X462161Y1095812D03*
X458461D03*
X465861Y1089403D03*
X456612Y1092607D03*
X454761Y1089403D03*
X460311Y1086200D03*
X454760Y1082995D03*
X465861Y1095812D03*
X464012Y1092607D03*
X454761Y1095812D03*
X458461Y1089403D03*
X462161D03*
X467711Y1099017D03*
X462162Y1102221D03*
X458461Y1108630D03*
X456612Y1105426D03*
X454761Y1108630D03*
Y1102221D03*
X460312Y1111834D03*
X456611D03*
X460312Y1099016D03*
X464012Y1124651D03*
X462161Y1121447D03*
X460312Y1124651D03*
X456611D03*
X454761Y1121447D03*
X464011Y1118243D03*
X462161Y1115039D03*
X460312Y1118243D03*
X456611D03*
X454761Y1115039D03*
X462161Y1127856D03*
X454761D03*
X465861D03*
X464012Y1137469D03*
X460312D03*
X456612D03*
X464012Y1131060D03*
X462161Y1134264D03*
X460312Y1131060D03*
X456611D03*
X454761Y1134264D03*
X462161Y1140973D03*
X458461D03*
X454761D03*
X467712Y1137469D03*
X465861Y1134264D03*
X467712Y1131060D03*
X465861Y1140973D03*
X474678Y848176D03*
X482078D03*
X474678Y867401D03*
X482078D03*
X474678Y860993D03*
X482078D03*
X480229Y870606D03*
X476529D03*
X478378Y873810D03*
X483929Y870606D03*
X474678Y880219D03*
X476529Y883423D03*
X482078Y880219D03*
X483929Y883423D03*
X472829D03*
X480229D03*
X474678Y873810D03*
X482078D03*
X474678Y893036D03*
X472829Y896240D03*
X482078Y893036D03*
X483929Y896240D03*
X478378Y886627D03*
Y899445D03*
X474678Y886627D03*
X482078D03*
X476529Y896240D03*
Y915466D03*
X478380Y912262D03*
X478379Y918670D03*
X480229Y902649D03*
X483929Y915466D03*
X480229D03*
X472828D03*
X472829Y902649D03*
X480228Y909057D03*
X482078Y905853D03*
X476529Y902649D03*
X470978Y905853D03*
X478378D03*
X472829Y909057D03*
X476529D03*
X480229Y928283D03*
X478378Y931488D03*
Y925079D03*
X482078D03*
X472829Y921875D03*
X470536Y928349D03*
X478378Y937896D03*
X480229Y941100D03*
X483929Y934691D03*
X480229Y947509D03*
X471550Y942152D03*
X473851Y942246D03*
X478378Y963530D03*
X483929Y953917D03*
X480228Y960326D03*
X478378Y950713D03*
X480229Y953917D03*
X478378Y957122D03*
X471404Y956620D03*
X480229Y966735D03*
X482078Y963529D03*
X483929Y973143D03*
X482078Y982756D03*
X478379Y969939D03*
X476285Y973826D03*
Y971526D03*
X471404Y971100D03*
X473904D03*
X480229Y979552D03*
X478378Y982756D03*
X480229Y973143D03*
X478378Y976347D03*
X471404Y985580D03*
X480662Y999684D03*
X478811Y1002888D03*
Y1009297D03*
X480662Y1012501D03*
X484362Y1006093D03*
X471404Y1000080D03*
X484362Y1025318D03*
X480662Y1031727D03*
X482511Y1015705D03*
X480661Y1018910D03*
X478811Y1022114D03*
Y1028523D03*
Y1015705D03*
X476325Y1031795D03*
Y1027195D03*
Y1029495D03*
X470724Y1028827D03*
X480662Y1025318D03*
X484362Y1044544D03*
X475111Y1047749D03*
X469562Y1044544D03*
X478811Y1034931D03*
X480662Y1038136D03*
X478811Y1041340D03*
X480662Y1044544D03*
X473262D03*
X476962D03*
X478811Y1047749D03*
X484362Y1063770D03*
X473261Y1057361D03*
X471412Y1060565D03*
X475112Y1054157D03*
X469562Y1063770D03*
X469561Y1057361D03*
X473262Y1063770D03*
X469561Y1050952D03*
X473262D03*
X482511Y1054157D03*
X480662Y1063770D03*
X480661Y1057361D03*
X478812Y1060565D03*
X476962Y1063770D03*
Y1057361D03*
X478812Y1054157D03*
X476961Y1050952D03*
X478811Y1066974D03*
X471411D03*
X476962Y1076587D03*
X480662D03*
Y1070178D03*
X476962D03*
X473262Y1076587D03*
X469562D03*
X471411Y1073383D03*
Y1079791D03*
X475111Y1073383D03*
X482511D03*
X484362Y1082995D03*
X473262Y1095813D03*
X469562Y1082995D03*
X480662Y1089404D03*
X478812Y1092607D03*
X475112D03*
X473261Y1089403D03*
X471412Y1086199D03*
X476961Y1082994D03*
X482512Y1092607D03*
X476961Y1095812D03*
X471412Y1092607D03*
X475112Y1086199D03*
X478812D03*
X480662Y1102221D03*
X473262Y1121447D03*
X480662D03*
Y1134264D03*
X469561D03*
X489478Y848176D03*
X496878D03*
X489478Y867401D03*
X496878D03*
X489478Y860993D03*
X496878D03*
X487629Y870606D03*
X495029D03*
X485778Y873810D03*
X491329Y870606D03*
X493178Y873810D03*
X498729Y870606D03*
X500578Y873810D03*
X489478Y880219D03*
X491329Y883423D03*
X496878Y880219D03*
X498729Y883423D03*
X487629D03*
X495029D03*
X496878Y873810D03*
X489478D03*
X485778Y899445D03*
X493178D03*
Y893036D03*
X496878D03*
X485778D03*
X491329Y896240D03*
X487629D03*
X495029D03*
X485778Y886627D03*
X493178D03*
X500578D03*
X489478D03*
X496878D03*
X485778Y912262D03*
X487629Y909057D03*
X493178Y912262D03*
X491329Y909057D03*
X487629Y902649D03*
X491329D03*
X487629Y915466D03*
X495029D03*
X491329D03*
Y921875D03*
X493178Y918670D03*
X485778Y931488D03*
X491329Y928283D03*
X493178Y931488D03*
X487629Y928283D03*
Y921875D03*
X485778Y918670D03*
X487629Y947509D03*
X491329D03*
X487629Y941100D03*
X485778Y937896D03*
X491329Y941100D03*
X493178Y937896D03*
X487629Y934691D03*
X495029D03*
X491329D03*
X487629Y966735D03*
X491329D03*
X498729D03*
X496878Y963530D03*
X485778Y950713D03*
X493178D03*
X491329Y960326D03*
X493178Y957122D03*
X487629Y960326D03*
X485778Y957122D03*
X495029Y953917D03*
X487629D03*
X491329D03*
X495029Y973143D03*
X487629D03*
X491329D03*
X485778Y969939D03*
X493178D03*
X500578D03*
X495462Y1006093D03*
X486211Y1002888D03*
X493611D03*
X488062Y999684D03*
X491762D03*
X491761Y1012501D03*
X493611Y1009297D03*
X488062Y1012501D03*
X486211Y1009297D03*
X488062Y1031727D03*
X486211Y1028523D03*
X491762Y1031727D03*
X493611Y1028523D03*
X486211Y1022114D03*
X488062Y1018910D03*
X493611Y1022114D03*
X491762Y1018910D03*
X488062Y1025318D03*
X495462D03*
X491762D03*
X486211Y1047749D03*
X493611D03*
X486211Y1041340D03*
X488062Y1038136D03*
X493611Y1041340D03*
X491762Y1038136D03*
X488062Y1044544D03*
X495462D03*
X491762D03*
X486211Y1060565D03*
X488062Y1057361D03*
X493611Y1060565D03*
X491762Y1057361D03*
X488062Y1050952D03*
X491762D03*
X488062Y1063770D03*
X495462D03*
X491762D03*
X486211Y1079791D03*
X488062Y1076587D03*
X493611Y1079791D03*
X491762Y1076587D03*
X488062Y1070178D03*
X486211Y1066974D03*
X491762Y1070178D03*
X493611Y1066974D03*
X491762Y1089404D03*
X493611Y1086200D03*
X488062Y1089404D03*
X486211Y1086200D03*
X495462Y1082995D03*
X488062D03*
X491762D03*
X488062Y1095813D03*
X501012Y1105426D03*
Y1111833D03*
X488062Y1115039D03*
Y1121447D03*
X495462Y1134264D03*
X488062D03*
X511678Y848176D03*
X504278D03*
X511678Y867401D03*
X504278D03*
X511678Y860993D03*
X504278D03*
X517229Y870606D03*
X502429D03*
X509829D03*
X513529D03*
X515378Y873810D03*
X506129Y870606D03*
X507978Y873810D03*
X511678Y880219D03*
X513529Y883423D03*
X504278Y880219D03*
X506129Y883423D03*
X509829D03*
X517229D03*
X502429D03*
X511678Y873810D03*
X504278D03*
X515378Y886627D03*
X507978D03*
X511678D03*
X504278D03*
X506129Y966735D03*
X507978Y963530D03*
X504278Y969939D03*
X502862Y1006093D03*
X510262Y1102221D03*
X502861Y1108629D03*
X512112Y1105426D03*
X508412Y1111833D03*
X506561Y1102220D03*
X504712Y1111833D03*
Y1105426D03*
X510261Y1108630D03*
X512112Y1111833D03*
X508412Y1105426D03*
X502862Y1115039D03*
X510262Y1121447D03*
X502862D03*
X517662D03*
X506561Y1115038D03*
X510262Y1134264D03*
X502862D03*
X517662D03*
X519078Y848176D03*
Y867401D03*
X526479D03*
Y860993D03*
X519078D03*
X524629Y870606D03*
X532029D03*
X520929D03*
X522778Y873810D03*
X528329Y870606D03*
X530178Y873810D03*
X519078Y880219D03*
X520929Y883423D03*
X526479Y880219D03*
X528329Y883423D03*
X524629D03*
X526479Y873810D03*
X519078D03*
X530178Y893036D03*
X522778Y886627D03*
X530179D03*
X526479D03*
X519078D03*
X533879D03*
X528762Y1102221D03*
X525062D03*
X523212Y1099017D03*
X530611Y1105426D03*
X526911Y1118243D03*
X525062Y1121447D03*
X534311Y1118243D03*
X532461Y1121446D03*
X534311Y1124650D03*
X532461Y1127855D03*
X525062Y1134264D03*
X528761Y1140973D03*
X532461D03*
X541711Y1118243D03*
X538010Y1118242D03*
X543561Y1121446D03*
X539861Y1127855D03*
X536161D03*
Y1121446D03*
X539861D03*
X541711Y1124650D03*
X543561Y1127855D03*
X538012Y1131059D03*
X650599Y766798D03*
X918264Y506011D03*
X1030780Y1266532D03*
X1074480Y1263742D03*
X1181941Y766798D03*
X1297012Y157449D03*
X1293802Y159299D03*
Y166699D03*
X1293511Y179048D03*
X1296999Y183349D03*
X1297007Y172249D03*
X1296999Y175949D03*
X1293802Y170399D03*
X1294163Y175865D03*
X1296999Y179649D03*
Y194449D03*
Y198149D03*
Y190749D03*
Y187049D03*
Y201849D03*
X1293805Y211099D03*
X1293798Y205833D03*
X1296999Y216649D03*
X1293807Y218499D03*
Y214799D03*
X1296999Y212949D03*
Y205549D03*
X1294357Y224688D03*
X1296999Y224049D03*
X1293807Y222199D03*
X1300393Y235762D03*
X1303417Y164849D03*
X1300213Y162999D03*
X1300212Y166699D03*
X1306622D03*
X1309832Y157449D03*
X1306626Y162999D03*
Y159299D03*
X1313037Y162999D03*
X1309832Y164849D03*
X1313037Y159299D03*
X1303417Y157449D03*
X1300217Y159299D03*
X1313033Y166699D03*
X1300212Y170399D03*
X1306626D03*
X1303407Y183349D03*
X1309817Y175949D03*
X1300212Y174099D03*
X1313037Y170399D03*
X1306617Y185199D03*
X1309832Y172249D03*
X1313027Y181499D03*
Y185199D03*
X1303407Y175949D03*
Y179649D03*
X1306617Y177799D03*
X1309817Y179649D03*
X1300204Y181499D03*
X1309817Y194449D03*
X1306617Y188899D03*
X1303407Y194449D03*
X1306617Y196299D03*
X1300207D03*
X1303407Y190749D03*
Y187049D03*
X1300204Y188899D03*
X1313027Y192599D03*
X1309817Y190749D03*
X1313025Y188899D03*
X1309817Y198149D03*
X1303407D03*
X1300207Y203699D03*
Y207399D03*
X1309832Y209249D03*
X1313027Y203699D03*
X1300220Y218499D03*
X1309833Y220349D03*
X1303416Y205549D03*
X1306614Y203699D03*
X1306627Y214799D03*
X1316242Y209249D03*
X1300207Y211099D03*
X1303422Y220349D03*
X1300220Y222199D03*
X1313033D03*
X1303425Y224049D03*
X1300493Y238062D03*
X1314184Y849978D03*
X1307426Y978814D03*
X1314353Y1118243D03*
Y1131060D03*
X1319452Y162999D03*
X1316242Y168549D03*
X1319442Y159299D03*
X1316241Y157449D03*
X1316242Y164849D03*
X1322652D03*
X1329062D03*
X1326918Y161161D03*
X1329062Y157449D03*
X1322652D03*
X1325853Y174099D03*
X1331102Y179724D03*
Y182874D03*
Y186024D03*
X1325085Y176402D03*
X1324802Y179724D03*
Y186024D03*
Y182874D03*
X1315352Y186024D03*
Y179724D03*
X1319442Y174099D03*
X1332268D03*
X1324802Y195474D03*
X1327952D03*
X1318502D03*
X1321652D03*
X1327952Y201774D03*
X1321652D03*
X1331102Y189174D03*
X1315405Y189227D03*
X1329062Y212949D03*
X1325852Y211099D03*
X1319442D03*
X1324802Y204924D03*
X1327952D03*
X1318502D03*
X1315352D03*
X1322652Y209249D03*
X1325857Y218499D03*
X1322652Y216649D03*
X1329062Y220349D03*
X1325856Y222199D03*
X1322652Y224049D03*
Y220349D03*
X1321320Y854584D03*
X1325021Y860993D03*
X1326871Y870606D03*
X1330571D03*
X1328720Y873810D03*
X1330571Y883423D03*
X1325020Y873810D03*
X1323171Y877014D03*
X1325020Y880219D03*
X1319903Y999684D03*
X1325453Y1105426D03*
X1329153D03*
X1325454Y1111834D03*
X1327303Y1102221D03*
X1321753Y1111834D03*
X1318054D03*
X1318053Y1105426D03*
X1327304Y1108630D03*
X1329154Y1111834D03*
X1331003Y1102221D03*
X1319904Y1108630D03*
X1321753Y1105426D03*
X1327304Y1127856D03*
X1329153Y1118243D03*
X1331003Y1121447D03*
X1323603Y1115039D03*
X1331003Y1134264D03*
X1323603D03*
X1339727Y161149D03*
X1341992Y156897D03*
X1332268Y162999D03*
X1342903Y170399D03*
X1339727Y168549D03*
X1335472Y164849D03*
X1346140Y161149D03*
X1342937Y162999D03*
X1335472Y157449D03*
X1346140D03*
X1339727D03*
X1332268Y170399D03*
X1334252Y176574D03*
X1339727Y183349D03*
X1346137Y175949D03*
X1342937Y177799D03*
X1346137Y183349D03*
X1337901Y196035D03*
X1339727Y187049D03*
X1337345Y201831D03*
X1339727Y201849D03*
X1337402Y198624D03*
X1342937Y192599D03*
X1346137Y187049D03*
X1346147Y201849D03*
Y198149D03*
X1336527Y214799D03*
X1339727Y216649D03*
X1346147Y212949D03*
Y216649D03*
X1336527Y218499D03*
X1342937D03*
Y214799D03*
X1332262Y211099D03*
X1339686Y205478D03*
X1332262Y207399D03*
X1339727Y209249D03*
Y220349D03*
X1336527Y222199D03*
X1346147Y220349D03*
X1347220Y848176D03*
X1339820D03*
X1332420D03*
X1347220Y867401D03*
X1332420D03*
X1339820D03*
Y860993D03*
X1347220D03*
X1332420D03*
X1334271Y870606D03*
X1337971D03*
X1341671D03*
X1336120Y873810D03*
X1343520D03*
X1345371Y870606D03*
X1332420Y880219D03*
X1334271Y883423D03*
X1339820Y880219D03*
X1341671Y883423D03*
X1347220Y880219D03*
X1337971Y883423D03*
X1345371D03*
X1339820Y873810D03*
X1332420D03*
X1347220D03*
X1339821Y893036D03*
X1343521D03*
X1336120Y886627D03*
X1343520D03*
X1347220D03*
X1339820D03*
X1343953Y1002888D03*
X1334704Y1102221D03*
X1345803D03*
X1343953Y1105426D03*
X1336554D03*
X1345804Y1121447D03*
X1338403D03*
X1338404Y1134264D03*
X1345804D03*
X1352550Y157449D03*
X1355961Y155458D03*
X1352557Y168548D03*
X1355762Y166698D03*
X1349344Y162999D03*
X1348386Y156646D03*
X1352551Y161148D03*
X1352557Y172248D03*
X1349351Y177798D03*
Y170398D03*
Y174098D03*
Y192598D03*
X1352551Y187048D03*
X1355761Y188898D03*
X1349361Y199998D03*
X1352561Y201848D03*
X1355766Y214798D03*
X1349351Y218498D03*
X1352561Y216648D03*
X1355766Y218498D03*
X1352561Y220348D03*
X1355766Y222198D03*
X1360186Y226264D03*
X1362020Y848176D03*
X1354620D03*
Y867401D03*
X1362020D03*
Y860993D03*
X1354620D03*
X1363871Y870606D03*
X1349071D03*
X1356471D03*
X1350920Y873810D03*
X1352771Y870606D03*
X1358320Y873810D03*
X1360171Y870606D03*
X1349071Y883423D03*
X1354620Y880219D03*
X1356471Y883423D03*
X1362020Y880219D03*
X1363871Y883423D03*
X1352771D03*
X1360171D03*
X1354620Y873810D03*
X1362020D03*
X1350920Y886627D03*
X1358320D03*
X1354620D03*
X1362020D03*
X1363871Y909057D03*
Y902649D03*
X1362020Y905853D03*
X1363871Y921875D03*
Y928283D03*
X1362020Y925079D03*
X1363871Y947509D03*
Y941100D03*
X1362020Y944304D03*
X1363871Y960326D03*
Y966735D03*
X1362020Y963530D03*
Y982756D03*
X1363871Y979552D03*
X1352771D03*
X1356471D03*
X1350920Y976347D03*
X1358320D03*
X1349071Y973143D03*
X1360171D03*
X1362453Y1015705D03*
Y1034931D03*
Y1054157D03*
Y1073383D03*
Y1092608D03*
X1351354Y1099017D03*
X1356904Y1095813D03*
X1358753Y1099017D03*
X1362453Y1111834D03*
Y1105426D03*
X1358753D03*
X1351353Y1111834D03*
Y1105426D03*
X1358753Y1111834D03*
X1360604Y1108630D03*
X1355053Y1111834D03*
X1356904Y1102221D03*
X1353204Y1108630D03*
X1355054Y1105426D03*
X1360604Y1121447D03*
X1353204D03*
X1356904Y1115039D03*
X1353204Y1134264D03*
X1360604D03*
X1376820Y848176D03*
X1369420D03*
X1376820Y867401D03*
X1369420D03*
X1376820Y860993D03*
X1369420D03*
X1367571Y870606D03*
X1371271D03*
X1378671D03*
X1365720Y873810D03*
X1373120D03*
X1374971Y870606D03*
X1369420Y880219D03*
X1371271Y883423D03*
X1376820Y880219D03*
X1378671Y883423D03*
X1367571D03*
X1374971D03*
X1369420Y873810D03*
X1376820D03*
X1378671Y896240D03*
X1376820Y899445D03*
X1365720D03*
X1369420D03*
X1369421Y893036D03*
X1373121D03*
X1373120Y886627D03*
X1365720D03*
X1374971Y896240D03*
X1376820Y893036D03*
X1369420Y886627D03*
X1376820D03*
X1380520Y899445D03*
X1376820Y905853D03*
X1378671Y915466D03*
Y909057D03*
X1365720Y912262D03*
X1369420D03*
X1371271Y909057D03*
Y902649D03*
X1369420Y905853D03*
X1365720D03*
X1373120D03*
X1376820Y912262D03*
X1378671Y902649D03*
X1376820Y931488D03*
X1378671Y928283D03*
X1369420Y931488D03*
X1371271Y928283D03*
X1365720Y918670D03*
X1371271Y921875D03*
X1369420Y918670D03*
X1365720Y931488D03*
X1369420Y925079D03*
X1365720D03*
X1373120D03*
X1378671Y921875D03*
X1374971Y934691D03*
X1378671D03*
X1371271Y947509D03*
X1365720Y937896D03*
X1371271Y941100D03*
X1369420Y937896D03*
Y944304D03*
X1365720D03*
X1373120D03*
X1378671Y947509D03*
X1365720Y957122D03*
X1371271Y960326D03*
X1369420Y957122D03*
X1371271Y966735D03*
X1365720Y950713D03*
X1369420D03*
X1373120Y963530D03*
X1369420D03*
X1365720D03*
X1378671Y966735D03*
Y960326D03*
Y953917D03*
X1374971D03*
X1376822Y950713D03*
X1369420Y982756D03*
X1365720D03*
X1373120D03*
X1369420Y976347D03*
X1371271Y979552D03*
X1365721Y976347D03*
X1365720Y969939D03*
X1369420D03*
X1375404Y1006093D03*
X1379104D03*
X1375404Y999684D03*
X1379104D03*
X1364304Y1012501D03*
X1371704D03*
X1366153Y1009297D03*
X1369853D03*
X1377253D03*
X1379104Y1012501D03*
Y1031727D03*
X1373553Y1015705D03*
X1364304Y1031727D03*
X1366153Y1028523D03*
X1371704Y1031727D03*
X1369853Y1028523D03*
X1366153Y1022114D03*
X1364304Y1018910D03*
X1369853Y1022114D03*
X1371704Y1018910D03*
X1377253Y1028523D03*
X1375404Y1025318D03*
X1377253Y1022114D03*
X1379102Y1018910D03*
X1379104Y1025318D03*
X1377253Y1015705D03*
X1366153Y1041340D03*
X1364304Y1038136D03*
X1369853Y1041340D03*
X1371704Y1038136D03*
X1366153Y1047749D03*
X1369853D03*
Y1034931D03*
X1366153D03*
X1373553D03*
X1375404Y1044544D03*
X1377253Y1041340D03*
X1379104Y1044544D03*
Y1038136D03*
X1377253Y1047749D03*
X1366153Y1060565D03*
X1364304Y1057361D03*
X1369853Y1060565D03*
X1371704Y1057361D03*
X1364304Y1050952D03*
X1371704D03*
X1369853Y1054157D03*
X1366153D03*
X1373553D03*
X1379104Y1057361D03*
Y1063770D03*
X1377255Y1060565D03*
X1375404Y1063770D03*
X1377253Y1054157D03*
X1379104Y1050952D03*
X1380953Y1054157D03*
X1379104Y1076587D03*
Y1070178D03*
X1366153Y1079791D03*
X1364304Y1076587D03*
X1369853Y1079791D03*
X1371704Y1076587D03*
X1364304Y1070178D03*
X1366153Y1066974D03*
X1371704Y1070178D03*
X1369853Y1066974D03*
Y1073383D03*
X1366153D03*
X1373553D03*
X1377254Y1066974D03*
X1371704Y1095813D03*
X1364304Y1089404D03*
X1366153Y1086200D03*
X1371704Y1089404D03*
X1369853Y1086200D03*
X1364304Y1095813D03*
X1369853Y1092608D03*
X1366153D03*
X1373553D03*
X1375404Y1082995D03*
X1379104D03*
X1379103Y1089404D03*
X1369853Y1099017D03*
X1366153D03*
X1368004Y1102221D03*
X1369853Y1105426D03*
X1368004Y1121447D03*
X1375404D03*
X1368004Y1134264D03*
X1375404D03*
X1374847Y1153069D03*
X1391620Y848176D03*
X1384220D03*
Y867401D03*
X1391620D03*
X1384220Y860993D03*
X1391620D03*
X1380520Y873810D03*
X1382371Y870606D03*
X1384220Y880219D03*
X1386071Y883423D03*
X1382371D03*
X1395320Y873810D03*
X1393471Y870606D03*
X1387920Y873810D03*
X1389771Y870606D03*
X1391620Y873810D03*
X1384220D03*
X1380520Y886627D03*
X1387920D03*
X1380520Y893036D03*
X1382371Y896240D03*
X1384220Y886627D03*
X1391620D03*
Y899445D03*
X1384221Y899446D03*
X1393471Y909057D03*
X1382371D03*
X1389771D03*
Y915466D03*
X1399020Y905853D03*
X1382371Y915466D03*
X1384220Y918670D03*
X1387920Y905853D03*
X1384220D03*
Y912262D03*
X1382371Y902649D03*
X1391620Y905853D03*
X1387920Y912262D03*
X1391620D03*
X1393471Y915466D03*
X1391621Y918670D03*
X1382371Y921875D03*
X1382809Y927986D03*
X1385070Y928468D03*
X1393471Y921875D03*
X1391550Y925219D03*
X1387921Y918670D03*
X1386030Y942163D03*
X1383730D03*
X1381430D03*
X1392534Y942097D03*
X1394834D03*
X1393826Y956619D03*
X1387826D03*
X1391326D03*
X1385526D03*
X1380926Y971099D03*
X1383226D03*
X1387826D03*
X1385526D03*
X1396346D03*
X1396286Y985549D03*
X1388506Y985609D03*
X1386206D03*
X1385526Y1014539D03*
X1387826D03*
X1383226D03*
X1386226Y1000079D03*
X1396356Y1000039D03*
X1388526Y1000079D03*
X1396546Y1014469D03*
X1388102Y1028854D03*
X1390602D03*
X1393102D03*
X1395602D03*
X1380953Y1041340D03*
X1388353D03*
X1392053D03*
X1395753D03*
Y1047749D03*
X1392053D03*
X1382804Y1044544D03*
X1386504D03*
X1384653Y1047749D03*
X1390204Y1044544D03*
X1382804Y1050952D03*
Y1057361D03*
X1386504D03*
X1390204Y1050952D03*
X1393904Y1057361D03*
X1395753Y1054157D03*
X1382804Y1063770D03*
X1384653Y1060565D03*
X1386504Y1063770D03*
X1388353Y1054157D03*
X1390204Y1057361D03*
X1393904Y1063770D03*
X1390204D03*
X1395753Y1060565D03*
Y1079791D03*
X1384653Y1073383D03*
X1382804Y1070178D03*
X1380953Y1073383D03*
X1393904Y1076587D03*
X1392053Y1079791D03*
X1384653Y1066974D03*
X1388353Y1073383D03*
X1392053D03*
X1390204Y1070178D03*
X1393904D03*
X1388353Y1066974D03*
X1395753D03*
X1384653Y1079791D03*
X1395754Y1099017D03*
X1380953Y1092608D03*
X1393904Y1095813D03*
X1390203D03*
X1388353Y1086200D03*
X1386504Y1082995D03*
X1390204Y1089404D03*
X1382804D03*
X1390204Y1082995D03*
X1382804D03*
X1395753Y1086200D03*
Y1092608D03*
X1380953Y1086200D03*
X1386504Y1089404D03*
X1384653Y1092608D03*
X1392054Y1124651D03*
X1393903Y1121447D03*
Y1127856D03*
X1395754Y1118243D03*
Y1124651D03*
X1382803Y1121447D03*
X1390204Y1127856D03*
X1382804Y1134264D03*
X1390203Y1140973D03*
X1392054Y1131060D03*
Y1137469D03*
X1393903Y1134264D03*
Y1140973D03*
X1395754Y1131060D03*
Y1137469D03*
X1388354D03*
X1399020Y848176D03*
X1406420Y867401D03*
X1399020D03*
X1406420Y860993D03*
X1399020D03*
X1408271Y870606D03*
X1402720Y873810D03*
X1400871Y870606D03*
X1410121Y873810D03*
X1404571Y870606D03*
X1397171D03*
X1411971D03*
X1399020Y873810D03*
X1406420D03*
Y886627D03*
X1399020D03*
X1406420Y899445D03*
X1399020D03*
Y912262D03*
X1400871Y915466D03*
X1402720Y912262D03*
X1406420D03*
X1408271Y915466D03*
X1397171Y909057D03*
X1411971D03*
Y915466D03*
X1408270Y909057D03*
X1410120Y905853D03*
X1400870Y909057D03*
X1406420Y905853D03*
X1402720D03*
X1397171Y915466D03*
X1410121Y912262D03*
X1406420Y918670D03*
X1408271Y921875D03*
X1410121Y918670D03*
X1411971Y921875D03*
X1401528Y927155D03*
X1399028D03*
X1401817Y929464D03*
X1399317D03*
X1400871Y921875D03*
X1399020Y918670D03*
X1397171Y921875D03*
X1402720Y918670D03*
X1411971Y934691D03*
X1406420Y925079D03*
X1408271Y928283D03*
X1406420Y931488D03*
X1411971Y928283D03*
X1406421Y944304D03*
X1408271Y941100D03*
X1411971D03*
X1404016Y944229D03*
Y941929D03*
X1408270Y947509D03*
X1411971D03*
X1408271Y934691D03*
X1406421Y950713D03*
Y957122D03*
X1408270Y953917D03*
Y960326D03*
X1411971Y953917D03*
Y960326D03*
X1404016Y954072D03*
Y956372D03*
X1401326Y956619D03*
X1398826D03*
X1406421Y963530D03*
X1408270Y966735D03*
X1411971D03*
X1406421Y969939D03*
X1406409Y976347D03*
X1408270Y973143D03*
X1411971D03*
X1404016Y971266D03*
Y968966D03*
X1398826Y971099D03*
X1406421Y982756D03*
X1408270Y979552D03*
X1411971D03*
X1404016Y983110D03*
Y985410D03*
X1398826Y985579D03*
X1404016Y997520D03*
X1412404Y999684D03*
Y1006093D03*
Y1012501D03*
X1406853Y1002888D03*
Y1009297D03*
X1408703Y999684D03*
Y1006093D03*
Y1012501D03*
X1404016Y1012151D03*
Y999820D03*
X1398826Y1000059D03*
X1404016Y1014451D03*
X1399156Y1014469D03*
X1398102Y1028854D03*
X1406853Y1028523D03*
X1412404Y1018910D03*
X1406853Y1015705D03*
Y1022114D03*
X1408703Y1018910D03*
X1412404Y1025318D03*
X1408703D03*
X1404016Y1026703D03*
X1412404Y1031727D03*
X1408703D03*
X1404016Y1029003D03*
Y1031303D03*
X1403153Y1047749D03*
X1403154Y1041340D03*
X1399454D03*
X1401304Y1044544D03*
X1412403Y1038136D03*
Y1044544D03*
X1406853Y1034931D03*
Y1041340D03*
X1408703Y1038136D03*
Y1044544D03*
X1410554Y1041340D03*
X1404016Y1033603D03*
X1399426Y1036883D03*
Y1034583D03*
Y1032283D03*
X1410554Y1047749D03*
X1397604Y1044544D03*
X1403153Y1054157D03*
X1406853D03*
X1405003Y1057361D03*
X1408703D03*
Y1063770D03*
X1412404Y1050952D03*
Y1057361D03*
Y1063770D03*
X1397604Y1057361D03*
X1401304Y1050952D03*
X1399453Y1054157D03*
X1405004Y1050952D03*
X1397604D03*
X1401304Y1063770D03*
X1399453Y1060565D03*
X1403153D03*
X1405003Y1063770D03*
X1406853Y1060565D03*
X1397604Y1076587D03*
X1408702Y1070178D03*
X1399453Y1073383D03*
Y1079791D03*
X1412404Y1070178D03*
Y1076587D03*
X1397604Y1070178D03*
X1401304D03*
X1405004D03*
X1406853Y1066974D03*
X1412404Y1082995D03*
Y1089404D03*
X1412403Y1095813D03*
X1401304Y1082995D03*
X1405003Y1089404D03*
X1399453Y1086200D03*
X1406853Y1092608D03*
X1399453D03*
X1397604Y1089404D03*
X1403154Y1086200D03*
X1406852D03*
X1403153Y1092608D03*
X1401304Y1095813D03*
X1397604Y1102221D03*
X1399453Y1099017D03*
X1412404Y1102221D03*
Y1108630D03*
X1401304D03*
X1403154Y1105426D03*
Y1111834D03*
X1405003Y1102221D03*
Y1108630D03*
X1406853Y1099017D03*
Y1105426D03*
Y1111834D03*
X1408703Y1102221D03*
Y1108630D03*
X1410554Y1099017D03*
X1412404Y1115039D03*
Y1121447D03*
Y1127856D03*
X1397603Y1121447D03*
Y1127856D03*
X1401304Y1115039D03*
Y1121447D03*
Y1127856D03*
X1403154Y1118243D03*
Y1124651D03*
X1405003Y1115039D03*
Y1121447D03*
Y1127856D03*
X1406853Y1118243D03*
Y1124651D03*
X1408703Y1115039D03*
Y1121447D03*
Y1127856D03*
X1412403Y1134264D03*
X1397603D03*
Y1140973D03*
X1401304Y1134264D03*
X1401303Y1140973D03*
X1403154Y1131060D03*
Y1137569D03*
X1405003Y1134264D03*
Y1140973D03*
X1406853Y1131060D03*
Y1137769D03*
X1408703Y1134264D03*
X1428620Y867401D03*
X1421220D03*
X1413820D03*
X1421220Y860993D03*
X1428621D03*
X1424921Y873810D03*
X1423071Y870606D03*
X1417520Y873810D03*
X1415671Y870606D03*
X1426771D03*
X1419371D03*
X1413821Y873810D03*
X1428621D03*
X1421220D03*
X1428620Y899445D03*
Y886627D03*
X1421220D03*
X1419371Y909057D03*
X1415671Y915466D03*
X1421221Y905853D03*
X1417521D03*
X1430471Y909057D03*
X1426772D03*
X1428621Y905853D03*
X1424921D03*
X1424922Y912262D03*
X1417522D03*
X1415671Y909057D03*
X1421222Y912262D03*
X1419371Y915466D03*
X1426771D03*
X1428620Y912262D03*
X1424921Y918670D03*
X1430471Y915466D03*
X1415671Y921875D03*
X1417520Y918670D03*
X1426771Y921875D03*
X1421220Y918670D03*
X1419371Y921875D03*
X1428620Y918670D03*
X1424921Y931488D03*
X1419371Y928283D03*
X1413820Y931488D03*
X1424921Y925079D03*
X1419371Y934691D03*
X1421220Y931488D03*
Y925079D03*
X1415671Y928283D03*
X1413820Y925079D03*
X1426771Y928283D03*
X1413821Y944304D03*
X1415671Y941100D03*
X1417521Y944304D03*
X1419371Y941100D03*
X1421220Y944304D03*
X1424921D03*
X1426771Y941100D03*
X1415670Y947509D03*
X1419370D03*
X1426771D03*
X1423071Y934691D03*
X1415671D03*
X1413821Y950713D03*
Y957122D03*
X1415670Y953917D03*
Y960326D03*
X1417521Y950713D03*
Y957122D03*
X1419370Y953917D03*
Y960326D03*
X1421220Y950713D03*
Y957122D03*
X1424921Y950713D03*
Y957122D03*
X1426771Y953917D03*
Y960326D03*
X1413821Y963530D03*
X1415670Y966735D03*
X1417521Y963530D03*
X1419370Y966735D03*
X1421220Y963530D03*
X1424921D03*
X1426771Y966735D03*
X1413821Y969939D03*
Y976347D03*
X1415670Y973143D03*
X1417521Y969939D03*
Y976347D03*
X1419370Y973143D03*
X1421220Y969939D03*
Y976347D03*
X1424921Y969939D03*
Y976347D03*
X1426771Y973143D03*
X1413821Y982756D03*
X1415670Y979552D03*
X1417521Y982756D03*
X1419370Y979552D03*
X1421220Y982756D03*
X1424921D03*
X1426771Y979552D03*
X1414254Y1002888D03*
Y1009297D03*
X1416103Y999684D03*
Y1006093D03*
Y1012501D03*
X1417954Y1002888D03*
Y1009297D03*
X1419803Y999684D03*
Y1006093D03*
Y1012501D03*
X1421653Y1002888D03*
Y1009297D03*
X1425354Y1002888D03*
Y1009297D03*
X1427203Y999684D03*
Y1006093D03*
Y1012501D03*
X1421653Y1028523D03*
X1414254D03*
X1417954D03*
X1425354D03*
X1414254Y1015705D03*
Y1022114D03*
X1416103Y1018910D03*
X1417954Y1015705D03*
Y1022114D03*
X1419803Y1018910D03*
X1421653Y1015705D03*
Y1022114D03*
X1425354Y1015705D03*
Y1022114D03*
X1427203Y1018910D03*
X1416103Y1025318D03*
X1419803D03*
X1427203D03*
X1416103Y1031727D03*
X1419803D03*
X1427203D03*
X1429053Y1047749D03*
X1414254Y1034931D03*
Y1041340D03*
X1416103Y1038136D03*
Y1044544D03*
X1417954Y1034931D03*
Y1041340D03*
X1419803Y1038136D03*
Y1044544D03*
X1421653Y1034931D03*
Y1041340D03*
X1423503Y1044544D03*
X1425354Y1034931D03*
X1425353Y1041340D03*
X1427203Y1038136D03*
X1421653Y1047749D03*
X1414254D03*
X1417954D03*
X1425353Y1054157D03*
X1425355Y1060565D03*
X1414254Y1054157D03*
X1416103Y1050952D03*
X1417954Y1054157D03*
X1419803Y1050952D03*
X1421653Y1054157D03*
X1414254Y1060565D03*
X1416103Y1057361D03*
X1417954Y1060565D03*
X1419803Y1057361D03*
X1421653Y1060565D03*
X1416103Y1063770D03*
X1419803D03*
X1427203D03*
X1429053Y1054157D03*
X1427203Y1050952D03*
X1430903D03*
X1430904Y1057361D03*
X1427204D03*
X1429053Y1073383D03*
X1427203Y1076587D03*
X1414254Y1066974D03*
Y1073383D03*
X1416103Y1070178D03*
Y1076587D03*
X1417954Y1066974D03*
Y1073383D03*
X1419803Y1070178D03*
Y1076587D03*
X1421653Y1066974D03*
Y1073383D03*
X1414254Y1079791D03*
X1417954D03*
X1421653D03*
X1429053Y1066974D03*
X1425353D03*
X1427204Y1070178D03*
X1429053Y1086200D03*
X1416103Y1082995D03*
X1419803D03*
X1414254Y1086200D03*
Y1092608D03*
X1416103Y1089404D03*
Y1095813D03*
X1417954Y1086200D03*
Y1092608D03*
X1419803Y1089404D03*
Y1095813D03*
X1421653Y1086200D03*
Y1092608D03*
X1423503Y1089404D03*
Y1095813D03*
X1425353Y1092608D03*
X1427202Y1082995D03*
X1414254Y1099017D03*
Y1105426D03*
Y1111834D03*
X1416103Y1102221D03*
Y1108630D03*
X1417954Y1099017D03*
Y1105426D03*
Y1111834D03*
X1419803Y1102221D03*
Y1108630D03*
X1421653Y1099017D03*
Y1105426D03*
Y1111834D03*
X1425354Y1099017D03*
Y1105426D03*
Y1111834D03*
X1427203Y1102221D03*
Y1108630D03*
X1429054Y1105426D03*
Y1111834D03*
X1414254Y1118243D03*
Y1124651D03*
X1416103Y1115039D03*
Y1121447D03*
Y1127856D03*
X1417954Y1118243D03*
Y1124651D03*
X1419803Y1115039D03*
Y1121447D03*
Y1127856D03*
X1421653Y1118243D03*
Y1124651D03*
X1425354Y1118243D03*
Y1124651D03*
X1427203Y1115039D03*
Y1121447D03*
Y1127856D03*
X1429054Y1118243D03*
Y1124651D03*
X1414254Y1131060D03*
Y1137769D03*
X1416103Y1134264D03*
X1417954Y1131060D03*
Y1137769D03*
X1419803Y1134264D03*
X1421653Y1131060D03*
Y1137769D03*
X1425354Y1131060D03*
Y1137769D03*
X1427203Y1134264D03*
X1429054Y1131060D03*
Y1137769D03*
X1443420Y848176D03*
X1436020D03*
X1443420Y867401D03*
X1436020D03*
X1443420Y860993D03*
X1436020D03*
X1445271Y870606D03*
X1439720Y873810D03*
X1437871Y870606D03*
X1432320Y873810D03*
X1430471Y870606D03*
X1441571D03*
X1434171D03*
X1436020Y873810D03*
X1443420D03*
X1436020Y899445D03*
X1443420D03*
X1436020Y886627D03*
X1443420D03*
X1447120Y899445D03*
X1445271Y902649D03*
X1434171Y909057D03*
X1437871Y915466D03*
X1443420Y912262D03*
X1445271Y915466D03*
X1437871Y909057D03*
X1434171Y915466D03*
X1436020Y918670D03*
X1439720Y912262D03*
X1436020D03*
Y905853D03*
X1439720D03*
X1443420D03*
X1445271Y909057D03*
X1430471Y921875D03*
X1443420Y918670D03*
X1439777Y928348D03*
X1437477D03*
X1435177D03*
X1444377D03*
X1442077D03*
X1445271Y921875D03*
X1439720Y918670D03*
X1441571Y921875D03*
X1434171D03*
X1445392Y942195D03*
X1429726Y944537D03*
Y939937D03*
Y942237D03*
X1429544Y959298D03*
Y956998D03*
X1437565Y956619D03*
X1434545D03*
X1445045D03*
X1429544Y970798D03*
Y973098D03*
X1437565Y971139D03*
X1434545Y971099D03*
X1429544Y986898D03*
Y984598D03*
X1437565Y985579D03*
X1434545D03*
X1445045D03*
X1429544Y998398D03*
Y1012198D03*
Y1000698D03*
X1437565Y1000079D03*
X1434545D03*
X1445045D03*
X1429544Y1014498D03*
X1437436Y1014509D03*
X1434545Y1014539D03*
X1445036Y1014549D03*
X1439321Y1028854D03*
X1436821D03*
X1434321D03*
X1441821D03*
X1434083Y1031908D03*
X1447553Y1041340D03*
X1443853D03*
X1436453Y1047750D03*
X1443853D03*
X1430904Y1044544D03*
Y1038136D03*
X1434083Y1034408D03*
X1434813Y1037069D03*
X1439413D03*
X1437113D03*
X1432753Y1041340D03*
X1440153D03*
X1438304Y1044544D03*
X1434604D03*
X1432753Y1060565D03*
X1438303Y1057361D03*
Y1063770D03*
X1442002Y1050952D03*
X1440153Y1054157D03*
X1436454D03*
X1434604Y1057361D03*
X1443854Y1054157D03*
Y1060565D03*
X1430903Y1063770D03*
X1440154Y1060565D03*
X1434603Y1050952D03*
X1436453Y1060565D03*
Y1073383D03*
X1434602Y1070178D03*
X1436453Y1066974D03*
X1440153D03*
X1442002Y1070178D03*
X1447553Y1066974D03*
X1440154Y1079791D03*
X1436454D03*
X1438304Y1076587D03*
X1432753Y1066974D03*
X1442004Y1076587D03*
X1440153Y1073383D03*
X1434604Y1076587D03*
X1438304Y1082995D03*
X1442004D03*
X1438303Y1095812D03*
X1434603D03*
X1442003Y1089403D03*
X1432754Y1092607D03*
X1430903Y1089403D03*
X1436454Y1086199D03*
X1430902Y1082995D03*
X1442003Y1095812D03*
X1440154Y1092607D03*
X1430903Y1095812D03*
X1434603Y1089403D03*
X1438303D03*
X1438304Y1102221D03*
X1443853Y1099017D03*
X1430903Y1102221D03*
Y1108630D03*
X1432754Y1105426D03*
X1432753Y1111834D03*
X1434603Y1108630D03*
X1436454Y1111834D03*
Y1099016D03*
X1430903Y1115039D03*
Y1121447D03*
Y1127856D03*
X1432753Y1118243D03*
Y1124651D03*
X1436454Y1118243D03*
Y1124651D03*
X1438303Y1115039D03*
Y1121447D03*
Y1127856D03*
X1440153Y1118243D03*
X1440154Y1124651D03*
X1442003Y1127856D03*
X1443854Y1131060D03*
Y1137469D03*
X1430903Y1134264D03*
Y1140973D03*
X1432753Y1131060D03*
X1432754Y1137469D03*
X1434603Y1140973D03*
X1436454Y1131060D03*
Y1137469D03*
X1438303Y1134264D03*
Y1140973D03*
X1440154Y1131060D03*
Y1137469D03*
X1442003Y1134264D03*
Y1140973D03*
X1450820Y848176D03*
X1458220D03*
X1450820Y867401D03*
X1458220D03*
X1450820Y860993D03*
X1458220D03*
X1456371Y870606D03*
X1452671D03*
X1454520Y873810D03*
X1460071Y870606D03*
X1450820Y880219D03*
X1452671Y883423D03*
X1458220Y880219D03*
X1460071Y883423D03*
X1448971D03*
X1456371D03*
X1458220Y873810D03*
X1450820D03*
Y893036D03*
X1448971Y896240D03*
X1458220Y893036D03*
X1460071Y896240D03*
X1454520Y886627D03*
Y899445D03*
X1458220Y886627D03*
X1450820D03*
X1452671Y896240D03*
X1456371Y902649D03*
X1460071Y915466D03*
X1456371D03*
X1447122Y912262D03*
X1454521Y918670D03*
X1452671Y915466D03*
X1454522Y912262D03*
X1448971Y902649D03*
X1456370Y909057D03*
X1458220Y905853D03*
X1452671Y902649D03*
X1448970Y915466D03*
X1447120Y905853D03*
X1454520D03*
X1448971Y909057D03*
X1452671D03*
X1456371Y928283D03*
X1454522Y931488D03*
X1454520Y925079D03*
X1458220D03*
X1448971Y921875D03*
X1447120Y918670D03*
X1446677Y928348D03*
X1454520Y937896D03*
X1456371Y941100D03*
X1460071Y934691D03*
X1456371Y947509D03*
X1449992Y942195D03*
X1447692D03*
X1454520Y963530D03*
X1456371Y966735D03*
X1458220Y963529D03*
X1460071Y953917D03*
X1456370Y960326D03*
X1456371Y953917D03*
X1454520Y957122D03*
Y950713D03*
X1447545Y956619D03*
X1460071Y973143D03*
X1458220Y982756D03*
X1454521Y969939D03*
X1450045Y971099D03*
X1445445D03*
X1447745D03*
X1452426Y973825D03*
Y971525D03*
X1456371Y979552D03*
X1454520Y982756D03*
X1456371Y973143D03*
X1454520Y976347D03*
X1447545Y985579D03*
X1456804Y999684D03*
X1454953Y1002888D03*
Y1009297D03*
X1456804Y1012501D03*
X1460504Y1006093D03*
X1447545Y1000079D03*
X1447345Y1014539D03*
X1460504Y1025318D03*
X1456804Y1031727D03*
X1454953Y1028523D03*
Y1022114D03*
X1456803Y1018910D03*
X1454953Y1015705D03*
X1446934Y1028889D03*
X1452466Y1031794D03*
Y1029494D03*
Y1027194D03*
X1456804Y1025318D03*
X1458653Y1015705D03*
X1460504Y1044544D03*
X1451253Y1047749D03*
X1445704Y1044544D03*
X1454953Y1034931D03*
X1456804Y1038136D03*
X1454953Y1041340D03*
X1456804Y1044544D03*
X1449404D03*
X1454953Y1047749D03*
X1453104Y1044544D03*
X1460504Y1063770D03*
X1456804D03*
X1458653Y1054157D03*
X1454954D03*
X1453104Y1057361D03*
Y1063770D03*
X1454954Y1060565D03*
X1456803Y1057361D03*
X1453103Y1050952D03*
X1445703Y1057361D03*
X1445704Y1063770D03*
X1447554Y1060565D03*
X1449403Y1057361D03*
X1449404Y1063770D03*
X1451254Y1054157D03*
X1445703Y1050952D03*
X1449404D03*
X1454953Y1066974D03*
X1445702Y1070178D03*
X1453104Y1076587D03*
X1456804D03*
Y1070178D03*
X1453104D03*
X1447553Y1073383D03*
X1449404Y1076587D03*
X1445704D03*
X1447553Y1079791D03*
X1451253Y1073383D03*
X1458653D03*
X1460504Y1082995D03*
X1445704D03*
X1456804Y1089404D03*
X1449404Y1095813D03*
X1454954Y1092607D03*
X1451254D03*
X1449403Y1089403D03*
X1447554Y1086199D03*
X1453103Y1082994D03*
X1458654Y1092607D03*
X1453103Y1095812D03*
X1447554Y1092607D03*
X1451254Y1086199D03*
X1454954D03*
X1456804Y1102221D03*
Y1121447D03*
X1449404D03*
X1456804Y1134264D03*
X1445703D03*
X1465620Y848176D03*
X1473020D03*
X1465620Y867401D03*
X1473020D03*
X1465620Y860993D03*
X1473020D03*
X1463771Y870606D03*
X1471171D03*
X1461920Y873810D03*
X1467471Y870606D03*
X1469320Y873810D03*
X1474871Y870606D03*
X1476720Y873810D03*
X1465620Y880219D03*
X1467471Y883423D03*
X1473020Y880219D03*
X1474871Y883423D03*
X1463771D03*
X1471171D03*
X1473020Y873810D03*
X1465620D03*
X1461920Y899445D03*
X1469320D03*
Y893036D03*
X1473020D03*
X1461920D03*
X1467471Y896240D03*
X1463771D03*
X1471171D03*
X1461920Y886627D03*
X1469320D03*
X1476720D03*
X1473020D03*
X1465620D03*
X1461920Y912262D03*
X1463771Y909057D03*
X1469320Y912262D03*
X1467471Y909057D03*
X1463771Y902649D03*
X1467471D03*
X1463771Y915466D03*
X1471171D03*
X1467471D03*
Y921875D03*
X1469320Y918670D03*
X1461920Y931488D03*
X1467471Y928283D03*
X1469320Y931488D03*
X1463771Y928283D03*
Y921875D03*
X1461920Y918670D03*
X1463771Y947509D03*
X1467471D03*
X1463771Y941100D03*
X1461920Y937896D03*
X1467471Y941100D03*
X1469320Y937896D03*
X1463771Y934691D03*
X1471171D03*
X1467471D03*
X1463771Y966735D03*
X1467471D03*
X1474871D03*
X1473020Y963530D03*
X1461920Y950713D03*
X1469320D03*
X1467471Y960326D03*
X1469320Y957122D03*
X1463771Y960326D03*
X1461920Y957122D03*
X1471171Y953917D03*
X1463771D03*
X1467471D03*
X1471171Y973143D03*
X1463771D03*
X1467471D03*
X1461920Y969939D03*
X1469320D03*
X1476720D03*
X1471604Y1006093D03*
X1462353Y1002888D03*
X1469753D03*
X1464204Y999684D03*
X1467904D03*
X1467903Y1012501D03*
X1469753Y1009297D03*
X1464204Y1012501D03*
X1462353Y1009297D03*
X1464204Y1031727D03*
X1462353Y1028523D03*
X1467904Y1031727D03*
X1469753Y1028523D03*
X1462353Y1022114D03*
X1464204Y1018910D03*
X1469753Y1022114D03*
X1467904Y1018910D03*
X1464204Y1025318D03*
X1471604D03*
X1467904D03*
X1462353Y1047749D03*
X1469753D03*
X1462353Y1041340D03*
X1464204Y1038136D03*
X1469753Y1041340D03*
X1467904Y1038136D03*
X1464204Y1044544D03*
X1471604D03*
X1467904D03*
X1462353Y1060565D03*
X1464204Y1057361D03*
X1469753Y1060565D03*
X1467904Y1057361D03*
X1464204Y1050952D03*
X1467904D03*
X1464204Y1063770D03*
X1471604D03*
X1467904D03*
X1462353Y1079791D03*
X1464204Y1076587D03*
X1469753Y1079791D03*
X1467904Y1076587D03*
X1464204Y1070178D03*
X1462353Y1066974D03*
X1467904Y1070178D03*
X1469753Y1066974D03*
X1467904Y1089404D03*
X1469753Y1086200D03*
X1464204Y1089404D03*
X1462353Y1086200D03*
X1471604Y1082995D03*
X1464204D03*
X1467904D03*
X1464204Y1095813D03*
X1477154Y1105426D03*
Y1111833D03*
X1464204Y1115039D03*
Y1121447D03*
X1471604Y1134264D03*
X1464204D03*
X1487820Y848176D03*
X1480420D03*
X1487820Y867401D03*
X1480420D03*
X1487820Y860993D03*
X1480420D03*
X1493371Y870606D03*
X1478571D03*
X1485971D03*
X1489671D03*
X1491520Y873810D03*
X1482271Y870606D03*
X1484120Y873810D03*
X1487820Y880219D03*
X1489671Y883423D03*
X1480420Y880219D03*
X1482271Y883423D03*
X1485971D03*
X1493371D03*
X1478571D03*
X1487820Y873810D03*
X1480420D03*
X1491520Y886627D03*
X1484120D03*
X1480420D03*
X1487820D03*
X1482271Y966735D03*
X1484120Y963530D03*
X1480420Y969939D03*
X1479004Y1006093D03*
X1486404Y1102221D03*
X1479003Y1108629D03*
X1488254Y1105426D03*
X1484554Y1111833D03*
X1482703Y1102220D03*
X1480854Y1111833D03*
Y1105426D03*
X1486403Y1108630D03*
X1488254Y1111833D03*
X1484554Y1105426D03*
X1479004Y1115039D03*
Y1121447D03*
X1493804D03*
X1486404D03*
X1482703Y1115038D03*
X1479004Y1134264D03*
X1493804D03*
X1486404D03*
X1495220Y848176D03*
Y867401D03*
X1502621D03*
X1495220Y860993D03*
X1502621D03*
X1500771Y870606D03*
X1508171D03*
X1497071D03*
X1498920Y873810D03*
X1504471Y870606D03*
X1506321Y873810D03*
X1495220Y880219D03*
X1497071Y883423D03*
X1502621Y880219D03*
X1504471Y883423D03*
X1500771D03*
X1495220Y873810D03*
X1502621D03*
X1506320Y893036D03*
X1498920Y886627D03*
X1506321D03*
X1495220D03*
X1502621D03*
X1510021D03*
X1506753Y1105426D03*
X1504904Y1102221D03*
X1501204D03*
X1499354Y1099017D03*
X1503053Y1118243D03*
X1510453D03*
X1501204Y1121447D03*
X1508603Y1121446D03*
X1510453Y1124650D03*
X1508603Y1127855D03*
X1501204Y1134264D03*
X1508603Y1140973D03*
X1504903D03*
X1517853Y1118243D03*
X1519703Y1121446D03*
X1516003Y1127855D03*
X1512303D03*
Y1121446D03*
X1516003D03*
X1517853Y1124650D03*
X1519703Y1127855D03*
X1514154Y1131059D03*
X1611475Y1259227D03*
X1714440Y1255381D03*
X1821083Y1252034D03*
G54D39*
X322500Y1391830D03*
X537477Y1395413D03*
X1298642Y1391830D03*
X1513618Y1395413D03*
G54D10*
X27559Y87795D03*
X40708Y631890D03*
Y1368897D03*
X51181Y1714961D03*
X373622Y87795D03*
X395670Y1714961D03*
X661023Y631890D03*
X707677Y1714961D03*
X800787Y87795D03*
X931692Y757874D03*
Y1072834D03*
Y1387795D03*
X1045865Y87795D03*
X1155708Y1714961D03*
X1271260Y631890D03*
X1461805Y1714961D03*
X1499606Y87795D03*
X1816771Y631890D03*
Y1368897D03*
X1806299Y1714961D03*
X1829921Y87795D03*
G54D36*
X277098Y185236D03*
X395208D03*
G54D32*
X205159Y1430034D03*
X393067Y1354446D03*
X422833D03*
X453169D03*
X468443Y1379662D03*
X482543Y1353962D03*
X718638Y1429579D03*
X1178470Y1466363D03*
X1369208Y1353946D03*
X1398974D03*
X1429310D03*
X1444043Y1379362D03*
X1459076Y1353946D03*
X1679944Y1463655D03*
X1836248Y269763D03*
Y299056D03*
G54D30*
X174685Y637367D03*
X174393Y668511D03*
X526478Y1439952D03*
X1502956Y1439530D03*
X1682882Y618174D03*
Y669109D03*
X1769790Y194789D03*
X1799350D03*
G54D47*
X493500Y246362D03*
X559236Y1441207D03*
G54D50*
X688500Y1601900D03*
X1041435Y153357D03*
X1056225Y153131D03*
X1099970Y1702570D03*
G54D65*
X1133779Y1653543D03*
G54D37*
X278126Y676260D03*
Y700414D03*
X395771Y1242785D03*
X420171D03*
X444493D03*
X468893D03*
X493293D03*
X1371912D03*
X1396312D03*
X1420634D03*
X1445034D03*
X1469434D03*
G54D28*
X159474Y1320753D03*
X183847Y1320778D03*
X208247D03*
X275289Y575702D03*
Y599861D03*
Y624015D03*
Y648169D03*
X673093Y1320778D03*
X697466Y1320803D03*
X721866D03*
X1100800Y251488D03*
X1100700Y275788D03*
X1131100Y1357088D03*
X1155500D03*
X1179900D03*
X1577000Y591888D03*
Y616388D03*
Y640888D03*
Y665288D03*
Y689788D03*
Y714288D03*
X1634259Y1354374D03*
X1658632Y1354399D03*
X1683032D03*
G54D77*
X1902608Y988322D03*
X1902682Y1351295D03*
X1951178Y1349597D03*
X1993618Y1349897D03*
G54D74*
X1881720Y988279D03*
X1881211Y1350983D03*
X1930200Y1349548D03*
X1972697Y1349606D03*
G54D23*
X40120Y744554D03*
Y1000853D03*
Y1287664D03*
X69820Y744554D03*
Y1000853D03*
Y1287664D03*
X99520Y744554D03*
Y1000853D03*
Y1287664D03*
X129220Y744554D03*
Y1000853D03*
Y1287664D03*
X158920Y744554D03*
Y1000853D03*
Y1287664D03*
X188620Y744554D03*
Y1000853D03*
Y1287664D03*
X218320Y744554D03*
Y1000853D03*
Y1287664D03*
X248020Y744554D03*
Y1000853D03*
Y1287664D03*
X633320Y744554D03*
Y1000853D03*
Y1287664D03*
X663020Y744554D03*
Y1000853D03*
Y1287664D03*
X692720Y744554D03*
Y1000853D03*
Y1287664D03*
X722420Y744554D03*
Y1000853D03*
Y1287664D03*
X752120Y744554D03*
Y1000853D03*
Y1287664D03*
X781820Y744554D03*
Y1000853D03*
Y1287664D03*
X811520Y744554D03*
Y1000853D03*
Y1287664D03*
X841220Y744554D03*
Y1000853D03*
Y1287664D03*
X1016262Y744554D03*
Y1000853D03*
Y1287664D03*
X1045962Y744554D03*
Y1000853D03*
Y1287664D03*
X1075662Y744554D03*
Y1000853D03*
Y1287664D03*
X1105362Y744554D03*
Y1000853D03*
Y1287664D03*
X1135062Y744554D03*
Y1000853D03*
Y1287664D03*
X1164762Y744554D03*
Y1000853D03*
Y1287664D03*
X1194462Y744554D03*
Y1000853D03*
Y1287664D03*
X1224162Y744554D03*
Y1000853D03*
Y1287664D03*
X1609462Y744554D03*
Y1000853D03*
Y1287664D03*
X1639162Y744554D03*
Y1000853D03*
Y1287664D03*
X1668862Y744554D03*
Y1000853D03*
Y1287664D03*
X1698562Y744554D03*
Y1000853D03*
Y1287664D03*
X1728262Y744554D03*
Y1000853D03*
Y1287664D03*
X1757962Y744554D03*
Y1000853D03*
Y1287664D03*
X1787662Y744554D03*
Y1000853D03*
Y1287664D03*
X1817362Y744554D03*
Y1000853D03*
Y1287664D03*
G54D60*
X928739Y321653D03*
G54D33*
X250326Y185236D03*
X368437D03*
G54D61*
X916545Y309459D03*
X911494Y321653D03*
X916545Y333847D03*
X940933Y309459D03*
X928739Y304408D03*
Y338898D03*
X940933Y333847D03*
X945984Y321653D03*
G54D67*
X1247638Y269488D03*
X1405118Y112008D03*
X1766929Y1714960D03*
G54D13*
X19685Y-29134D03*
Y1803261D03*
X1837795Y-29134D03*
Y1803261D03*
X2081889Y-29134D03*
Y1803261D03*
G54D68*
X1405876Y1453298D03*
X1430204Y1452014D03*
G54D18*
X38346Y1420330D03*
X117932Y605380D03*
X763601Y605413D03*
X1094074Y605380D03*
X1739706Y605455D03*
X1819208Y1420330D03*
G54D21*
X49280Y337402D03*
X41870Y1511291D03*
X441043Y1672205D03*
Y1718465D03*
X1416437Y1672204D03*
Y1718464D03*
X1808192Y1569255D03*
X1812980Y502472D03*
G54D38*
X306772Y991220D03*
X350099Y811121D03*
X356063Y1171318D03*
X531240Y811121D03*
X525276Y1171318D03*
X574567Y991220D03*
X1282914D03*
X1326240Y811121D03*
X1332205Y1171318D03*
X1507382Y811121D03*
X1501418Y1171318D03*
X1550709Y991220D03*
G54D53*
X791280Y1704890D03*
X1066280D03*
G54D34*
X238780Y1648385D03*
X230906Y1644448D03*
X238780Y1662558D03*
X230906Y1658621D03*
X238780Y1676732D03*
X230906Y1672795D03*
X238780Y1690905D03*
X230906Y1686968D03*
X238780Y1705078D03*
X230906Y1701141D03*
Y1715314D03*
X238780Y1719251D03*
X230906Y1729488D03*
X238780Y1733425D03*
X254528Y1648385D03*
X246654Y1644448D03*
X254528Y1662558D03*
X246654Y1658621D03*
X254528Y1676732D03*
X246654Y1672795D03*
X254528Y1690905D03*
X246654Y1686968D03*
X254528Y1705078D03*
X246654Y1701141D03*
Y1715314D03*
X254528Y1719251D03*
X246654Y1729488D03*
X254528Y1733425D03*
X270276Y1648385D03*
X262402Y1644448D03*
X270276Y1662558D03*
X262402Y1658621D03*
X270276Y1676732D03*
X262402Y1672795D03*
X270276Y1690905D03*
X262402Y1686968D03*
X270276Y1705078D03*
X262402Y1701141D03*
Y1715314D03*
X270276Y1719251D03*
X262402Y1729488D03*
X270276Y1733425D03*
X286024Y1648385D03*
X278150Y1644448D03*
X286024Y1662558D03*
X278150Y1658621D03*
X286024Y1676732D03*
X278150Y1672795D03*
X286024Y1690905D03*
X278150Y1686968D03*
X286024Y1705078D03*
X278150Y1701141D03*
Y1715314D03*
X286024Y1719251D03*
X278150Y1729488D03*
X286024Y1733425D03*
X297835Y1672795D03*
X305709Y1676732D03*
X297835Y1686968D03*
X305709Y1690905D03*
X297835Y1701141D03*
X305709Y1705078D03*
X297835Y1715314D03*
X305709Y1719251D03*
X297835Y1729488D03*
X305709Y1733425D03*
X313583Y1672795D03*
X321457Y1676732D03*
X313583Y1686968D03*
X321457Y1690905D03*
X313583Y1701141D03*
X321457Y1705078D03*
X313583Y1715314D03*
X321457Y1719251D03*
X313583Y1729488D03*
X321457Y1733425D03*
X329331Y1672795D03*
X337205Y1676732D03*
X329331Y1686968D03*
X337205Y1690905D03*
X329331Y1701141D03*
X337205Y1705078D03*
X329331Y1715314D03*
X337205Y1719251D03*
X329331Y1729488D03*
X337205Y1733425D03*
X345079Y1672795D03*
X352953Y1676732D03*
X345079Y1686968D03*
X352953Y1690905D03*
X345079Y1701141D03*
X352953Y1705078D03*
X345079Y1715314D03*
X352953Y1719251D03*
X345079Y1729488D03*
X352953Y1733425D03*
X495079Y1672795D03*
Y1686968D03*
Y1701141D03*
Y1715314D03*
Y1729488D03*
X510827Y1672795D03*
X502953Y1676732D03*
X518701D03*
X510827Y1686968D03*
X502953Y1690905D03*
X518701D03*
X510827Y1701141D03*
X502953Y1705078D03*
X518701D03*
X510827Y1715314D03*
X502953Y1719251D03*
X518701D03*
X510827Y1729488D03*
X502953Y1733425D03*
X518701D03*
X526575Y1672795D03*
X534449Y1676732D03*
X526575Y1686968D03*
X534449Y1690905D03*
X526575Y1701141D03*
X534449Y1705078D03*
X526575Y1715314D03*
X534449Y1719251D03*
X526575Y1729488D03*
X534449Y1733425D03*
X542323Y1672795D03*
X550197Y1676732D03*
X542323Y1686968D03*
X550197Y1690905D03*
X542323Y1701141D03*
X550197Y1705078D03*
X542323Y1715314D03*
X550197Y1719251D03*
X542323Y1729488D03*
X550197Y1733425D03*
X562008Y1672795D03*
Y1686968D03*
Y1701141D03*
Y1715314D03*
Y1729488D03*
X577756Y1672795D03*
X569882Y1676732D03*
X577756Y1686968D03*
X569882Y1690905D03*
X577756Y1701141D03*
X569882Y1705078D03*
X577756Y1715314D03*
X569882Y1719251D03*
X577756Y1729488D03*
X569882Y1733425D03*
X593504Y1672795D03*
X585630Y1676732D03*
X593504Y1686968D03*
X585630Y1690905D03*
X593504Y1701141D03*
X585630Y1705078D03*
X593504Y1715314D03*
X585630Y1719251D03*
X593504Y1729488D03*
X585630Y1733425D03*
X609252Y1672795D03*
X601378Y1676732D03*
X609252Y1686968D03*
X601378Y1690905D03*
X609252Y1701141D03*
X601378Y1705078D03*
X609252Y1715314D03*
X601378Y1719251D03*
X609252Y1729488D03*
X601378Y1733425D03*
X617126Y1676732D03*
Y1690905D03*
Y1705078D03*
Y1719251D03*
Y1733425D03*
X1238780Y1672795D03*
X1246654Y1676732D03*
X1238780Y1686968D03*
X1246654Y1690905D03*
X1238780Y1701141D03*
X1246654Y1705078D03*
X1238780Y1715314D03*
X1246654Y1719251D03*
X1238780Y1729488D03*
X1246654Y1733425D03*
X1254528Y1672795D03*
X1262402Y1676732D03*
X1254528Y1686968D03*
X1262402Y1690905D03*
X1254528Y1701141D03*
X1262402Y1705078D03*
X1254528Y1715314D03*
X1262402Y1719251D03*
X1254528Y1729488D03*
X1262402Y1733425D03*
X1270276Y1672795D03*
X1278150Y1676732D03*
X1270276Y1686968D03*
X1278150Y1690905D03*
X1270276Y1701141D03*
X1278150Y1705078D03*
X1270276Y1715314D03*
X1278150Y1719251D03*
X1270276Y1729488D03*
X1278150Y1733425D03*
X1286024Y1672795D03*
X1293898Y1676732D03*
X1286024Y1686968D03*
X1293898Y1690905D03*
X1286024Y1701141D03*
X1293898Y1705078D03*
X1286024Y1715314D03*
X1293898Y1719251D03*
X1286024Y1729488D03*
X1293898Y1733425D03*
X1305709Y1672795D03*
X1313583Y1676732D03*
X1305709Y1686968D03*
X1313583Y1690905D03*
X1305709Y1701141D03*
X1313583Y1705078D03*
X1305709Y1715314D03*
X1313583Y1719251D03*
X1305709Y1729488D03*
X1313583Y1733425D03*
X1321457Y1672795D03*
X1329331Y1676732D03*
X1321457Y1686968D03*
X1329331Y1690905D03*
X1321457Y1701141D03*
X1329331Y1705078D03*
X1321457Y1715314D03*
X1329331Y1719251D03*
X1321457Y1729488D03*
X1329331Y1733425D03*
X1337205Y1672795D03*
X1345079Y1676732D03*
X1337205Y1686968D03*
X1345079Y1690905D03*
X1337205Y1701141D03*
X1345079Y1705078D03*
X1337205Y1715314D03*
X1345079Y1719251D03*
X1337205Y1729488D03*
X1345079Y1733425D03*
X1352953Y1672795D03*
X1360827Y1676732D03*
X1352953Y1686968D03*
X1360827Y1690905D03*
X1352953Y1701141D03*
X1360827Y1705078D03*
X1352953Y1715314D03*
X1360827Y1719251D03*
X1352953Y1729488D03*
X1360827Y1733425D03*
X1502953Y1672795D03*
X1510827Y1676732D03*
X1502953Y1686968D03*
X1510827Y1690905D03*
X1502953Y1701141D03*
X1510827Y1705078D03*
X1502953Y1715314D03*
X1510827Y1719251D03*
X1502953Y1729488D03*
X1510827Y1733425D03*
X1518701Y1672795D03*
X1526575Y1676732D03*
X1518701Y1686968D03*
X1526575Y1690905D03*
X1518701Y1701141D03*
X1526575Y1705078D03*
X1518701Y1715314D03*
X1526575Y1719251D03*
X1518701Y1729488D03*
X1526575Y1733425D03*
X1534449Y1672795D03*
X1542323Y1676732D03*
X1534449Y1686968D03*
X1542323Y1690905D03*
X1534449Y1701141D03*
X1542323Y1705078D03*
X1534449Y1715314D03*
X1542323Y1719251D03*
X1534449Y1729488D03*
X1542323Y1733425D03*
X1550197Y1672795D03*
X1558071Y1676732D03*
X1550197Y1686968D03*
X1558071Y1690905D03*
X1550197Y1701141D03*
X1558071Y1705078D03*
X1550197Y1715314D03*
X1558071Y1719251D03*
X1550197Y1729488D03*
X1558071Y1733425D03*
X1569882Y1672795D03*
Y1686968D03*
Y1701141D03*
Y1715314D03*
Y1729488D03*
X1585630Y1672795D03*
X1577756Y1676732D03*
X1585630Y1686968D03*
X1577756Y1690905D03*
X1585630Y1701141D03*
X1577756Y1705078D03*
X1585630Y1715314D03*
X1577756Y1719251D03*
X1585630Y1729488D03*
X1577756Y1733425D03*
X1601378Y1672795D03*
X1593504Y1676732D03*
X1601378Y1686968D03*
X1593504Y1690905D03*
X1601378Y1701141D03*
X1593504Y1705078D03*
X1601378Y1715314D03*
X1593504Y1719251D03*
X1601378Y1729488D03*
X1593504Y1733425D03*
X1617126Y1672795D03*
X1609252Y1676732D03*
X1625000D03*
X1617126Y1686968D03*
X1609252Y1690905D03*
X1625000D03*
X1617126Y1701141D03*
X1609252Y1705078D03*
X1625000D03*
X1617126Y1715314D03*
X1609252Y1719251D03*
X1625000D03*
X1617126Y1729488D03*
X1609252Y1733425D03*
X1625000D03*
G54D44*
X441043Y1698268D03*
X1416437Y1698267D03*
G54D55*
X805690Y204724D03*
X1057658D03*
G54D20*
X41492Y290637D03*
X44833Y1659909D03*
X61340Y384362D03*
X61250Y396142D03*
X49250Y396332D03*
X49400Y384392D03*
X47618Y413113D03*
X47619Y421155D03*
X56799Y1524094D03*
Y1528094D03*
Y1532094D03*
Y1544094D03*
Y1548094D03*
Y1552094D03*
Y1556094D03*
X54333Y1604359D03*
X50900Y1677775D03*
X65881Y305426D03*
X72774Y1549669D03*
X66906Y1598324D03*
Y1603280D03*
X84274Y1517619D03*
X81038Y1536899D03*
X91538Y1539399D03*
X84700Y1627000D03*
X99274Y1526019D03*
X126225Y504368D03*
X120225D03*
Y510368D03*
X126225Y516368D03*
X120225D03*
X112749Y1524594D03*
Y1540594D03*
Y1544594D03*
Y1548594D03*
Y1536594D03*
Y1564594D03*
Y1560594D03*
X132225Y504368D03*
Y510368D03*
X132401Y516368D03*
X129670Y1563160D03*
X153271Y1540961D03*
X153138Y1549032D03*
X166986Y575918D03*
X161321Y1540858D03*
X161374Y1549073D03*
X189800Y705062D03*
X208312Y576125D03*
X196526Y567825D03*
X208312Y581085D03*
Y578605D03*
X197423Y601496D03*
X194059Y604901D03*
X208312Y615085D03*
Y610125D03*
Y612605D03*
X194059Y638901D03*
X197423Y635496D03*
X208312Y649085D03*
Y644125D03*
Y646605D03*
X213912Y576125D03*
X220668Y574131D03*
X223775D03*
X224064Y568113D03*
X221464D03*
X213912Y578605D03*
Y581085D03*
X217556Y590575D03*
X217561Y582131D03*
Y579531D03*
X223775Y587731D03*
X223759Y590675D03*
X220652D03*
X223775Y584531D03*
X220668Y576731D03*
Y579331D03*
X223775Y581931D03*
Y579331D03*
Y576731D03*
X220668Y581931D03*
Y608131D03*
X223775D03*
X224064Y602113D03*
X221464D03*
X223403Y596820D03*
Y594220D03*
X213912Y612605D03*
Y615085D03*
Y610125D03*
X217561Y616131D03*
Y613531D03*
X217556Y624575D03*
X223759Y624675D03*
X220652D03*
X223775Y618531D03*
X220668Y610731D03*
Y613331D03*
X223775Y615931D03*
Y613331D03*
Y610731D03*
X220668Y615931D03*
X223775Y621731D03*
X223403Y630820D03*
Y628220D03*
X224064Y636113D03*
X221464D03*
X213912Y646605D03*
Y649085D03*
Y644125D03*
X217561Y650131D03*
Y647531D03*
X223775Y655731D03*
Y652531D03*
X220668Y644731D03*
Y647331D03*
Y642131D03*
X223775Y649931D03*
Y647331D03*
Y644731D03*
Y642131D03*
X220668Y649931D03*
X217556Y658575D03*
X223403Y664820D03*
X223759Y658675D03*
X220652D03*
X217510Y668712D03*
X225167Y672006D03*
X222567D03*
X219967D03*
X217367D03*
X211348Y688087D03*
Y685287D03*
X214100Y687376D03*
Y690376D03*
Y684376D03*
Y681376D03*
Y678376D03*
X211348Y690787D03*
Y693587D03*
X214100Y693576D03*
X224506Y698138D03*
Y700738D03*
X221906Y698138D03*
Y700738D03*
X219306D03*
Y698138D03*
X231864Y568113D03*
X229264D03*
X226664D03*
X238393Y570490D03*
X240993D03*
X229264Y602113D03*
X226664D03*
X226003Y594220D03*
Y596820D03*
X228603Y594220D03*
Y596820D03*
X231864Y602113D03*
X233803Y594220D03*
Y596820D03*
X231203Y594220D03*
Y596820D03*
X238393Y604490D03*
X240993D03*
Y596820D03*
X238393D03*
X240993Y594220D03*
X238393D03*
X226003Y628220D03*
Y630820D03*
X228603Y628220D03*
Y630820D03*
X231864Y636113D03*
X233803Y628220D03*
Y630820D03*
X231203Y628220D03*
Y630820D03*
X229264Y636113D03*
X226664D03*
X238393Y638490D03*
X240993D03*
Y630820D03*
X238393D03*
X240993Y628220D03*
X238393D03*
X228603Y664820D03*
X233803D03*
X231203D03*
X226003D03*
X230367Y672006D03*
X227767D03*
X227106Y698138D03*
Y700738D03*
X246400Y563162D03*
X263580Y218627D03*
X318651Y22921D03*
X320825Y159062D03*
X410700Y1658460D03*
X435340Y125346D03*
X435240Y1609200D03*
X433383Y1602629D03*
X450380Y104647D03*
X440019Y1576809D03*
X442128Y1574879D03*
X441308Y1602654D03*
X505055Y1387601D03*
Y1382301D03*
Y1396001D03*
Y1398601D03*
Y1390201D03*
X563634Y1334315D03*
X561034D03*
X612670Y142872D03*
X612520Y154812D03*
X624610Y142842D03*
X624520Y154622D03*
X702975Y414864D03*
X739206Y608020D03*
Y603064D03*
X758830Y1674823D03*
X819114Y115223D03*
X824498Y145198D03*
X831114Y115223D03*
X829114Y150273D03*
X854577Y99651D03*
X876124Y66072D03*
Y86072D03*
Y106072D03*
Y126072D03*
X887869Y386618D03*
X881372Y920655D03*
X898062Y976652D03*
Y969716D03*
X942646Y400793D03*
X946865Y974077D03*
X953235Y972642D03*
X946938Y991162D03*
X943720Y985772D03*
X956022Y1620730D03*
X953022D03*
Y1632730D03*
X956022D03*
Y1629730D03*
X953022D03*
X956022Y1626730D03*
X953022D03*
Y1623730D03*
X956022D03*
X963610Y981292D03*
X959535Y990477D03*
X963780Y997496D03*
X966852Y1585920D03*
X969852D03*
X960852D03*
X963852D03*
X957852D03*
X962022Y1620730D03*
X959022D03*
Y1632730D03*
X962022D03*
Y1629730D03*
X959022D03*
X962022Y1626730D03*
X959022D03*
Y1623730D03*
X962022D03*
X978403Y-9022D03*
Y-13978D03*
Y-19022D03*
Y-23978D03*
Y6022D03*
Y10978D03*
Y20978D03*
Y16022D03*
X988835Y185443D03*
X989500Y376362D03*
X985672Y432961D03*
X987662Y1620870D03*
Y1629870D03*
Y1626870D03*
Y1623870D03*
Y1632870D03*
X1002500Y266862D03*
X991770Y418835D03*
X992608Y432961D03*
X1002640Y594692D03*
X1002782Y1585920D03*
X999782D03*
X996782D03*
X990782D03*
X993782D03*
X990662Y1620870D03*
X993662D03*
Y1629870D03*
X990662D03*
X993662Y1626870D03*
X990662D03*
Y1623870D03*
X993662D03*
X990662Y1632870D03*
X993662D03*
X1001810Y1662700D03*
Y1665200D03*
X1018000Y263862D03*
X1022000Y264362D03*
X1014500Y263862D03*
X1010500D03*
X1018000Y266862D03*
X1010500D03*
X1006500D03*
X1014500D03*
X1011611Y430038D03*
X1021942Y1586090D03*
X1019252Y1620870D03*
X1022252D03*
Y1623870D03*
Y1626870D03*
X1019252Y1623870D03*
Y1626870D03*
X1019910Y1662700D03*
Y1665200D03*
X1025000Y264362D03*
X1038220Y589862D03*
X1030980Y598722D03*
X1023740Y596152D03*
X1036480Y596272D03*
X1030942Y1586090D03*
X1033942D03*
X1024942D03*
X1027942D03*
X1025252Y1620870D03*
Y1623870D03*
Y1626870D03*
X1023580Y1662700D03*
Y1665200D03*
X1027370Y1662700D03*
Y1665200D03*
X1040924Y286073D03*
X1043720Y589362D03*
X1050200Y598062D03*
X1050390Y604172D03*
X1053200Y612162D03*
X1053612Y1586010D03*
X1050721Y1633043D03*
X1053721D03*
Y1624043D03*
Y1627043D03*
Y1630043D03*
X1050721Y1624043D03*
Y1627043D03*
Y1630043D03*
X1053721Y1621043D03*
X1050721D03*
X1044850Y1665050D03*
Y1662550D03*
X1067718Y288500D03*
X1070618D03*
X1056280Y601232D03*
X1062612Y1586010D03*
X1065612D03*
X1056612D03*
X1059612D03*
X1056721Y1633043D03*
Y1624043D03*
Y1627043D03*
Y1630043D03*
Y1621043D03*
X1092302Y1585650D03*
X1089302D03*
X1098302D03*
X1095302D03*
X1095900Y1646935D03*
X1095649Y1638875D03*
X1099457D03*
X1104457Y1675490D03*
X1120544Y312200D03*
X1129995Y301637D03*
X1150914Y197407D03*
X1148354Y222677D03*
X1150272Y638346D03*
X1160720Y180862D03*
X1165000Y190962D03*
X1162500D03*
X1164300Y197262D03*
X1163732Y204887D03*
X1160732D03*
X1158172Y230157D03*
X1159912Y638216D03*
X1166722Y636206D03*
X1158762Y642266D03*
X1168402Y642136D03*
X1159930Y1645632D03*
X1164830D03*
X1161613Y1669112D03*
X1173065Y194174D03*
X1172865Y210174D03*
X1172795Y222174D03*
X1180398Y289814D03*
X1171540Y310902D03*
X1176362Y636076D03*
X1180262Y642216D03*
X1181930Y1645632D03*
X1186830D03*
X1175830D03*
X1170930D03*
X1183613Y1669112D03*
X1172613D03*
X1189902Y642086D03*
X1192500Y1645942D03*
X1197400D03*
X1194183Y1669422D03*
X1192340Y1691422D03*
X1197240D03*
X1194023Y1714902D03*
X1206093Y120362D03*
X1214593Y168962D03*
X1208518Y174162D03*
X1203858Y185451D03*
X1208365Y271151D03*
X1210457Y1658415D03*
X1218810Y1691732D03*
X1213910D03*
X1203110Y1691467D03*
X1208010D03*
X1215593Y1715212D03*
X1204793Y1714947D03*
X1228704Y112122D03*
X1223100Y127300D03*
X1226093Y152792D03*
X1227500Y380400D03*
X1242520Y165362D03*
X1236593Y209562D03*
X1236584Y217462D03*
X1245614Y227462D03*
X1266093Y129962D03*
X1256093Y143462D03*
X1264685Y175506D03*
X1279485Y105752D03*
X1278949Y123567D03*
X1282293Y248962D03*
X1275557Y269477D03*
Y272436D03*
X1282653Y269446D03*
X1278557Y272436D03*
Y269477D03*
X1272557Y272436D03*
X1287795Y-29033D03*
Y-33989D03*
Y-9033D03*
Y-13989D03*
Y-19033D03*
Y-23989D03*
Y967D03*
Y-3989D03*
X1293430Y84072D03*
X1294354Y105912D03*
X1295053Y140181D03*
X1292293Y143162D03*
X1287943Y233748D03*
X1284437Y230280D03*
X1293893Y237962D03*
X1286611Y260908D03*
X1295887Y315571D03*
X1314741Y68652D03*
X1300454Y95302D03*
X1302964Y124633D03*
X1301993Y140462D03*
X1313950Y261612D03*
X1308790Y290172D03*
X1302450Y290072D03*
X1307798Y287561D03*
X1313246Y287631D03*
X1308220Y304262D03*
X1303120Y304162D03*
X1330102Y59025D03*
X1327920Y84418D03*
X1316478Y92970D03*
X1330273Y128373D03*
X1326493Y249562D03*
X1317893Y257462D03*
X1328393Y264262D03*
X1339280Y126175D03*
X1356223Y131569D03*
X1362793Y145262D03*
X1366124Y101529D03*
X1377597Y197604D03*
X1375300Y208422D03*
X1378452Y236055D03*
X1389609Y145291D03*
X1389443Y147859D03*
X1386780Y197668D03*
X1395321D03*
X1409558Y151948D03*
Y156904D03*
X1401240Y171672D03*
X1404071Y197668D03*
X1412851D03*
X1398700Y1597800D03*
X1436436Y300319D03*
X1456423Y209362D03*
X1453823Y205982D03*
X1445777Y362021D03*
X1449296Y410497D03*
X1451580Y1627990D03*
X1462777Y362021D03*
X1470877Y374496D03*
X1463277Y406446D03*
X1470954D03*
X1476570Y1657974D03*
X1480154Y-29033D03*
Y-33989D03*
Y-9033D03*
Y-13989D03*
Y-19033D03*
Y-23989D03*
Y967D03*
Y-3989D03*
X1481155Y1387742D03*
X1481255Y1382042D03*
X1481155Y1396342D03*
Y1398942D03*
Y1390342D03*
X1478724Y1637189D03*
X1505821Y215802D03*
X1524770Y195792D03*
X1521201Y215551D03*
X1531750Y199762D03*
X1529610Y211614D03*
X1532590Y225432D03*
X1561494Y584292D03*
X1604040Y219692D03*
X1604290Y242472D03*
X1636393Y181778D03*
X1632899Y213012D03*
X1670004Y537065D03*
Y543065D03*
Y531065D03*
X1683394Y469878D03*
X1683476Y473378D03*
X1684356Y476290D03*
X1681602Y485180D03*
X1684356Y485628D03*
X1677464Y491790D03*
X1682004Y537065D03*
X1682180Y543065D03*
X1676004D03*
X1682004Y531065D03*
X1676004D03*
X1697648Y463724D03*
X1693648D03*
X1692883Y703943D03*
X1709027Y655141D03*
X1725473Y474859D03*
X1754307Y262186D03*
X1751068Y262123D03*
X1754245Y269724D03*
X1751068Y266048D03*
X1754307Y266111D03*
X1754414Y275329D03*
X1752165Y273901D03*
X1749565D03*
X1751006Y269661D03*
X1749595Y276711D03*
X1752195D03*
X1748989Y380206D03*
X1764955Y301951D03*
X1768757Y380498D03*
X1793061Y24659D03*
X1828880Y1626595D03*
Y1646595D03*
Y1666595D03*
Y1686595D03*
X1840691Y329470D03*
Y349470D03*
Y369470D03*
Y389470D03*
Y409470D03*
Y429470D03*
Y449470D03*
Y469470D03*
Y489470D03*
Y509470D03*
Y529470D03*
Y549470D03*
Y569470D03*
Y589470D03*
Y669470D03*
Y1329470D03*
Y1409470D03*
Y1429470D03*
Y1449470D03*
Y1469470D03*
Y1489470D03*
Y1509470D03*
Y1529470D03*
Y1549470D03*
Y1569470D03*
Y1589470D03*
X1854470Y112379D03*
Y152379D03*
Y172379D03*
Y192379D03*
Y212379D03*
Y232379D03*
Y252379D03*
Y272379D03*
Y292379D03*
G54D59*
X922441Y154311D03*
Y243799D03*
G54D12*
X14092Y287115D03*
X17371Y49388D03*
X22223Y388057D03*
X29509Y398132D03*
X29962Y401000D03*
X24700Y765600D03*
X37371Y49388D03*
X36255Y304972D03*
X42809Y360862D03*
X39410Y384582D03*
X39226Y395346D03*
X33020Y382822D03*
X36524Y398013D03*
X30680Y438142D03*
X58379Y69340D03*
X60379Y66844D03*
Y71836D03*
X60692Y87118D03*
X54920Y185039D03*
Y177165D03*
X46834Y360862D03*
X55190D03*
X53825Y421746D03*
X54762Y444993D03*
X53800Y435451D03*
X58658Y754145D03*
X55177Y1322328D03*
X55277Y1326068D03*
X46994Y1663165D03*
X69058Y3010D03*
X79047Y23978D03*
X74091D03*
X72091Y25974D03*
X73020Y37106D03*
Y48720D03*
X67335Y69340D03*
X65335Y66844D03*
Y71836D03*
X65648Y87118D03*
X71379Y72844D03*
Y77836D03*
X76335Y72844D03*
Y77836D03*
X78335Y75340D03*
X69379D03*
X71772Y421746D03*
X75490Y432519D03*
X68365Y443677D03*
X64150Y434972D03*
X74340Y663422D03*
X76365Y699244D03*
X76565Y717949D03*
X72315Y717414D03*
X64325Y715674D03*
X75564Y1509952D03*
X78120Y1512936D03*
Y1521336D03*
X75922Y1564874D03*
Y1556474D03*
X73429Y1570008D03*
X78415D03*
X73832Y1689362D03*
X77833Y1689162D03*
X89058Y3010D03*
X81196Y17042D03*
Y22034D03*
X86152Y17042D03*
Y22034D03*
X95369Y17042D03*
Y22034D03*
X79196Y19538D03*
X88152D03*
X93369D03*
X88264Y23978D03*
X93220D03*
X86264Y25974D03*
X95220D03*
X81047D03*
X94279Y37106D03*
X87193D03*
X80106D03*
X94279Y48720D03*
X87193D03*
X80106D03*
X80379Y69340D03*
X89335D03*
X82379Y66844D03*
Y71836D03*
X87335Y66844D03*
Y71836D03*
X91379Y75340D03*
X93379Y72844D03*
Y77836D03*
X86490Y200787D03*
Y208661D03*
X85960Y224409D03*
X85788Y240157D03*
X90700Y282762D03*
Y300262D03*
X87654Y376026D03*
X87520Y386502D03*
X94811Y510173D03*
X80460Y655672D03*
X83100Y649762D03*
X82735Y717949D03*
X87865Y714394D03*
X85165D03*
X81225Y715854D03*
X79635Y717949D03*
X85835Y718049D03*
X93295Y762019D03*
X92071Y1492888D03*
X80649Y1509944D03*
X93544Y1510099D03*
X88459Y1510107D03*
X90998Y1513037D03*
Y1521437D03*
X84048Y1578008D03*
X90713Y1585852D03*
Y1589852D03*
Y1593867D03*
X90788Y1611821D03*
Y1605867D03*
Y1623821D03*
X90698Y1638362D03*
Y1634362D03*
X86245Y1690362D03*
X81833Y1689162D03*
X94220Y1686622D03*
X109058Y3010D03*
X100325Y17042D03*
Y22034D03*
X109542Y17042D03*
Y22034D03*
X102325Y19538D03*
X107542D03*
X102437Y23978D03*
X107393D03*
X100437Y25974D03*
X109393D03*
X108453Y37106D03*
X101366D03*
X108453Y48720D03*
X101366D03*
X102379Y69340D03*
X111335D03*
X104379Y66844D03*
Y71836D03*
X109335Y66844D03*
Y71836D03*
X98335Y72844D03*
Y77836D03*
X100335Y75340D03*
X101317Y431727D03*
X102060Y493578D03*
X111087Y520052D03*
X98134Y722501D03*
X99716Y1567878D03*
X99750Y1559478D03*
X96251Y1577532D03*
X107451Y1574704D03*
X100451D03*
X104318Y1592304D03*
Y1603690D03*
X110200Y1605200D03*
X104318Y1622380D03*
Y1641075D03*
X99980Y1685362D03*
Y1696052D03*
X114498Y17042D03*
Y22034D03*
X123716Y17042D03*
Y22034D03*
X116498Y19538D03*
X121716D03*
X121567Y23978D03*
X116611D03*
X114611Y25974D03*
X123567D03*
X122626Y37106D03*
X115539D03*
X122626Y48720D03*
X115539D03*
X124379Y69340D03*
X126379Y66844D03*
Y71836D03*
X115379Y72844D03*
Y77836D03*
X120335Y72844D03*
Y77836D03*
X122335Y75340D03*
X113379D03*
X114087Y285495D03*
Y302854D03*
X127206Y480216D03*
X123257Y547506D03*
X119087D03*
X115060D03*
X120267Y1327697D03*
X127366Y1535855D03*
Y1541874D03*
Y1547935D03*
X116798Y1586288D03*
Y1598572D03*
Y1635303D03*
X127195Y1670362D03*
X117795Y1698862D03*
X127195Y1688362D03*
Y1692362D03*
Y1708362D03*
X117255Y1730422D03*
X129058Y3010D03*
X128672Y17042D03*
Y22034D03*
X130672Y19538D03*
X129713Y37106D03*
Y48720D03*
X133335Y69340D03*
X131335Y66844D03*
Y71836D03*
X137379Y72844D03*
Y77836D03*
X142335Y72844D03*
Y77836D03*
X135379Y75340D03*
X130057Y636103D03*
X129600Y669400D03*
X132967Y760525D03*
X141470Y1359100D03*
X140104Y1560136D03*
X139080Y1731398D03*
X149058Y3010D03*
X159582Y17042D03*
Y22034D03*
X157582Y19538D03*
X152477Y23978D03*
X157433D03*
X150477Y25974D03*
X159433D03*
X158492Y37106D03*
X151405D03*
X158492Y48720D03*
X151405D03*
X146379Y69340D03*
X155335D03*
X148379Y66844D03*
Y71836D03*
X153335Y66844D03*
Y71836D03*
X158583Y75340D03*
X144335D03*
X149371Y423383D03*
Y419383D03*
Y427383D03*
Y439383D03*
Y431383D03*
Y435383D03*
Y443383D03*
X147141Y698811D03*
X147435Y690807D03*
X149861Y698831D03*
X150155Y690807D03*
X156685Y706836D03*
X153965Y706816D03*
X153879Y721660D03*
X156469D03*
X147031Y706835D03*
X149621D03*
X149669Y721660D03*
X147079D03*
X154477Y1360797D03*
X148663Y1378607D03*
X151163D03*
Y1383807D03*
Y1381207D03*
X158318Y1384286D03*
X155718D03*
X158318Y1387393D03*
X155718D03*
X148663Y1386407D03*
X151163D03*
X148663Y1383807D03*
Y1381207D03*
X160201Y1399732D03*
X157731D03*
Y1394132D03*
X160201D03*
X152806Y1414175D03*
X144748Y1514878D03*
X149728D03*
X154581Y1520981D03*
X158570D03*
X150502Y1572021D03*
X145522D03*
X159107Y1571364D03*
X144854Y1702389D03*
X154803Y1708532D03*
X155100Y1723262D03*
X169058Y3010D03*
X164538Y17042D03*
Y22034D03*
X173755Y17042D03*
Y22034D03*
X166538Y19538D03*
X171755D03*
X166650Y23978D03*
X171606D03*
X164650Y25974D03*
X173606D03*
X172665Y37106D03*
X165579D03*
X172665Y48720D03*
X165579D03*
X169583Y69340D03*
X171583Y66844D03*
Y71836D03*
X176539Y66844D03*
Y71836D03*
X165539Y72844D03*
X160583D03*
Y77836D03*
X165539D03*
X167539Y75340D03*
X174327Y230928D03*
X171180Y401885D03*
X163900Y409362D03*
X163132Y493299D03*
X162750Y512502D03*
X172807Y1360797D03*
X160918Y1384286D03*
X163518D03*
Y1387393D03*
X160918D03*
X169318Y1384286D03*
X166118D03*
X172262Y1384302D03*
Y1387409D03*
X174932Y1378797D03*
Y1381397D03*
X163718Y1390500D03*
X161118D03*
X162631Y1399732D03*
Y1394132D03*
X172231Y1390532D03*
X162693Y1411529D03*
X171262Y1443390D03*
X168900Y1520510D03*
X163920D03*
X166476Y1572464D03*
X171456D03*
X166529Y1707678D03*
X166661Y1721211D03*
X189058Y3010D03*
X178711Y17042D03*
Y22034D03*
X180711Y19538D03*
X179752Y37106D03*
Y48720D03*
X191583Y69340D03*
X178539D03*
X182583Y72844D03*
Y77836D03*
X187539Y72844D03*
Y77836D03*
X189539Y75340D03*
X180583D03*
X186457Y393071D03*
Y385071D03*
Y389071D03*
Y405071D03*
X192220Y408662D03*
Y412162D03*
X177871Y421383D03*
Y425383D03*
Y430883D03*
Y443383D03*
X187490Y568752D03*
X190977Y669718D03*
X191976Y684326D03*
X184215Y1361072D03*
X181403Y1361115D03*
X192620Y1360797D03*
X188233Y1387027D03*
Y1379227D03*
Y1381827D03*
Y1384427D03*
X183283Y1387987D03*
X185633Y1387027D03*
X180672Y1387987D03*
X185633Y1379227D03*
X180672Y1380187D03*
X183283D03*
X177532Y1378797D03*
X185633Y1384427D03*
Y1381827D03*
X180672Y1382787D03*
Y1385387D03*
X183283Y1382787D03*
Y1385387D03*
X177421Y1383997D03*
X177532Y1381397D03*
X182653Y1404535D03*
X192767Y1413725D03*
X185643Y1413945D03*
X185895Y1535462D03*
Y1539723D03*
Y1544029D03*
Y1548487D03*
Y1552875D03*
X176793Y1585173D03*
X188119Y1580678D03*
Y1575686D03*
Y1592590D03*
Y1587598D03*
X192529Y1728947D03*
X183822Y1720517D03*
X209058Y3010D03*
X203716Y17042D03*
Y22034D03*
X208672Y17042D03*
Y22034D03*
X201716Y19538D03*
X201567Y23978D03*
X196611D03*
X194611Y25974D03*
X203567D03*
X208784D03*
X202626Y37106D03*
X195539D03*
X202626Y48720D03*
X195539D03*
X200539Y69340D03*
X193583Y66844D03*
Y71836D03*
X198539Y66844D03*
Y71836D03*
X204717Y72844D03*
Y77836D03*
X202717Y75340D03*
X195888Y581071D03*
X194515Y583433D03*
X195888Y615071D03*
X194515Y617433D03*
Y651433D03*
X195888Y649071D03*
X205320Y667562D03*
X207856Y686443D03*
X203043Y686483D03*
X207824Y681560D03*
X203044Y684036D03*
X207834Y684006D03*
X203237Y681549D03*
X199720Y732862D03*
X206720Y731862D03*
X199220Y739362D03*
X207602Y756855D03*
X199602D03*
X201661Y1384286D03*
X193861D03*
X196461D03*
X199061D03*
X201661Y1387393D03*
X193861D03*
X196461D03*
X199061D03*
X204261Y1384286D03*
X207461D03*
X201861Y1390500D03*
X199261D03*
X195874Y1399732D03*
X198344D03*
X200774D03*
X195874Y1394132D03*
X198344D03*
X200774D03*
X201071Y1412173D03*
X193075Y1580678D03*
Y1575686D03*
X200179D03*
X205135D03*
X200179Y1580678D03*
X205135D03*
X193075Y1592590D03*
Y1587598D03*
X200179Y1592590D03*
X205135D03*
X200179Y1587598D03*
X205135D03*
X198375Y1599884D03*
X193419D03*
X205479D03*
X193419Y1616788D03*
Y1611796D03*
X198375D03*
X193419Y1604876D03*
X198375D03*
Y1616788D03*
X205479Y1611796D03*
Y1604876D03*
Y1616788D03*
X207229Y1631181D03*
X193410Y1711606D03*
X205582Y1700867D03*
X196443Y1722197D03*
X217889Y17042D03*
Y22034D03*
X222845Y17042D03*
Y22034D03*
X210672Y19538D03*
X215889D03*
X224845D03*
X215740Y23978D03*
X210784D03*
X217740Y25974D03*
X223886Y37106D03*
X216799D03*
X209713D03*
X223886Y48720D03*
X216799D03*
X209713D03*
X215717Y66844D03*
Y71836D03*
X220673Y66844D03*
Y71836D03*
X213717Y69340D03*
X222673D03*
X209673Y72844D03*
Y77836D03*
X211673Y75340D03*
X224717D03*
X209579Y457222D03*
Y462235D03*
X211220Y740362D03*
X215824Y1361199D03*
X211350Y1360797D03*
X218960Y1388312D03*
X210405Y1384302D03*
Y1387409D03*
X213075Y1381558D03*
X217133Y1384055D03*
X214425Y1384058D03*
X215675Y1381558D03*
X218175D03*
X213075Y1378958D03*
X215675D03*
X218175D03*
X210374Y1390532D03*
X212239Y1580678D03*
X217195D03*
Y1575686D03*
X212239D03*
X224299D03*
Y1580678D03*
X212239Y1587598D03*
X217195D03*
X212239Y1592590D03*
X217195D03*
X224299Y1587598D03*
Y1592590D03*
X210435Y1599884D03*
X222495D03*
X217539D03*
X210435Y1611796D03*
Y1604876D03*
Y1616788D03*
X222495D03*
X217539D03*
X222495Y1604876D03*
Y1611796D03*
X217539Y1604876D03*
Y1611796D03*
X212684Y1720307D03*
X229058Y3010D03*
X238063Y37162D03*
X230972Y37106D03*
Y48720D03*
X226717Y72844D03*
Y77836D03*
X231673Y72844D03*
Y77836D03*
X233673Y75340D03*
X233800Y162692D03*
X237539Y174266D03*
X228550Y420412D03*
X229255Y1575686D03*
Y1580678D03*
X236359D03*
Y1575686D03*
X241315Y1580678D03*
Y1575686D03*
X229255Y1587598D03*
Y1592590D03*
X236359D03*
Y1587598D03*
X241315Y1592590D03*
Y1587598D03*
X229599Y1599884D03*
X234555D03*
X229599Y1604876D03*
Y1611796D03*
X234555Y1604876D03*
Y1611796D03*
X229599Y1616788D03*
X234555D03*
X249058Y3010D03*
X243490Y23002D03*
X247720Y71862D03*
X244300Y59762D03*
X247720Y75862D03*
X251797Y100843D03*
X249735Y152694D03*
X242255Y162512D03*
X249300Y510362D03*
X253800Y515362D03*
X249860Y518222D03*
X248419Y1575686D03*
X253375D03*
X248419Y1580678D03*
X253375D03*
X248419Y1587598D03*
X253375D03*
X248419Y1592590D03*
X253375D03*
X246615Y1599884D03*
X241659D03*
X253719D03*
X241659Y1616788D03*
X246615D03*
Y1604876D03*
X241659D03*
X246615Y1611796D03*
X241659D03*
X253719Y1604876D03*
Y1611796D03*
Y1616788D03*
X269058Y3010D03*
X263280Y35312D03*
X272600Y27182D03*
X271600Y40162D03*
X272361Y120243D03*
X270364Y118415D03*
X261387Y133783D03*
X258257D03*
X264578Y155203D03*
Y159203D03*
X260700Y218662D03*
X268940Y217982D03*
X270745Y207562D03*
X265343Y244460D03*
X272029Y443735D03*
X274270Y746602D03*
X260479Y1580678D03*
X265435D03*
X260479Y1575592D03*
X265435D03*
X272539Y1575686D03*
Y1580678D03*
X260479Y1592590D03*
X265435D03*
X260479Y1587598D03*
X265435D03*
X272539D03*
Y1592590D03*
X258675Y1599884D03*
X270735Y1599790D03*
X265779D03*
X258675Y1604876D03*
Y1611796D03*
Y1616788D03*
X270735D03*
X265779D03*
X270735Y1611796D03*
Y1604876D03*
X265779D03*
Y1611796D03*
X289058Y3010D03*
X285900Y23962D03*
X287952Y39984D03*
X286071Y48720D03*
X286500Y52462D03*
X278984Y48720D03*
X287800Y60062D03*
X283953Y152503D03*
X288520Y157062D03*
X279740Y205962D03*
X276890Y249022D03*
X289920Y248652D03*
X286920D03*
X282420D03*
X287819Y691097D03*
X287820Y727962D03*
X278520Y738072D03*
X290077Y739735D03*
X289047Y760245D03*
X277495Y1575686D03*
Y1580678D03*
X284599D03*
X289555D03*
Y1575686D03*
X284599D03*
X277495Y1587598D03*
Y1592590D03*
X284599D03*
X289555D03*
X284599Y1587598D03*
X289555D03*
X282795Y1599884D03*
X277839D03*
X289899D03*
X282795Y1604876D03*
Y1611796D03*
X277839D03*
Y1604876D03*
X282795Y1616788D03*
X277839D03*
X289899D03*
Y1604876D03*
Y1611796D03*
X291520Y12762D03*
X291660Y21642D03*
X298720Y40017D03*
X306720Y39982D03*
X292942Y67513D03*
X293447Y78573D03*
X293452Y82483D03*
Y85983D03*
X303047Y79373D03*
X299947Y79273D03*
X299657Y92503D03*
X299628Y149203D03*
Y158703D03*
X294553Y153819D03*
X306087Y569718D03*
X294658Y637809D03*
X290680Y745312D03*
X299427Y768265D03*
X303831Y1318566D03*
X303807Y1342225D03*
X303831Y1344866D03*
X304047Y1368565D03*
X296659Y1575686D03*
X301615D03*
X296659Y1580678D03*
X301615D03*
X296659Y1587598D03*
X301615D03*
X296659Y1592590D03*
X301615D03*
X294855Y1599884D03*
X301959D03*
X294855Y1616788D03*
Y1604876D03*
Y1611796D03*
X301959Y1604876D03*
Y1611796D03*
Y1616788D03*
X309058Y3010D03*
X320057Y85803D03*
Y88803D03*
X314200Y585282D03*
X316080Y578262D03*
X320691Y602448D03*
X311820Y598762D03*
X316397Y776125D03*
X312301Y1345539D03*
Y1342432D03*
X309701Y1345539D03*
Y1342432D03*
X316655Y1352295D03*
X314175D03*
X311695D03*
X320101Y1342432D03*
X317701Y1348646D03*
X315101D03*
X314901Y1345539D03*
X317501D03*
X314901Y1342432D03*
X317501D03*
X316655Y1357895D03*
X311695D03*
X314175D03*
X317979Y1371248D03*
X315221Y1372445D03*
X308719Y1580678D03*
X313675D03*
X308719Y1575686D03*
X313675D03*
X320779D03*
Y1580678D03*
X308719Y1592590D03*
X313675D03*
X308719Y1587598D03*
X313675D03*
X320779D03*
Y1592590D03*
X306915Y1599884D03*
X318975D03*
X314019D03*
X306915Y1604876D03*
Y1611796D03*
Y1616788D03*
X318975D03*
X314019D03*
X318975Y1604876D03*
Y1611796D03*
X314019Y1604876D03*
Y1611796D03*
X329535Y49388D03*
X336240Y150738D03*
X330674Y368261D03*
X331760Y705882D03*
X328915Y1337104D03*
X331515D03*
X328915Y1331904D03*
X331515D03*
X328915Y1329304D03*
X331515D03*
X328915Y1334504D03*
X331515D03*
X328915Y1339704D03*
X326145Y1348651D03*
X326245Y1345555D03*
Y1342448D03*
X323301Y1342432D03*
X338917Y1349488D03*
X336347Y1348353D03*
X325735Y1575686D03*
Y1580678D03*
X332839D03*
X337795D03*
X332839Y1575686D03*
X337795D03*
X325735Y1587598D03*
Y1592590D03*
X332839D03*
X337795D03*
X332839Y1587598D03*
X337795D03*
X326079Y1599884D03*
X331035D03*
X338139D03*
X326079Y1604876D03*
Y1611796D03*
X331035Y1604876D03*
Y1611796D03*
X326079Y1616788D03*
X331035D03*
X338139D03*
Y1604876D03*
Y1611796D03*
X349535Y49388D03*
X343040Y122522D03*
X345869Y192716D03*
X353145Y228362D03*
X345164Y314234D03*
X349187Y715485D03*
X344446Y739434D03*
X348000Y755362D03*
X344429Y1322741D03*
X347029D03*
X341829D03*
X347029Y1319634D03*
X344429D03*
X341829D03*
X349629Y1322741D03*
Y1319634D03*
X352229D03*
X355429D03*
X346303Y1335097D03*
X343823D03*
Y1329497D03*
X346303D03*
X347229Y1325848D03*
X348783Y1329497D03*
X349829Y1325848D03*
X348783Y1335097D03*
X348804Y1346877D03*
X350470Y1349030D03*
X344899Y1575686D03*
X349855D03*
X344899Y1580678D03*
X349855D03*
X344899Y1587598D03*
X349855D03*
X344899Y1592590D03*
X349855D03*
X343095Y1599884D03*
X355155D03*
X350199D03*
X343095Y1616788D03*
Y1604876D03*
Y1611796D03*
X355155Y1604876D03*
Y1611796D03*
X350199Y1604876D03*
Y1611796D03*
X355155Y1616788D03*
X350199D03*
X366775Y127662D03*
X356250Y216342D03*
X358209Y208169D03*
X357764Y314234D03*
X363750Y369362D03*
X371370Y373622D03*
X364014Y382304D03*
X359930Y732985D03*
X360927Y757665D03*
X361043Y1306506D03*
X363643D03*
X367939Y1303319D03*
Y1305919D03*
Y1308519D03*
X358373Y1322757D03*
Y1319650D03*
X361043Y1314306D03*
Y1316906D03*
X362393Y1319406D03*
X361043Y1309106D03*
Y1311706D03*
X363643Y1316906D03*
Y1314306D03*
Y1309106D03*
Y1311706D03*
X358273Y1325853D03*
X370874Y1335876D03*
X367490Y1332568D03*
X356959Y1580678D03*
X361915D03*
X356959Y1575592D03*
X361915D03*
X369019Y1575686D03*
Y1580678D03*
X356959Y1592590D03*
X361915D03*
X356959Y1587598D03*
X361915D03*
X367215Y1599790D03*
X362259D03*
X369019Y1587598D03*
Y1592590D03*
X367215Y1616788D03*
X362259D03*
X367215Y1604876D03*
Y1611796D03*
X362259Y1604876D03*
Y1611796D03*
X376245Y212862D03*
Y217362D03*
Y221362D03*
Y225362D03*
X386120Y220322D03*
X385720Y323761D03*
X376500Y362736D03*
X373957Y1306208D03*
X381757D03*
X379157D03*
X376557D03*
X384357D03*
X387557D03*
X375951Y1321671D03*
X380911Y1316071D03*
X378431D03*
Y1321671D03*
X380911D03*
X373957Y1309315D03*
X381957Y1312422D03*
X381757Y1309315D03*
X379357Y1312422D03*
X379157Y1309315D03*
X376557D03*
X375951Y1316071D03*
X380842Y1334095D03*
X383549Y1333998D03*
X383127Y1395610D03*
X381060Y1433622D03*
X380930Y1531402D03*
X384210Y1534152D03*
X387152Y1582659D03*
X373975Y1575686D03*
Y1580678D03*
Y1587598D03*
Y1592590D03*
X379275Y1599884D03*
X374319D03*
X379275Y1604876D03*
Y1611796D03*
X374319Y1604876D03*
Y1611796D03*
X379275Y1616788D03*
X374319D03*
X374690Y1631700D03*
X375550Y1662052D03*
X386824Y1682866D03*
X387760Y1671092D03*
X393830Y62062D03*
X399800Y59662D03*
X403800D03*
X390830Y155833D03*
X388965Y209949D03*
X398720Y318643D03*
X403675Y363081D03*
X391195Y368199D03*
X391101Y380939D03*
X403581Y375880D03*
X390730Y394852D03*
X403570Y388874D03*
X395771Y1303480D03*
X393171D03*
X395771Y1300880D03*
X393171D03*
X395771Y1295680D03*
X393171D03*
X395771Y1298280D03*
X393171D03*
X394521Y1305980D03*
X390501Y1306224D03*
X400067Y1303319D03*
Y1300719D03*
Y1295519D03*
Y1298119D03*
Y1305919D03*
Y1308519D03*
X390401Y1312427D03*
X390501Y1309331D03*
X399673Y1332653D03*
X403130Y1335963D03*
X400919Y1411231D03*
X391370Y1424782D03*
X392108Y1582659D03*
X401812Y1616456D03*
X394910Y1632364D03*
Y1637320D03*
X402246Y1671745D03*
X409535Y49388D03*
X412930Y62572D03*
X413459Y129061D03*
X411434Y163662D03*
X407490Y216912D03*
X412820Y231922D03*
X405478Y236726D03*
X410090Y241932D03*
X420710Y242482D03*
X419023Y381760D03*
X418982Y407847D03*
X416485Y1306208D03*
X419685D03*
X413885D03*
X406085D03*
X411285D03*
X408685D03*
X414085Y1312422D03*
X413885Y1309315D03*
X411485Y1312422D03*
X408685Y1309315D03*
X406085D03*
X411285D03*
X413039Y1316071D03*
X408079D03*
X410559D03*
X413039Y1321671D03*
X408079D03*
X410559D03*
X416099Y1335568D03*
X414617Y1333473D03*
X412465Y1393878D03*
X419974Y1405289D03*
Y1412789D03*
X420474Y1420289D03*
X407125Y1424978D03*
X404475Y1552452D03*
X419002Y1600306D03*
X406526Y1591212D03*
Y1596168D03*
X406768Y1616456D03*
X408700Y1603500D03*
Y1614300D03*
X411910Y1629170D03*
Y1624214D03*
X410232Y1670244D03*
X429535Y49388D03*
X430655Y58677D03*
X433695Y214862D03*
X429395Y232562D03*
X426295Y227862D03*
X422210Y221452D03*
X429395Y236562D03*
Y240562D03*
X425249Y338061D03*
X431503Y376642D03*
X431462Y402729D03*
X422629Y1306224D03*
X432195Y1303319D03*
Y1305919D03*
X425299Y1303480D03*
X426649Y1305980D03*
X427899Y1303480D03*
X425299Y1295680D03*
X427899D03*
X432195Y1295519D03*
Y1298119D03*
X427899Y1298280D03*
X425299D03*
X432195Y1300719D03*
X427899Y1300880D03*
X425299D03*
X432195Y1308519D03*
X422529Y1312427D03*
X422629Y1309331D03*
X434983Y1335924D03*
X431578Y1332560D03*
X427474Y1405289D03*
X434974D03*
Y1412789D03*
X427474Y1420289D03*
X434974D03*
X423958Y1600306D03*
X428099Y1586282D03*
X428941Y1606441D03*
X449535Y49388D03*
X443678Y145710D03*
X445964Y314234D03*
X450400Y338812D03*
X442853Y542519D03*
Y547519D03*
X448613Y1306208D03*
X446013D03*
X443413D03*
X440813D03*
X438213D03*
X451813D03*
X443613Y1312422D03*
X443413Y1309315D03*
X440813D03*
X438213D03*
X446213Y1312422D03*
X446013Y1309315D03*
X440207Y1316071D03*
X445167D03*
X442687D03*
X440207Y1321671D03*
X445167D03*
X442687D03*
X446944Y1335928D03*
X445153Y1334095D03*
X446258Y1441606D03*
X449778D03*
X451910Y1643282D03*
X437562Y1649770D03*
X442518D03*
X469535Y49388D03*
X454568Y78782D03*
X466992Y145888D03*
X458264Y254862D03*
X460300Y303662D03*
X468490Y340572D03*
X469830Y366158D03*
X460323Y510183D03*
X458327Y1303980D03*
X460927D03*
X464427Y1305380D03*
X454757Y1306224D03*
X460927Y1306580D03*
X458327D03*
Y1301380D03*
X460927D03*
X464427Y1300180D03*
Y1302780D03*
X458327Y1296180D03*
X460927D03*
X464427D03*
X458327Y1298780D03*
X460927D03*
X464423Y1308519D03*
X454657Y1312427D03*
X454757Y1309331D03*
X464738Y1333085D03*
X467644Y1335981D03*
X455576Y1409125D03*
Y1417125D03*
Y1420625D03*
Y1427632D03*
Y1424125D03*
X454450Y1433580D03*
X464160Y1587122D03*
X458414Y1624994D03*
Y1629950D03*
X468040Y1654807D03*
X478240Y55935D03*
Y66575D03*
Y61129D03*
X484396Y161364D03*
X475500Y212685D03*
X472800Y299462D03*
X484800Y307362D03*
X476740Y309272D03*
X479740Y300202D03*
X482920Y398060D03*
X479379Y452445D03*
X480741Y1306208D03*
X478141D03*
X475541D03*
X472941D03*
X470341D03*
X483941D03*
X472941Y1309315D03*
X478141D03*
X470341D03*
X478341Y1312422D03*
X475741D03*
X475541Y1309315D03*
X472335Y1316071D03*
X477295D03*
X474815D03*
X472335Y1321671D03*
X477295D03*
X474815D03*
X477162Y1334095D03*
X478909Y1336038D03*
X485236Y1417844D03*
X482741Y1438698D03*
X482742Y1441312D03*
X484333Y1575686D03*
Y1580678D03*
X477229D03*
X472273D03*
Y1575686D03*
X477229D03*
X482529Y1599884D03*
X477573D03*
X484333Y1587598D03*
Y1592590D03*
X472273D03*
X477229D03*
Y1587598D03*
X472273D03*
X482529Y1616788D03*
X477573D03*
Y1611796D03*
X482529D03*
X477573Y1604876D03*
X482529D03*
X472210Y1618626D03*
X485150Y1624942D03*
X477905Y1667242D03*
X489535Y49347D03*
X497002Y88167D03*
X501540Y105152D03*
X498630Y140492D03*
X489980Y250512D03*
X492074Y300306D03*
X497568Y397632D03*
X494193Y550447D03*
X486885Y1306224D03*
X496451Y1306345D03*
X489555Y1303480D03*
X492155D03*
X490905Y1305980D03*
X492155Y1300880D03*
X489555D03*
X486785Y1312427D03*
X486885Y1309331D03*
X496220Y1322440D03*
X496451Y1316745D03*
Y1308945D03*
Y1314145D03*
Y1311545D03*
X499458Y1349468D03*
X499818Y1385027D03*
X499859Y1393027D03*
X490307Y1421499D03*
X491156Y1438713D03*
X499541Y1438698D03*
X491142Y1441312D03*
X499542D03*
X501349Y1580678D03*
X496393D03*
Y1575686D03*
X501349D03*
X489289D03*
Y1580678D03*
X501693Y1599884D03*
X494589D03*
X489633D03*
X501349Y1592590D03*
X496393D03*
X501349Y1587598D03*
X496393D03*
X489289D03*
Y1592590D03*
X501693Y1611796D03*
Y1604876D03*
Y1616788D03*
X489633Y1611796D03*
X494589Y1604876D03*
X489633D03*
X494589Y1611796D03*
X489633Y1616788D03*
X494589D03*
X487340Y1641352D03*
X517902Y69508D03*
X510815D03*
X503100Y78402D03*
X510030Y78412D03*
X504980Y101752D03*
X503290Y140492D03*
X507360D03*
X514850Y168443D03*
X504075Y231262D03*
X508000Y237862D03*
X505900Y311562D03*
X510740Y332592D03*
X513173Y408740D03*
X514425Y489112D03*
Y495112D03*
X509493Y539819D03*
X513025Y615742D03*
X516069Y1319634D03*
X502469D03*
Y1322741D03*
X512869Y1319634D03*
X510269D03*
X507669D03*
X505069D03*
X507669Y1322741D03*
X505069D03*
X510269D03*
X504463Y1329497D03*
Y1335097D03*
X509423Y1329497D03*
X506943D03*
X509423Y1335097D03*
X506943D03*
X510469Y1325848D03*
X507869D03*
X509382Y1347521D03*
X511149Y1349468D03*
X505018Y1385027D03*
X502418D03*
X505059Y1393027D03*
X502459D03*
X508001Y1438669D03*
X507942Y1441312D03*
X508453Y1575686D03*
X513409D03*
X508453Y1580678D03*
X513409D03*
X513753Y1599884D03*
X506649D03*
X508453Y1587598D03*
X513409D03*
X508453Y1592590D03*
X513409D03*
X513753Y1616788D03*
Y1604876D03*
Y1611796D03*
X506649D03*
Y1604876D03*
Y1616788D03*
X518606Y23797D03*
X532075Y69508D03*
Y57894D03*
X524988Y69508D03*
X529239Y99997D03*
Y92911D03*
X528400Y104225D03*
Y114275D03*
X527823Y131802D03*
Y149802D03*
X527278Y164726D03*
X529480Y183921D03*
X536127Y247652D03*
X523660Y323222D03*
X535220Y383552D03*
X528145Y408705D03*
X518735Y452442D03*
X526852Y511331D03*
X527042Y505830D03*
X526853Y516817D03*
X523033Y1319406D03*
X519013Y1319650D03*
Y1322757D03*
X527645Y1326076D03*
X528579Y1329143D03*
X528377Y1335982D03*
X518913Y1325853D03*
X528579Y1342143D03*
Y1344743D03*
X534597Y1345539D03*
Y1342432D03*
X528975Y1369724D03*
X532573Y1575686D03*
Y1580678D03*
X520513D03*
X525469D03*
X520513Y1575686D03*
X525469D03*
X525813Y1599884D03*
X530769D03*
X518709D03*
X532573Y1587598D03*
Y1592590D03*
X525469D03*
X520513D03*
Y1587598D03*
X525469D03*
X525813Y1611796D03*
X530769D03*
X525813Y1604876D03*
X530769D03*
Y1616788D03*
X525813D03*
X518709D03*
Y1604876D03*
Y1611796D03*
X548609Y32500D03*
X546248Y69508D03*
X539161D03*
Y57894D03*
X546234Y77443D03*
X542620Y103352D03*
X537360Y120522D03*
X550545Y147302D03*
X542798Y202646D03*
X535630Y306602D03*
X543035Y441005D03*
X538120Y463137D03*
X544813Y1322668D03*
X542213D03*
X538293D03*
X535693D03*
X548197Y1342432D03*
X539997Y1348646D03*
X542397Y1345539D03*
X542597Y1348646D03*
X537197Y1342432D03*
X539797D03*
X542397D03*
X544997D03*
X537197Y1345539D03*
X539797D03*
X539071Y1352295D03*
X536591D03*
X541551D03*
Y1357895D03*
X542256Y1369935D03*
X536591Y1357895D03*
X539071D03*
X549589Y1580678D03*
X544633D03*
X549589Y1575592D03*
X544633D03*
X537529Y1575686D03*
Y1580678D03*
X549933Y1599790D03*
X537873Y1599884D03*
X542829D03*
X549589Y1592590D03*
X544633D03*
X549589Y1587598D03*
X544633D03*
X537529D03*
Y1592590D03*
X549933Y1611796D03*
Y1604876D03*
Y1616788D03*
X542829D03*
X537873D03*
Y1604876D03*
X542829D03*
X537873Y1611796D03*
X542829D03*
X560421Y69508D03*
X553335D03*
X553320Y77443D03*
X564988Y118670D03*
X555545Y134340D03*
X565500Y145252D03*
X555220Y167937D03*
X553657Y193862D03*
X564944Y252173D03*
X553536Y307527D03*
X569080Y414002D03*
X559300Y422732D03*
X558933Y1323658D03*
Y1326258D03*
X556563Y1337918D03*
X553963D03*
X558933Y1328938D03*
X556563Y1335318D03*
Y1332718D03*
X558933Y1331538D03*
X553963Y1335318D03*
Y1332718D03*
X555313Y1340418D03*
X551141Y1345555D03*
X551041Y1348651D03*
X551141Y1342448D03*
X555372Y1343037D03*
X561070Y1346174D03*
X556693Y1575686D03*
X561649D03*
X556693Y1580678D03*
X561649D03*
X561993Y1599884D03*
X554889Y1599790D03*
X556693Y1587598D03*
X561649D03*
Y1592590D03*
X556693D03*
X561993Y1616788D03*
Y1604876D03*
Y1611796D03*
X554889D03*
Y1604876D03*
Y1616788D03*
X567673Y130542D03*
X581175Y164717D03*
X569965Y161232D03*
X579481Y202378D03*
Y210378D03*
X568149Y217916D03*
X580712Y215877D03*
X581645Y233362D03*
X569668Y229812D03*
X578711Y230109D03*
X578509Y265132D03*
X569880Y300992D03*
X580400Y302402D03*
X582436Y361032D03*
X570200Y372229D03*
X570760Y451710D03*
X571990Y501046D03*
X571700Y552200D03*
X580813Y1575686D03*
Y1580678D03*
X573709D03*
X568753D03*
Y1575686D03*
X573709D03*
X579009Y1599884D03*
X574053D03*
X566949D03*
X580813Y1587598D03*
Y1592590D03*
X573709D03*
X568753D03*
X573709Y1587598D03*
X568753D03*
X574053Y1616788D03*
X579009D03*
Y1611796D03*
X574053D03*
X579009Y1604876D03*
X574053D03*
X566949Y1616788D03*
Y1604876D03*
Y1611796D03*
X591395Y132142D03*
X595220Y140922D03*
X588000D03*
X592710Y156342D03*
X593248Y159480D03*
X598295Y171862D03*
X596581Y184849D03*
X590337Y177604D03*
X598760Y203712D03*
X593966Y229965D03*
X592039Y252202D03*
X588577Y285862D03*
X586820Y314662D03*
X597820Y317062D03*
X592920Y326362D03*
X591720Y430787D03*
X599220Y444362D03*
X593545Y488212D03*
X594090Y505107D03*
X589260Y519421D03*
X594240Y511953D03*
X593675Y534702D03*
X589989Y745475D03*
X597829Y1580678D03*
X592873D03*
X597829Y1575686D03*
X592873D03*
X585769D03*
Y1580678D03*
X598173Y1599884D03*
X586113D03*
X591069D03*
X597829Y1592590D03*
X592873D03*
X597829Y1587598D03*
X592873D03*
X585769D03*
Y1592590D03*
X598173Y1616788D03*
Y1611796D03*
Y1604876D03*
X586113D03*
X591069D03*
X586113Y1611796D03*
X591069D03*
Y1616788D03*
X586113D03*
X615185Y69508D03*
X603374D03*
X601050Y100008D03*
X610104Y119342D03*
X602306Y143077D03*
X602430Y153862D03*
X606260Y161652D03*
X615572Y173942D03*
X615573Y181984D03*
X614531Y200378D03*
X611030Y188372D03*
X603340Y208142D03*
X614531Y209878D03*
X609456Y204994D03*
X606719Y254966D03*
X609844Y330407D03*
X608830Y374302D03*
X605830Y402782D03*
X604779Y423862D03*
X600351Y461862D03*
X614220Y452862D03*
X610820Y472862D03*
X603779Y486922D03*
X606200Y514862D03*
X609520Y515162D03*
X614086Y537624D03*
X614000Y550800D03*
X603317Y738415D03*
X614660Y739553D03*
X602027Y761445D03*
X612407Y769485D03*
X609889Y1575686D03*
X604933D03*
X609889Y1580678D03*
X604933D03*
X615189Y1599884D03*
X610233D03*
X603129D03*
X609889Y1587598D03*
X604933D03*
X609889Y1592590D03*
X604933D03*
X615189Y1604876D03*
X610233D03*
X615189Y1611796D03*
X610233D03*
X615189Y1616788D03*
X610233D03*
X603129D03*
Y1611796D03*
Y1604876D03*
X631546Y85024D03*
X618460Y119342D03*
X631300Y167872D03*
X628195Y178414D03*
X628194Y170372D03*
X630818Y191248D03*
X625862D03*
X620030Y188782D03*
X627645Y236862D03*
X629564Y256277D03*
X623150Y273172D03*
X625800Y311912D03*
X628294Y317007D03*
X623580Y336429D03*
X629248Y436972D03*
X629220Y472862D03*
Y477862D03*
Y467862D03*
Y482862D03*
X626207Y747585D03*
X618114Y1258470D03*
X629053Y1575686D03*
Y1580678D03*
X621949D03*
X616993D03*
X621949Y1575686D03*
X616993D03*
X622293Y1599884D03*
X627249D03*
X629053Y1587598D03*
Y1592590D03*
X621949D03*
X616993D03*
X621949Y1587598D03*
X616993D03*
X627249Y1616788D03*
X622293D03*
Y1611796D03*
X627249D03*
X622293Y1604876D03*
X627249D03*
X646440Y43632D03*
X632463Y43302D03*
X645150Y69508D03*
X645350Y60612D03*
X632640Y107532D03*
X637500Y110362D03*
X642480Y184862D03*
X645876Y296231D03*
X633138Y296766D03*
X645528Y308623D03*
X645807Y304291D03*
X647200Y354300D03*
X643736Y457214D03*
X644245Y472862D03*
X644220Y467862D03*
X644245Y482862D03*
X636960Y516002D03*
X646069Y1580678D03*
X641113D03*
X646069Y1575592D03*
X641113D03*
X634009Y1575686D03*
Y1580678D03*
X646413Y1599790D03*
X639309Y1599884D03*
X634353D03*
X646069Y1592590D03*
X641113D03*
X646069Y1587598D03*
X641113D03*
X634009D03*
Y1592590D03*
X646413Y1616788D03*
Y1611796D03*
Y1604876D03*
X639309D03*
X634353D03*
X639309Y1611796D03*
X634353D03*
Y1616788D03*
X639309D03*
X641057Y1648659D03*
X645407Y1660425D03*
X639745Y1714362D03*
X648290Y1720052D03*
X639745Y1726362D03*
X661550Y45133D03*
X654464D03*
X652153Y98105D03*
X652680Y89712D03*
X651579Y102703D03*
X659000Y89262D03*
X651980Y133822D03*
X650790Y144982D03*
X660690Y408162D03*
X660720Y404362D03*
X653800Y498740D03*
X662282Y1386432D03*
X654606Y1431203D03*
X653173Y1575686D03*
X658129D03*
X653173Y1580678D03*
X658129D03*
X663429Y1599884D03*
X658473D03*
X651369Y1599790D03*
X653173Y1587598D03*
X658129D03*
X653173Y1592590D03*
X658129D03*
X663429Y1604876D03*
X658473D03*
X663429Y1611796D03*
X658473D03*
Y1616788D03*
X663429D03*
X651369D03*
Y1611796D03*
Y1604876D03*
X663043Y1647557D03*
X655307Y1647436D03*
X663118Y1659557D03*
X663145Y1664862D03*
Y1676862D03*
X656973Y1698727D03*
X652712Y1686275D03*
X672005Y44119D03*
X668800Y45262D03*
X666406Y69508D03*
X675225Y58108D03*
X673750Y77692D03*
X673690Y200672D03*
X673300Y211332D03*
X667020Y225762D03*
X680600Y375462D03*
X668329Y411714D03*
X677295Y404362D03*
X677195Y408262D03*
X674628Y414864D03*
Y443210D03*
X671479Y430612D03*
Y462108D03*
X668329Y481006D03*
X675220Y503837D03*
X680220D03*
X675220Y516852D03*
X671607Y742835D03*
X668096Y1360822D03*
X677137Y1384311D03*
X674537D03*
X671937D03*
X669337D03*
X677137Y1387418D03*
X674537D03*
X671937D03*
X669337D03*
X664782Y1383832D03*
Y1381232D03*
Y1378632D03*
Y1386432D03*
X679737Y1384311D03*
X677337Y1390525D03*
X674737D03*
X676250Y1399757D03*
X673820D03*
X671350D03*
X676250Y1394157D03*
X673820D03*
X671350D03*
X666425Y1414200D03*
X676312Y1411554D03*
X667926Y1547018D03*
X679192Y1564252D03*
X678515Y1573910D03*
X676648Y1657380D03*
X671620Y1670862D03*
X674195Y1708362D03*
X669120Y1718862D03*
X674195Y1732362D03*
X696838Y45112D03*
X686854Y43701D03*
X692380Y43532D03*
X682941Y69982D03*
X687050Y79212D03*
X685230Y76952D03*
X683820Y79192D03*
X682890Y72642D03*
X684953Y104968D03*
X694390Y133682D03*
X684520Y152482D03*
X688520D03*
X692520D03*
X686760Y222912D03*
X685600Y375462D03*
X690600D03*
X695600D03*
X688220Y388362D03*
X697220Y404362D03*
X697120Y408262D03*
X684077Y414864D03*
X680928Y424313D03*
X696676Y436911D03*
X693526Y443210D03*
Y440061D03*
Y436911D03*
X690376Y440061D03*
Y433761D03*
X693526Y452659D03*
Y449510D03*
X696676Y455809D03*
X693526D03*
X690376Y452659D03*
Y458959D03*
X696676Y477856D03*
X684077D03*
X680928Y468407D03*
X690220Y516852D03*
X684357Y742345D03*
X692784Y1298845D03*
X686426Y1360822D03*
X695022Y1361990D03*
X696462Y1386122D03*
X682937Y1384311D03*
X685881Y1384327D03*
Y1387434D03*
X691351Y1380922D03*
X688751D03*
X691240Y1383522D03*
X693851D03*
Y1378322D03*
Y1380922D03*
X691351Y1378322D03*
X688751D03*
X693851Y1386122D03*
X696462Y1378322D03*
Y1383522D03*
Y1380922D03*
X696272Y1404560D03*
X685850Y1390557D03*
X685015Y1438475D03*
X696940Y1437955D03*
X689875Y1577913D03*
X689128Y1652262D03*
X692595Y1670862D03*
X701838Y45112D03*
X700610Y57782D03*
X700741Y83050D03*
X706673Y122762D03*
X703520Y122540D03*
X704880Y133643D03*
X701926Y166535D03*
Y178346D03*
Y184252D03*
Y172441D03*
Y190157D03*
Y196063D03*
Y201968D03*
Y207874D03*
Y213779D03*
Y219685D03*
X700600Y375462D03*
X705600D03*
X706125Y421163D03*
X709274Y436911D03*
X706125Y440061D03*
Y436911D03*
X699825Y440061D03*
Y436911D03*
X712424Y443210D03*
Y440061D03*
Y436911D03*
Y455809D03*
X709274D03*
X706125D03*
Y452659D03*
X699825Y455809D03*
Y452659D03*
X712424D03*
Y449510D03*
X709274Y477856D03*
X699825Y468407D03*
X711220Y516852D03*
X705220D03*
X698600Y530700D03*
X701917Y742865D03*
X703755Y1290545D03*
X708795Y1303701D03*
X698094Y1361947D03*
X706239Y1360822D03*
X699062Y1380922D03*
Y1383522D03*
Y1378322D03*
X707480Y1384311D03*
X710080D03*
X707480Y1387418D03*
X710080D03*
X701662Y1380922D03*
Y1383522D03*
Y1378322D03*
X699062Y1386122D03*
X701662D03*
X712680Y1384311D03*
Y1387418D03*
X709493Y1399757D03*
Y1394157D03*
X712880Y1390525D03*
X711963Y1399757D03*
Y1394157D03*
X699262Y1413970D03*
X704568Y1414119D03*
X706680Y1437535D03*
X701730Y1437855D03*
X711440Y1436905D03*
X702112Y1583683D03*
X709111Y1618842D03*
X697595Y1658862D03*
X704433Y1657964D03*
X697770Y1680810D03*
X714015Y-27612D03*
X720308Y-26403D03*
X714015Y-21457D03*
Y-17583D03*
X714030Y-15068D03*
X714015Y-11428D03*
X714030Y-25097D03*
X720308Y-16374D03*
X714015Y-7554D03*
X714030Y-5039D03*
X720308Y-6345D03*
X728980Y39872D03*
X728028Y101968D03*
X728023Y98058D03*
X728028Y105468D03*
X727720Y356362D03*
X725220Y380787D03*
X715600Y375462D03*
X718220Y388362D03*
X715220Y404362D03*
X715120Y408262D03*
X725022Y414864D03*
X715574Y433761D03*
Y458959D03*
X728172Y449510D03*
X725022Y477856D03*
X722720Y521362D03*
X729200Y588952D03*
X713836Y1283689D03*
X724969Y1360822D03*
X729443Y1361224D03*
X726694Y1381583D03*
Y1378983D03*
X715280Y1384311D03*
X717880D03*
X715280Y1387418D03*
X721080Y1384311D03*
X724024Y1384327D03*
Y1387434D03*
X728044Y1384083D03*
X729294Y1381583D03*
Y1378983D03*
X715480Y1390525D03*
X723993Y1390557D03*
X714393Y1399757D03*
Y1394157D03*
X714455Y1411554D03*
X718230Y1600372D03*
X725378Y1614503D03*
X719770Y1614590D03*
X715780D03*
X722040Y1623970D03*
X713791Y1629816D03*
X721345Y1647300D03*
X716140Y1649895D03*
X726830Y1655380D03*
X724500Y1676500D03*
X744987Y49062D03*
X742840Y39832D03*
X736790D03*
X745130Y69508D03*
X738043D03*
X730957D03*
X731330Y60712D03*
X730820Y84062D03*
X737623Y98858D03*
X734523Y98758D03*
X735733Y111988D03*
X733220Y388362D03*
X737621Y411714D03*
X743720Y404362D03*
X743820Y408262D03*
X731322Y430612D03*
Y462108D03*
X737621Y481006D03*
X730070Y506212D03*
X744630Y506529D03*
X745220Y530362D03*
X737299Y766887D03*
X737784Y1360017D03*
X730752Y1384080D03*
X731794Y1381583D03*
Y1378983D03*
X732238Y1388343D03*
X738810Y1396665D03*
X741540Y1396585D03*
X739170Y1405655D03*
X741670Y1405675D03*
X738170Y1414185D03*
X740760Y1414165D03*
X741382Y1590691D03*
X758606Y23797D03*
X747487Y49062D03*
X752720Y59002D03*
X754219Y75707D03*
X754633Y108288D03*
Y105288D03*
X762172Y123898D03*
X754290Y286632D03*
X755200Y296062D03*
X759940Y438232D03*
X758420Y447662D03*
X751220Y530362D03*
X753137Y766625D03*
X757779Y1390645D03*
X757542Y1420684D03*
X761770Y1695347D03*
X765606Y44894D03*
X769474Y75360D03*
X765858Y87340D03*
X762368Y84088D03*
X769284Y103895D03*
X767061Y99959D03*
X767045Y95960D03*
X767028Y91490D03*
X776730Y117479D03*
X773943Y114633D03*
X771131Y111788D03*
X769775Y107977D03*
X766769Y140138D03*
X771774Y167518D03*
X773220Y296262D03*
X772866Y311558D03*
X776100Y375100D03*
X766195Y418212D03*
X765315Y464862D03*
Y488862D03*
X772220Y530362D03*
X775317Y764025D03*
X763747Y764335D03*
X768520Y1379962D03*
X768620Y1392762D03*
X767820Y1410262D03*
X785095Y49388D03*
X780617Y296345D03*
X779120Y306162D03*
X794600Y360600D03*
X787925Y387900D03*
X781195Y418212D03*
X791590Y417050D03*
X780020Y438287D03*
X781410Y431822D03*
X780340Y468982D03*
Y474862D03*
X793673Y512862D03*
X792720Y589862D03*
X789720Y581862D03*
X783100Y593582D03*
X788225Y1388683D03*
X805095Y49388D03*
X797443Y271469D03*
X806300Y279662D03*
X809700Y273562D03*
X795190Y298572D03*
X798620Y312773D03*
X809800Y360600D03*
X802200D03*
X806588Y351097D03*
X799800Y368700D03*
X802220Y393727D03*
X803150Y408512D03*
X795600Y402500D03*
X799458Y431217D03*
X795370Y474862D03*
X801567Y512942D03*
X798720Y585362D03*
X798220Y597362D03*
X808860Y603802D03*
X797720Y617862D03*
X799637Y763625D03*
X825095Y49388D03*
X821118Y134632D03*
X825698Y139062D03*
X813900Y269698D03*
X827403Y286625D03*
X816420Y287062D03*
X813855Y354008D03*
X820936Y356956D03*
X824980Y405260D03*
Y409260D03*
X821720Y428437D03*
X818500Y451700D03*
X816500Y476800D03*
X821720Y519082D03*
X815040Y590772D03*
X814800Y760922D03*
X822442Y762369D03*
X814234Y1340465D03*
X830975Y2388D03*
X830990Y4903D03*
X837268Y3597D03*
X830975Y22446D03*
Y8543D03*
Y12417D03*
X830990Y14932D03*
X830975Y18572D03*
X837268Y13626D03*
X830990Y24961D03*
X837268Y23655D03*
X836126Y62681D03*
X837791Y85186D03*
X831297Y104206D03*
X842864Y110296D03*
X830339Y228143D03*
X829680Y264580D03*
X836210Y272452D03*
X829720Y277562D03*
X829800Y271562D03*
X829320Y296762D03*
X834400Y283862D03*
X834900Y293462D03*
X828222Y359960D03*
X835471Y363003D03*
X843133Y366158D03*
X833300Y386500D03*
X838784Y392880D03*
X839200Y434300D03*
X841300Y446800D03*
X842600Y477200D03*
X842341Y474241D03*
X841795Y492862D03*
X829745Y498082D03*
X834635Y515447D03*
X830480Y527817D03*
X831700Y596962D03*
X836847Y762495D03*
X828799Y1336870D03*
X828910Y1331756D03*
Y1341725D03*
X845095Y49388D03*
X854107Y91232D03*
X850280Y113852D03*
X853828Y265057D03*
X854333Y276117D03*
X854338Y280027D03*
Y283527D03*
X852800Y288562D03*
X853200Y297462D03*
X856700Y304862D03*
X848000Y374622D03*
X851396Y369614D03*
X859734Y373032D03*
X857560Y417762D03*
X844200Y418800D03*
X847830Y443892D03*
X843810Y453322D03*
X846700Y473000D03*
X848710Y505641D03*
X860345Y522162D03*
X856698Y594011D03*
X853200Y751062D03*
X854687Y761685D03*
X865095Y49388D03*
X868187Y72006D03*
X860937Y71877D03*
X861350Y61672D03*
X871980Y199500D03*
X860833Y276817D03*
X863933Y276917D03*
X862043Y290047D03*
X867922Y376450D03*
X875922Y379793D03*
X870700Y382415D03*
Y390620D03*
Y394620D03*
X871320Y416752D03*
X862620Y503162D03*
Y499062D03*
X860345Y513062D03*
X892214Y141891D03*
X878220Y192055D03*
X880943Y283347D03*
Y286347D03*
X880473Y329370D03*
X883472Y382910D03*
X886362Y534380D03*
X886500Y739162D03*
X878152Y876760D03*
X889439Y1437938D03*
X903930Y202885D03*
X903980Y210355D03*
X903930Y217059D03*
X903980Y224529D03*
X893500Y339062D03*
X900061Y510962D03*
X906127Y496343D03*
X900061Y517898D03*
X893298Y534380D03*
X899462Y533380D03*
X906398D03*
X897000Y891895D03*
X894375Y913692D03*
X912214Y141891D03*
X917680Y174999D03*
Y177999D03*
Y171999D03*
X909386Y195925D03*
Y203011D03*
Y210098D03*
Y217185D03*
Y224271D03*
Y231358D03*
X919279Y461244D03*
X920682Y494586D03*
X920980Y503393D03*
X911720Y511662D03*
X911626Y523430D03*
X918562D03*
X924647Y526808D03*
Y533744D03*
X924600Y824262D03*
X922320Y1660953D03*
X932214Y141891D03*
X927133Y189386D03*
X925320Y203399D03*
X940709Y460438D03*
X938437Y455454D03*
X932724Y455538D03*
X926215Y461244D03*
X929234Y494915D03*
X938588Y485197D03*
X929698Y503595D03*
X928231Y530479D03*
X936273Y530478D03*
X927200Y811462D03*
X931496Y962082D03*
X929221Y1014664D03*
X927122Y1661380D03*
X938220Y1661062D03*
X952214Y141891D03*
X949710Y198289D03*
X941634Y199051D03*
Y193451D03*
X951354Y209437D03*
Y203837D03*
X944880Y210959D03*
Y216559D03*
Y230697D03*
Y225097D03*
X954874Y232071D03*
X954904Y225741D03*
X942827Y422743D03*
Y429679D03*
X945800Y432463D03*
Y439399D03*
X946492Y460410D03*
X956188Y495384D03*
Y502320D03*
X948495Y502784D03*
X948693Y509497D03*
X956188Y509484D03*
Y516420D03*
X952622Y529364D03*
X956700Y786862D03*
X941400Y810062D03*
X946100Y1661100D03*
X972214Y141891D03*
X963520Y214699D03*
X960703Y212668D03*
X971471Y242358D03*
X965792Y350959D03*
X965420Y365719D03*
X963856Y394202D03*
X960059Y387004D03*
X972986Y393171D03*
X970054Y478773D03*
Y485709D03*
X966720Y511362D03*
X960620Y509462D03*
X972379Y509303D03*
X959558Y529364D03*
X962162Y535130D03*
X969098D03*
X958755Y657078D03*
X963520Y665062D03*
X958866Y662378D03*
X959100Y789862D03*
X965622Y1579240D03*
Y1576240D03*
Y1573240D03*
X975688Y152950D03*
Y149950D03*
X985016Y344659D03*
X974791Y339990D03*
X986182Y361062D03*
X979380Y373082D03*
X988159Y409068D03*
X983760Y424292D03*
X980092Y421289D03*
X983720Y512362D03*
X976283Y534226D03*
X988988Y1579240D03*
Y1573240D03*
Y1576240D03*
X994553Y365711D03*
X997598Y382952D03*
X997612Y391804D03*
X1006221Y382945D03*
X997900Y400720D03*
X993387Y429827D03*
X999720Y512862D03*
X991097Y529902D03*
X996675Y1286985D03*
X1012214Y141826D03*
X1022002Y267342D03*
Y270142D03*
X1013500Y344900D03*
X1015638Y382968D03*
X1015637Y391334D03*
X1006589Y392017D03*
X1006750Y401010D03*
X1015657Y401013D03*
X1021259Y420548D03*
X1007249Y422682D03*
X1017511Y430038D03*
X1008720Y498362D03*
X1019145Y503823D03*
X1011720Y589362D03*
X1018720Y592362D03*
X1021720Y601862D03*
X1010630Y748741D03*
X1012354Y1579240D03*
Y1573240D03*
Y1576240D03*
X1023407Y-27681D03*
X1029700Y-26472D03*
X1023407Y-32055D03*
X1029700Y-37001D03*
X1023407Y-17652D03*
X1023422Y-15137D03*
X1023407Y-11497D03*
X1029700Y-16443D03*
X1023422Y-25166D03*
X1023407Y-21526D03*
X1029700Y3615D03*
X1023422Y4921D03*
X1023407Y2406D03*
X1023422Y-5108D03*
X1023407Y-7623D03*
Y-1468D03*
X1029700Y-6414D03*
X1023407Y22464D03*
Y18590D03*
Y8561D03*
X1023422Y14950D03*
X1023407Y12435D03*
X1029700Y13644D03*
Y23673D03*
X1023422Y24979D03*
X1038609Y49388D03*
X1027520Y122732D03*
X1037650Y128842D03*
X1023220Y187574D03*
X1031502Y267342D03*
X1028202D03*
X1025102D03*
X1033133Y272564D03*
X1031502Y270142D03*
X1029833Y272564D03*
X1026733D03*
X1023633D03*
X1028202Y270142D03*
X1025102D03*
X1029094Y383070D03*
Y387872D03*
X1033860Y400802D03*
X1038294Y506504D03*
X1027190Y510672D03*
X1029220Y520032D03*
X1035720Y1579240D03*
Y1573240D03*
Y1576240D03*
X1043629Y375078D03*
Y372578D03*
X1049100Y390162D03*
X1046156Y442699D03*
X1058609Y49388D03*
X1066820Y151632D03*
X1072310Y364422D03*
X1059086Y1579240D03*
Y1573240D03*
Y1576240D03*
X1078609Y49388D03*
X1075100Y55682D03*
X1084146Y67102D03*
X1078270Y93462D03*
X1077270Y369061D03*
Y374131D03*
Y379251D03*
X1073724Y476867D03*
X1081906Y472577D03*
X1076739Y506461D03*
X1077751Y522235D03*
X1098609Y49388D03*
X1097794Y67881D03*
X1102480Y133722D03*
X1105553Y356475D03*
X1096477Y744385D03*
X1102930Y1668690D03*
X1092072Y1734244D03*
X1118609Y49388D03*
X1118110Y1398010D03*
X1109118Y1526046D03*
X1116338Y1711380D03*
X1113055Y1718338D03*
X1132856Y52926D03*
X1129948Y66786D03*
X1127788Y1397126D03*
X1131629Y1420615D03*
X1129029D03*
X1134229D03*
X1123674Y1414936D03*
X1121174D03*
X1123674Y1417536D03*
Y1420136D03*
X1121174Y1417536D03*
Y1420136D03*
X1131629Y1423722D03*
X1129029D03*
X1134229D03*
X1123674Y1422736D03*
X1121174D03*
X1131042Y1436061D03*
X1135942D03*
X1133512D03*
X1131042Y1430461D03*
X1135942D03*
X1133512D03*
X1134429Y1426829D03*
X1136004Y1447858D03*
X1126117Y1450504D03*
X1127008Y1550285D03*
X1133780Y1550301D03*
X1138609Y49388D03*
X1145603Y73679D03*
X1140465Y379592D03*
X1142302Y366532D03*
X1142790Y611122D03*
X1146118Y1397126D03*
X1150843Y1415126D03*
X1148243D03*
X1150843Y1417726D03*
X1148243D03*
X1150732Y1420326D03*
X1142629Y1420615D03*
X1145573Y1420631D03*
X1139429Y1420615D03*
X1136829D03*
X1145573Y1423738D03*
X1136829Y1423722D03*
X1145542Y1426861D03*
X1137029Y1426829D03*
X1145108Y1476732D03*
X1158609Y49388D03*
X1156790Y373231D03*
X1153467Y586462D03*
X1153490Y610322D03*
X1165931Y1397126D03*
X1154714Y1398295D03*
X1157786Y1398252D03*
X1167172Y1420615D03*
X1153913Y1420606D03*
Y1415406D03*
Y1418006D03*
X1159124D03*
Y1420606D03*
Y1415406D03*
X1161724D03*
Y1420606D03*
Y1418006D03*
X1156524Y1415406D03*
Y1420606D03*
Y1418006D03*
X1167172Y1423722D03*
X1153913Y1423206D03*
X1159124D03*
X1161724D03*
X1156524D03*
X1155964Y1440864D03*
X1164260Y1450423D03*
X1158954Y1450274D03*
X1168192Y1604130D03*
X1152950Y1616470D03*
X1165950Y1617729D03*
X1152930Y1633880D03*
X1174980Y585632D03*
X1174880Y592652D03*
X1173990Y602192D03*
X1183230Y739102D03*
X1184661Y1397126D03*
X1183716Y1420631D03*
X1180772Y1420615D03*
X1174972D03*
X1177572D03*
X1172372D03*
X1169772D03*
X1183716Y1423738D03*
X1174972Y1423722D03*
X1172372D03*
X1169772D03*
X1174085Y1436061D03*
Y1430461D03*
X1171655Y1436061D03*
X1169185D03*
X1171655Y1430461D03*
X1169185D03*
X1183685Y1426861D03*
X1175172Y1426829D03*
X1172572D03*
X1174147Y1447858D03*
X1179922Y1550285D03*
X1184501Y1606521D03*
X1185030Y1633010D03*
X1182470Y1618914D03*
X1172530Y1623020D03*
X1176900Y1627510D03*
X1198609Y49388D03*
X1188720Y56755D03*
X1191700Y56822D03*
X1185500Y101400D03*
X1190700Y99000D03*
X1197627Y132859D03*
X1196100Y188962D03*
X1193500D03*
X1192600Y217662D03*
X1193000Y204486D03*
X1195500D03*
X1195100Y217662D03*
X1194840Y240672D03*
X1199027Y588714D03*
X1189135Y1397529D03*
X1187736Y1420387D03*
X1188986Y1415287D03*
Y1417887D03*
X1186386Y1415287D03*
Y1417887D03*
X1191486Y1415287D03*
Y1417887D03*
X1190444Y1420384D03*
X1194750Y1424672D03*
X1197700Y1432672D03*
X1191930Y1424647D03*
X1198010Y1441902D03*
X1198880Y1457162D03*
X1197181Y1563587D03*
X1195994Y1580678D03*
Y1575686D03*
X1200950Y1580678D03*
Y1575686D03*
X1201294Y1599884D03*
X1195994Y1592590D03*
Y1587598D03*
X1200950Y1592590D03*
Y1587598D03*
X1201294Y1604876D03*
Y1611796D03*
Y1616788D03*
X1213026Y56742D03*
X1201800Y94600D03*
X1204800Y108900D03*
X1206900Y115900D03*
X1214573Y148909D03*
X1204420Y195362D03*
X1210084Y224362D03*
X1207220Y247148D03*
X1217720Y249862D03*
X1204880Y754032D03*
X1213010Y1575686D03*
X1208054D03*
X1213010Y1580678D03*
X1208054D03*
X1206250Y1599884D03*
X1213354D03*
X1213010Y1587598D03*
X1208054D03*
X1213010Y1592590D03*
X1208054D03*
X1206250Y1604876D03*
Y1611796D03*
Y1616788D03*
X1213354D03*
Y1604876D03*
Y1611796D03*
X1213980Y1676500D03*
X1218609Y49388D03*
X1228420Y58862D03*
X1230250Y89450D03*
X1223720Y217862D03*
Y205862D03*
X1232000Y244332D03*
Y248332D03*
X1225070Y1580678D03*
Y1575686D03*
X1220114D03*
Y1580678D03*
X1232174D03*
Y1575686D03*
X1218310Y1599884D03*
X1225414D03*
X1230370D03*
X1225070Y1592590D03*
X1220114D03*
X1225070Y1587598D03*
X1220114D03*
X1232174D03*
Y1592590D03*
X1218310Y1616788D03*
Y1604876D03*
Y1611796D03*
X1225414D03*
Y1604876D03*
X1230370Y1611796D03*
Y1604876D03*
X1225414Y1616788D03*
X1230370D03*
X1238609Y49388D03*
X1239907Y95008D03*
X1243808Y116832D03*
X1247333Y121999D03*
X1236520Y213462D03*
X1246444Y256098D03*
X1252040Y306480D03*
X1237130Y1575686D03*
Y1580678D03*
X1244234D03*
X1249190D03*
X1244234Y1575686D03*
X1249190D03*
X1242430Y1599884D03*
X1237474D03*
X1249534D03*
X1237130Y1587598D03*
Y1592590D03*
X1249190D03*
X1244234D03*
Y1587598D03*
X1249190D03*
X1242430Y1616788D03*
X1237474D03*
X1242430Y1611796D03*
Y1604876D03*
X1237474Y1611796D03*
Y1604876D03*
X1249534Y1611796D03*
Y1604876D03*
Y1616788D03*
X1258609Y49388D03*
X1262800Y101100D03*
X1264620Y92724D03*
X1252961Y111903D03*
X1267150Y305998D03*
X1256787Y749605D03*
X1261250Y1575686D03*
X1256294D03*
X1261250Y1580678D03*
X1256294D03*
X1254490Y1599884D03*
X1261594D03*
X1261250Y1587598D03*
X1256294D03*
X1261250Y1592590D03*
X1256294D03*
X1254490Y1611796D03*
Y1604876D03*
Y1616788D03*
X1261594D03*
Y1611796D03*
Y1604876D03*
X1278300Y81232D03*
X1280135Y1340002D03*
Y1337402D03*
Y1345202D03*
Y1342602D03*
X1280312Y1365689D03*
X1273310Y1580678D03*
Y1575592D03*
X1268354D03*
Y1580678D03*
X1280414Y1575686D03*
Y1580678D03*
X1266550Y1599884D03*
X1273654Y1599790D03*
X1278610D03*
X1273310Y1592590D03*
X1268354D03*
X1273310Y1587598D03*
X1268354D03*
X1280414D03*
Y1592590D03*
X1266550Y1616788D03*
Y1611796D03*
Y1604876D03*
X1273654Y1611796D03*
Y1604876D03*
X1278610Y1611796D03*
Y1604876D03*
X1273654Y1616788D03*
X1278610D03*
X1295278Y297056D03*
X1290322D03*
X1294937Y746965D03*
X1292904Y782048D03*
X1292614Y789910D03*
X1291205Y1345875D03*
X1286005Y1342768D03*
Y1345875D03*
X1296405Y1342768D03*
X1293805D03*
X1288605D03*
X1291205D03*
X1288605Y1345875D03*
X1293805D03*
X1291405Y1348982D03*
X1294005D03*
X1292916Y1352531D03*
X1290436D03*
X1287956D03*
X1292916Y1358131D03*
X1290436D03*
X1287956D03*
X1283280Y1372301D03*
X1293887Y1370043D03*
X1294477Y1372651D03*
X1285370Y1575686D03*
Y1580678D03*
X1297430D03*
X1292474D03*
Y1575686D03*
X1297430D03*
X1285714Y1599884D03*
X1290670D03*
X1297774D03*
X1285370Y1587598D03*
Y1592590D03*
X1297430D03*
X1292474D03*
X1297430Y1587598D03*
X1292474D03*
X1290670Y1616788D03*
X1285714D03*
Y1611796D03*
X1290670D03*
X1285714Y1604876D03*
X1290670D03*
X1297774Y1611796D03*
Y1604876D03*
Y1616788D03*
X1311960Y49672D03*
X1314450Y319841D03*
X1312845Y324764D03*
X1305909D03*
X1303017Y785837D03*
X1311952Y1321945D03*
X1307656Y1337104D03*
X1305056D03*
X1307656Y1334504D03*
Y1329304D03*
Y1331904D03*
X1305056Y1334504D03*
Y1329304D03*
Y1331904D03*
Y1339704D03*
X1312488Y1348353D03*
X1299605Y1342768D03*
X1302549Y1345891D03*
X1302520Y1348762D03*
X1315058Y1349488D03*
X1302549Y1342784D03*
X1309490Y1575686D03*
X1304534D03*
X1309490Y1580678D03*
X1304534D03*
X1302730Y1599884D03*
X1309834D03*
X1314790D03*
X1309490Y1587598D03*
X1304534D03*
X1309490Y1592590D03*
X1304534D03*
X1302730Y1611796D03*
Y1604876D03*
Y1616788D03*
X1309834D03*
Y1611796D03*
Y1604876D03*
X1314790Y1616788D03*
Y1611796D03*
Y1604876D03*
X1318609Y49388D03*
X1319125Y296540D03*
X1324081D03*
X1324636Y290920D03*
X1329592D03*
X1330248Y325670D03*
X1323312D03*
X1321386Y319841D03*
X1329977Y334384D03*
X1327601Y540049D03*
X1317970Y1322741D03*
Y1319634D03*
X1325770Y1322741D03*
X1323170D03*
X1331570Y1319634D03*
X1323170D03*
X1325770D03*
X1328370D03*
X1320570Y1322741D03*
Y1319634D03*
X1322444Y1329497D03*
X1324924D03*
X1319964D03*
X1322444Y1335097D03*
X1324924D03*
X1319964D03*
X1323370Y1325848D03*
X1325970D03*
X1324945Y1346877D03*
X1327196Y1349068D03*
X1321550Y1580678D03*
X1316594D03*
X1321550Y1575686D03*
X1316594D03*
X1328654D03*
Y1580678D03*
X1321894Y1599884D03*
X1326850D03*
X1321550Y1592590D03*
X1316594D03*
X1321550Y1587598D03*
X1316594D03*
X1328654D03*
Y1592590D03*
X1321894Y1611796D03*
Y1604876D03*
X1326850Y1611796D03*
Y1604876D03*
X1321894Y1616788D03*
X1326850D03*
X1332726Y-27681D03*
X1339019Y-26472D03*
X1332726Y-32055D03*
X1339019Y-37001D03*
X1332726Y-11497D03*
X1339019Y-16443D03*
X1332741Y-15137D03*
X1332726Y-17652D03*
Y-21526D03*
X1332741Y-25166D03*
X1332726Y2406D03*
X1332741Y4921D03*
X1339019Y3615D03*
X1332726Y-1468D03*
X1339019Y-6414D03*
X1332726Y-7623D03*
X1332741Y-5108D03*
X1332726Y18590D03*
Y22464D03*
X1339019Y13644D03*
X1332726Y12435D03*
X1332741Y14950D03*
X1332726Y8561D03*
X1332741Y24979D03*
X1339019Y23673D03*
X1338609Y49388D03*
X1346720Y82912D03*
X1343362Y283155D03*
X1335947Y290755D03*
X1340903D03*
X1343656Y330749D03*
X1343199Y324461D03*
X1336263D03*
X1336913Y334384D03*
X1335643Y540048D03*
X1336187Y755635D03*
X1339784Y1306506D03*
X1337184D03*
X1344080Y1305919D03*
X1343968Y1300579D03*
X1344080Y1308519D03*
X1334514Y1322757D03*
Y1319650D03*
X1337184Y1309106D03*
X1339784D03*
X1338534Y1319406D03*
X1339784Y1316906D03*
Y1314306D03*
Y1311706D03*
X1337184Y1314306D03*
Y1316906D03*
Y1311706D03*
X1334414Y1325853D03*
X1347015Y1335876D03*
X1343631Y1332568D03*
X1333610Y1575686D03*
Y1580678D03*
X1345670D03*
X1340714D03*
X1345670Y1575686D03*
X1340714D03*
X1338910Y1599884D03*
X1333954D03*
X1346014D03*
X1333610Y1587598D03*
Y1592590D03*
X1345670D03*
X1340714D03*
X1345670Y1587598D03*
X1340714D03*
X1338910Y1616788D03*
Y1611796D03*
Y1604876D03*
X1333954Y1616788D03*
Y1611796D03*
Y1604876D03*
X1346014Y1611796D03*
Y1604876D03*
Y1616788D03*
X1350550Y101632D03*
X1363846Y279848D03*
X1349362Y283155D03*
X1353902Y287540D03*
X1359902D03*
X1350592Y330749D03*
X1356968Y339611D03*
X1350032D03*
X1363539Y334043D03*
X1356603D03*
X1350098Y1306208D03*
X1352698D03*
X1355298D03*
X1360498D03*
X1363698D03*
X1357898D03*
X1352698Y1309315D03*
X1350098D03*
X1355498Y1312422D03*
X1358098D03*
X1355298Y1309315D03*
X1357898D03*
X1352092Y1316071D03*
Y1321671D03*
X1357052Y1316071D03*
X1354572D03*
X1357052Y1321671D03*
X1354572D03*
X1356983Y1334095D03*
X1359516Y1334058D03*
X1355357Y1396020D03*
X1357730Y1575686D03*
X1352774D03*
X1357730Y1580678D03*
X1352774D03*
X1350970Y1599884D03*
X1363030D03*
X1358074D03*
X1357730Y1587598D03*
X1352774D03*
X1357730Y1592590D03*
X1352774D03*
X1350970Y1611796D03*
Y1604876D03*
Y1616788D03*
X1363030D03*
Y1611796D03*
Y1604876D03*
X1358074Y1616788D03*
Y1611796D03*
Y1604876D03*
X1378550Y110692D03*
X1377742Y244372D03*
Y250372D03*
X1377626Y258914D03*
Y264914D03*
X1369846Y279848D03*
X1372381Y661428D03*
X1371931Y672978D03*
Y685278D03*
X1372243Y697108D03*
Y709108D03*
Y721108D03*
X1370662Y1305980D03*
X1371912Y1303480D03*
X1376208Y1305919D03*
Y1303319D03*
X1371912Y1300880D03*
X1376208Y1300719D03*
Y1295586D03*
X1371912Y1295747D03*
Y1298280D03*
X1376208Y1298119D03*
X1369312Y1303480D03*
X1366642Y1306224D03*
X1369312Y1300880D03*
Y1295747D03*
Y1298280D03*
X1376208Y1308519D03*
X1366542Y1312427D03*
X1366642Y1309331D03*
X1379271Y1335963D03*
X1375814Y1332653D03*
X1377060Y1411231D03*
X1371960Y1436172D03*
X1365040Y1431142D03*
X1369790Y1580678D03*
X1364834D03*
X1369790Y1575592D03*
X1364834D03*
X1376894Y1575686D03*
Y1580678D03*
X1375090Y1599790D03*
X1370134D03*
X1369790Y1592590D03*
X1364834D03*
X1369790Y1587598D03*
X1364834D03*
X1376894D03*
Y1592590D03*
X1375090Y1611796D03*
Y1604876D03*
Y1616788D03*
X1370134Y1611796D03*
Y1604876D03*
Y1616788D03*
X1383480Y88932D03*
X1383734Y243329D03*
Y237329D03*
X1388778Y250661D03*
X1388908Y260301D03*
X1386237Y265620D03*
Y275200D03*
X1385190Y501242D03*
X1390220Y497742D03*
X1381131Y656378D03*
Y668378D03*
X1395831Y666278D03*
X1386931Y660978D03*
X1381131Y680278D03*
X1396031Y680678D03*
X1386931Y675478D03*
X1387143Y690208D03*
X1380731Y692208D03*
X1395631Y695108D03*
X1380731Y704208D03*
X1387143Y704708D03*
X1380731Y716208D03*
X1395631Y709608D03*
X1387143Y719235D03*
X1395631Y724135D03*
X1382920Y733725D03*
X1391408Y738625D03*
X1382226Y1306208D03*
X1384826D03*
X1387426D03*
X1390026D03*
X1392626D03*
X1395826D03*
X1386700Y1321671D03*
X1389180D03*
X1382226Y1309315D03*
X1384826D03*
X1390226Y1312422D03*
X1387626D03*
X1390026Y1309315D03*
X1387426D03*
X1384220Y1316071D03*
Y1321671D03*
X1389180Y1316071D03*
X1386700D03*
X1390758Y1333473D03*
X1392076Y1335658D03*
X1388813Y1393160D03*
X1396115Y1405289D03*
Y1412789D03*
X1396615Y1420289D03*
X1384695Y1425047D03*
X1392475Y1576097D03*
X1381850Y1575686D03*
Y1580678D03*
X1396600Y1582500D03*
X1387150Y1599884D03*
X1382194D03*
X1381850Y1587598D03*
Y1592590D03*
X1396600Y1594000D03*
X1387150Y1616788D03*
X1382194D03*
X1387150Y1611796D03*
Y1604876D03*
X1382194Y1611796D03*
Y1604876D03*
X1404630Y220018D03*
X1412270Y230952D03*
X1405436Y238378D03*
X1400207Y238257D03*
X1398770Y1306224D03*
X1404040Y1303480D03*
X1408336Y1305919D03*
Y1303319D03*
X1404040Y1300880D03*
X1408336Y1300719D03*
Y1295586D03*
X1404040Y1295747D03*
Y1298280D03*
X1408336Y1298119D03*
X1401440Y1303480D03*
X1402790Y1305980D03*
X1401440Y1300880D03*
Y1295747D03*
Y1298280D03*
X1408336Y1308519D03*
X1398670Y1312427D03*
X1398770Y1309331D03*
X1411124Y1335924D03*
X1407719Y1332560D03*
X1403615Y1405289D03*
X1411115D03*
Y1412789D03*
X1403615Y1420289D03*
X1411115D03*
X1403350Y1516435D03*
X1403590Y1532255D03*
X1403350Y1521335D03*
X1403740Y1548375D03*
X1403590Y1537155D03*
X1403740Y1543475D03*
X1407200Y1591400D03*
X1411070Y1603282D03*
X1400000Y1630362D03*
Y1642362D03*
X1413350Y220018D03*
X1416020D03*
X1424690D03*
X1424520Y225002D03*
X1416810Y225422D03*
X1428640Y230022D03*
X1431430Y251265D03*
X1428940Y269292D03*
X1414354Y1306208D03*
X1416954D03*
X1419554D03*
X1422154D03*
X1424754D03*
X1427954D03*
X1418828Y1316071D03*
X1416348D03*
X1418828Y1321671D03*
X1416348D03*
X1421308Y1316071D03*
Y1321671D03*
X1414354Y1309315D03*
X1416954D03*
X1419554D03*
X1422354Y1312422D03*
X1419754D03*
X1422154Y1309315D03*
X1421294Y1334095D03*
X1423656Y1335468D03*
X1429345Y1433695D03*
X1427349Y1442776D03*
X1414264Y1439494D03*
X1419256Y1440258D03*
X1423829Y1442776D03*
X1416800Y1564862D03*
X1428403Y1581378D03*
X1418241Y1583441D03*
X1422145Y1575362D03*
X1426680Y1603262D03*
X1425770Y1633772D03*
X1413230Y1641042D03*
X1438609Y49388D03*
X1441125Y57362D03*
X1438680Y64412D03*
X1441490Y224062D03*
X1438720Y220018D03*
X1430130Y259342D03*
X1437177Y720965D03*
X1437182Y1298991D03*
X1430898Y1306224D03*
X1434582Y1304191D03*
Y1306791D03*
Y1301591D03*
Y1296458D03*
Y1298991D03*
X1440507Y1305430D03*
Y1302830D03*
Y1300230D03*
X1440536Y1296455D03*
X1440464Y1308519D03*
X1437182Y1304191D03*
Y1306791D03*
Y1301591D03*
Y1296458D03*
X1430798Y1312427D03*
X1430898Y1309331D03*
X1443785Y1335981D03*
X1440879Y1333085D03*
X1439155Y1399064D03*
X1431717Y1420625D03*
Y1417125D03*
Y1409125D03*
Y1427632D03*
X1436330Y1521152D03*
X1436570Y1536972D03*
X1436720Y1548192D03*
X1437140Y1576012D03*
X1438300Y1598400D03*
X1430250Y1608442D03*
X1438300Y1611000D03*
X1438273Y1671103D03*
X1458609Y49388D03*
X1458720Y153362D03*
Y149362D03*
Y169862D03*
Y165862D03*
Y161862D03*
Y157862D03*
Y181862D03*
Y177862D03*
Y173862D03*
X1446830Y236232D03*
X1453670Y278170D03*
X1459312Y341130D03*
X1460600Y352742D03*
X1456700Y369642D03*
X1454889Y658712D03*
X1454439Y670262D03*
Y682562D03*
X1454751Y694392D03*
Y706392D03*
X1454439Y718362D03*
X1459057Y733545D03*
X1457597Y739035D03*
X1446482Y1306208D03*
X1449082D03*
X1451682D03*
X1456882D03*
X1460082D03*
X1454282D03*
X1450956Y1321671D03*
X1448476D03*
X1453436Y1316071D03*
Y1321671D03*
X1446482Y1309315D03*
X1451882Y1312422D03*
X1449082Y1309315D03*
X1451682D03*
X1454482Y1312422D03*
X1454282Y1309315D03*
X1450956Y1316071D03*
X1448476D03*
X1453303Y1334095D03*
X1455436Y1335598D03*
X1461377Y1417844D03*
X1459135Y1439627D03*
X1459136Y1442241D03*
X1461517Y1575686D03*
Y1580678D03*
X1446600Y1595400D03*
X1461517Y1587598D03*
Y1592590D03*
X1460441Y1602441D03*
X1446786Y1610639D03*
X1452757Y1671399D03*
X1446380Y1676291D03*
X1464200Y67802D03*
X1470220Y145362D03*
X1470101Y207751D03*
X1476858Y225448D03*
X1466940Y230272D03*
X1466958Y244948D03*
X1468620Y258857D03*
X1467230Y252472D03*
X1466660Y273878D03*
X1475790Y404842D03*
X1473310Y418502D03*
X1463639Y653662D03*
X1469651Y655992D03*
X1462010Y645842D03*
X1463639Y665662D03*
X1478139Y660892D03*
X1469439Y670262D03*
X1463639Y677562D03*
X1463239Y689492D03*
X1478139Y689892D03*
X1469651Y684992D03*
X1463239Y701492D03*
X1478139Y704392D03*
X1469477Y699475D03*
X1463239Y713492D03*
X1478139Y718892D03*
X1469651Y713992D03*
X1474100Y735662D03*
X1466451Y726992D03*
X1474939Y731892D03*
X1472592Y1306345D03*
X1463026Y1306224D03*
X1465696Y1303480D03*
X1467046Y1305980D03*
X1468296Y1303480D03*
X1465696Y1300880D03*
X1468296D03*
X1472361Y1322440D03*
X1472592Y1308945D03*
Y1316745D03*
Y1314145D03*
Y1311545D03*
X1462926Y1312427D03*
X1463026Y1309331D03*
X1475599Y1349468D03*
X1475959Y1385027D03*
X1476000Y1393027D03*
X1465747Y1401405D03*
X1466448Y1421499D03*
X1475935Y1439627D03*
X1475936Y1442241D03*
X1467550Y1439642D03*
X1467536Y1442241D03*
X1473577Y1580678D03*
Y1575686D03*
X1466473D03*
Y1580678D03*
X1471773Y1599884D03*
X1466817D03*
X1473577Y1592590D03*
Y1587598D03*
X1466473D03*
Y1592590D03*
X1466817Y1611796D03*
X1471773D03*
X1466817Y1604876D03*
X1471773D03*
Y1616788D03*
X1466817D03*
X1478609Y49388D03*
X1481360Y358792D03*
X1488500Y410152D03*
X1478539Y675462D03*
X1486410Y1322741D03*
X1483810D03*
X1486410Y1319634D03*
X1483810D03*
X1481210Y1322741D03*
Y1319634D03*
X1492210D03*
X1489010D03*
X1478610Y1322741D03*
Y1319634D03*
X1484010Y1325848D03*
X1486610D03*
X1485564Y1335097D03*
X1483084D03*
X1485564Y1329497D03*
X1483084D03*
X1480604Y1335097D03*
Y1329497D03*
X1485523Y1347521D03*
X1487386Y1349258D03*
X1478559Y1385027D03*
X1481159Y1384727D03*
X1478600Y1393027D03*
X1481107Y1393095D03*
X1484395Y1439598D03*
X1484336Y1442241D03*
X1490593Y1580678D03*
Y1575686D03*
X1485637D03*
Y1580678D03*
X1478533D03*
Y1575686D03*
X1490937Y1599884D03*
X1478877D03*
X1483833D03*
X1490593Y1587598D03*
X1485637D03*
Y1592590D03*
X1490593D03*
X1478533D03*
Y1587598D03*
X1490937Y1604876D03*
Y1611796D03*
Y1616788D03*
X1483833D03*
X1478877D03*
Y1611796D03*
X1483833D03*
X1478877Y1604876D03*
X1483833D03*
X1498609Y49388D03*
X1496200Y359522D03*
X1497880Y373062D03*
X1503450Y382693D03*
X1497770Y732502D03*
X1495154Y1322757D03*
Y1319650D03*
X1499048Y1319946D03*
X1504720Y1329143D03*
X1495054Y1325853D03*
X1503786Y1326076D03*
X1504518Y1335982D03*
X1504720Y1342143D03*
Y1344743D03*
X1505116Y1369724D03*
X1509757Y1575686D03*
Y1580678D03*
X1502653D03*
X1497697D03*
X1502653Y1575686D03*
X1497697D03*
X1502997Y1599884D03*
X1507953D03*
X1495893D03*
X1509757Y1587598D03*
Y1592590D03*
X1502653D03*
X1497697D03*
X1502653Y1587598D03*
X1497697D03*
X1502997Y1616788D03*
X1507953D03*
X1502997Y1604876D03*
Y1611796D03*
X1507953Y1604876D03*
Y1611796D03*
X1495893Y1604876D03*
Y1611796D03*
Y1616788D03*
X1518608Y49377D03*
X1522920Y113030D03*
X1526675Y140117D03*
X1526083Y146225D03*
X1513759Y263676D03*
X1516683Y278437D03*
X1511624Y291175D03*
X1519336Y303426D03*
X1520094Y306543D03*
X1514369Y308467D03*
X1524505Y748912D03*
X1522066Y1312808D03*
X1526066D03*
X1518066D03*
X1515066D03*
X1511066D03*
X1510738Y1345539D03*
Y1342432D03*
X1518538Y1345539D03*
Y1342432D03*
X1515938Y1345539D03*
Y1342432D03*
X1513338Y1345539D03*
Y1342432D03*
X1521138D03*
X1524338D03*
X1518738Y1348646D03*
X1516138D03*
X1515212Y1352295D03*
X1512732D03*
X1517692D03*
X1515212Y1357895D03*
X1512732D03*
X1517692D03*
X1518451Y1369919D03*
X1521817Y1580678D03*
Y1575686D03*
X1514713D03*
Y1580678D03*
X1520013Y1599884D03*
X1515057D03*
X1521817Y1592590D03*
Y1587598D03*
X1514713D03*
Y1592590D03*
X1520013Y1604876D03*
X1515057D03*
X1520013Y1611796D03*
X1515057D03*
Y1616788D03*
X1520013D03*
X1534818Y66801D03*
Y71793D03*
X1539774Y66801D03*
Y71793D03*
X1541774Y69297D03*
X1532818D03*
X1534774Y103093D03*
X1529818D03*
X1535320Y113062D03*
X1529500Y129602D03*
X1545447Y156035D03*
X1537262Y197834D03*
X1540989Y616587D03*
X1535052Y1325904D03*
X1532552Y1334504D03*
X1535052D03*
X1529952D03*
X1532552Y1339704D03*
X1529952D03*
X1537652Y1325904D03*
Y1334504D03*
X1532552Y1337104D03*
X1529952D03*
X1538510Y1346392D03*
X1531302Y1342204D03*
X1535892Y1346354D03*
Y1343754D03*
X1527282Y1345555D03*
Y1342448D03*
X1538757Y1356355D03*
X1527182Y1348651D03*
X1538757Y1360855D03*
Y1365355D03*
X1533877Y1575592D03*
X1538833D03*
X1533877Y1580678D03*
X1538833D03*
X1526773D03*
Y1575686D03*
X1539177Y1599790D03*
X1527117Y1599884D03*
X1532073D03*
X1533877Y1587598D03*
X1538833D03*
X1533877Y1592590D03*
X1538833D03*
X1526773D03*
Y1587598D03*
X1539177Y1611796D03*
Y1604876D03*
Y1616788D03*
X1527117D03*
Y1604876D03*
Y1611796D03*
X1532073Y1616788D03*
Y1604876D03*
Y1611796D03*
X1547768Y3010D03*
X1555635Y16999D03*
Y21991D03*
X1553635Y19495D03*
X1553486Y23935D03*
X1548530D03*
X1546530Y25931D03*
X1555486D03*
X1547429Y37106D03*
X1554515D03*
Y48720D03*
X1547429D03*
X1554818Y69297D03*
X1556818Y66801D03*
Y71793D03*
X1543818Y75297D03*
X1552774D03*
X1550774Y77793D03*
Y72801D03*
X1545818Y77793D03*
Y72801D03*
X1554239Y138263D03*
X1554723Y200375D03*
X1557560Y196912D03*
X1554723Y224529D03*
Y248945D03*
X1554727Y631527D03*
X1550417Y677045D03*
X1550057Y693485D03*
X1548479Y706088D03*
X1557997Y1575686D03*
Y1580678D03*
X1550893D03*
X1545937D03*
X1550893Y1575686D03*
X1545937D03*
X1556193Y1599884D03*
X1551237D03*
X1544133Y1599790D03*
X1557997Y1587598D03*
Y1592590D03*
X1545937D03*
X1550893D03*
Y1587598D03*
X1545937D03*
X1551237Y1616788D03*
X1556193D03*
Y1604876D03*
X1551237D03*
X1556193Y1611796D03*
X1551237D03*
X1544133Y1604876D03*
Y1611796D03*
Y1616788D03*
X1567768Y3010D03*
X1560591Y16999D03*
Y21991D03*
X1569808Y16999D03*
Y21991D03*
X1574764Y16999D03*
Y21991D03*
X1562591Y19495D03*
X1567808D03*
X1567659Y23935D03*
X1562703D03*
X1560703Y25931D03*
X1569659D03*
X1574876D03*
X1561602Y37106D03*
X1568688D03*
Y48720D03*
X1561602D03*
X1563774Y69297D03*
X1561774Y66801D03*
Y71793D03*
X1565818Y75297D03*
X1574774D03*
X1572774Y77793D03*
Y72801D03*
X1567818Y77793D03*
Y72801D03*
X1559860Y240002D03*
X1575169Y303929D03*
X1560717Y648522D03*
X1570720Y729362D03*
X1570057Y1580678D03*
X1575013D03*
X1570057Y1575686D03*
X1575013D03*
X1562953D03*
Y1580678D03*
X1575357Y1599884D03*
X1563297D03*
X1568253D03*
X1570057Y1592590D03*
X1575013D03*
X1570057Y1587598D03*
X1575013D03*
X1562953D03*
Y1592590D03*
X1575357Y1616788D03*
Y1604876D03*
Y1611796D03*
X1563297Y1604876D03*
Y1611796D03*
X1568253Y1604876D03*
Y1611796D03*
X1563297Y1616788D03*
X1568253D03*
X1587768Y3010D03*
X1583981Y16999D03*
Y21991D03*
X1588937Y16999D03*
Y21991D03*
X1576764Y19495D03*
X1581981D03*
X1590937D03*
X1576876Y23935D03*
X1581832D03*
X1591050D03*
X1583832Y25931D03*
X1589050D03*
X1575775Y37106D03*
X1582862D03*
X1589948D03*
Y48720D03*
X1582862D03*
X1575775D03*
X1576818Y69297D03*
X1585774D03*
X1578818Y66801D03*
Y71793D03*
X1583774Y66801D03*
Y71793D03*
X1587818Y75297D03*
X1589818Y77793D03*
Y72801D03*
X1582117Y1575686D03*
X1587073D03*
X1582117Y1580678D03*
X1587073D03*
X1587417Y1599884D03*
X1580313D03*
X1582117Y1587598D03*
X1587073D03*
X1582117Y1592590D03*
X1587073D03*
X1587417Y1604876D03*
Y1611796D03*
Y1616788D03*
X1580313D03*
Y1604876D03*
Y1611796D03*
X1607768Y3010D03*
X1598155Y16999D03*
Y21991D03*
X1603111Y16999D03*
Y21991D03*
X1596155Y19495D03*
X1605111D03*
X1596006Y23935D03*
X1598006Y25931D03*
X1597035Y37106D03*
X1604122D03*
Y48720D03*
X1597035D03*
X1598818Y69297D03*
X1607774D03*
X1600818Y66801D03*
Y71793D03*
X1605774Y66801D03*
Y71793D03*
X1596774Y75297D03*
X1594774Y77793D03*
Y72801D03*
X1603778Y189943D03*
X1603726Y198061D03*
X1596444Y215526D03*
X1598030Y251002D03*
X1606980Y1449922D03*
X1606237Y1575686D03*
Y1580678D03*
X1594177D03*
X1599133D03*
X1594177Y1575686D03*
X1599133D03*
X1599477Y1599884D03*
X1604433D03*
X1592373D03*
X1606237Y1587598D03*
Y1592590D03*
X1594177D03*
X1599133D03*
X1594177Y1587598D03*
X1599133D03*
X1599477Y1616788D03*
X1604433D03*
X1599477Y1604876D03*
Y1611796D03*
X1604433Y1604876D03*
Y1611796D03*
X1592373Y1604876D03*
Y1611796D03*
Y1616788D03*
X1620818Y69297D03*
X1622818Y66801D03*
Y71793D03*
X1609818Y75297D03*
X1618774D03*
X1616774Y77793D03*
Y72801D03*
X1611818Y77793D03*
Y72801D03*
X1623448Y1420028D03*
Y1417428D03*
Y1414828D03*
Y1412228D03*
X1612630Y1418842D03*
X1615597Y1433669D03*
X1618297Y1580678D03*
X1623253D03*
X1618297Y1575686D03*
X1623253D03*
X1611193D03*
Y1580678D03*
X1623597Y1599884D03*
X1611537D03*
X1616493D03*
X1618297Y1592590D03*
X1623253D03*
X1618297Y1587598D03*
X1623253D03*
X1611193D03*
Y1592590D03*
X1623597Y1616788D03*
Y1604876D03*
Y1611796D03*
X1611537Y1604876D03*
Y1611796D03*
X1616493Y1604876D03*
Y1611796D03*
X1611537Y1616788D03*
X1616493D03*
X1634021Y16999D03*
Y21991D03*
X1638977Y16999D03*
Y21991D03*
X1632021Y19495D03*
X1631872Y23935D03*
X1626916D03*
X1624916Y25931D03*
X1633872D03*
X1639089D03*
X1625814Y37106D03*
X1632901D03*
X1639988D03*
X1625814Y48720D03*
X1632901D03*
X1639988D03*
X1629774Y69297D03*
X1627774Y66801D03*
Y71793D03*
X1633022Y75297D03*
X1635022Y77793D03*
X1639978D03*
Y72801D03*
X1635022D03*
X1635032Y196188D03*
X1642135Y414202D03*
X1629262Y1394418D03*
X1625948Y1417428D03*
Y1412228D03*
X1633103Y1417907D03*
X1630503D03*
X1635703D03*
X1633103Y1421014D03*
X1630503D03*
X1635703D03*
X1638303Y1417907D03*
Y1421014D03*
X1625948Y1414828D03*
Y1420028D03*
X1635903Y1424121D03*
X1638503D03*
X1632516Y1427753D03*
Y1433353D03*
X1634986Y1427753D03*
Y1433353D03*
X1637416Y1427753D03*
Y1433353D03*
X1627591Y1447796D03*
X1637478Y1445150D03*
X1630357Y1575592D03*
X1635313D03*
X1630357Y1580678D03*
X1635313D03*
X1640613Y1599790D03*
X1635657D03*
X1628553Y1599884D03*
X1630357Y1587598D03*
X1635313D03*
X1630357Y1592590D03*
X1635313D03*
X1640613Y1604876D03*
Y1611796D03*
X1635657Y1604876D03*
Y1611796D03*
X1640613Y1616788D03*
X1635657D03*
X1628553D03*
Y1604876D03*
Y1611796D03*
X1648194Y16999D03*
Y21991D03*
X1653150Y16999D03*
Y21991D03*
X1640977Y19495D03*
X1646194D03*
X1655150D03*
X1641089Y23935D03*
X1646045D03*
X1648045Y25931D03*
X1654161Y37106D03*
X1647074D03*
Y48720D03*
X1654161D03*
X1644022Y69297D03*
X1652978D03*
X1646022Y66801D03*
Y71793D03*
X1650978Y66801D03*
Y71793D03*
X1655022Y75297D03*
X1641978D03*
X1657022Y77793D03*
Y72801D03*
X1652610Y394727D03*
X1652810Y407402D03*
X1647110Y434177D03*
X1651890Y520540D03*
X1649220Y620662D03*
X1656188Y1394736D03*
X1647592Y1394418D03*
X1655779Y1417618D03*
Y1412418D03*
Y1415018D03*
X1644103Y1417907D03*
X1647047Y1417923D03*
Y1421030D03*
X1653279Y1412418D03*
X1650679D03*
X1653279Y1415018D03*
X1650679D03*
X1653168Y1417618D03*
X1650557D03*
X1640903Y1417907D03*
X1647016Y1424153D03*
X1648947Y1476695D03*
X1647373Y1580678D03*
X1642417D03*
X1647373Y1575686D03*
X1642417D03*
X1647717Y1599884D03*
X1652673D03*
X1647373Y1592590D03*
X1642417D03*
X1647373Y1587598D03*
X1642417D03*
X1647717Y1616788D03*
X1652673D03*
X1647717Y1604876D03*
Y1611796D03*
X1652673Y1604876D03*
Y1611796D03*
X1671050Y23935D03*
X1669050Y25931D03*
X1669948Y37106D03*
Y48720D03*
X1666022Y69297D03*
X1668022Y66801D03*
Y71793D03*
X1672978Y66801D03*
Y71793D03*
X1663978Y75297D03*
X1661978Y77793D03*
Y72801D03*
X1668030Y200580D03*
X1666074Y229710D03*
X1660176Y231100D03*
X1670400Y229462D03*
X1659610Y394727D03*
X1663610D03*
X1661110Y434177D03*
X1660866Y546749D03*
X1664040Y569642D03*
X1668040D03*
X1672040D03*
X1662120Y604782D03*
X1657220Y620662D03*
X1667405Y1394418D03*
X1659260Y1394693D03*
X1658390Y1420218D03*
Y1415018D03*
Y1412418D03*
Y1417618D03*
X1663590Y1420218D03*
X1660990D03*
Y1415018D03*
Y1417618D03*
Y1412418D03*
X1663590Y1415018D03*
Y1417618D03*
Y1412418D03*
X1668646Y1417907D03*
Y1421014D03*
X1671246Y1417907D03*
Y1421014D03*
X1670659Y1427753D03*
X1673129D03*
X1670659Y1433353D03*
X1673129D03*
X1657438Y1438156D03*
X1660428Y1447566D03*
X1667577Y1447545D03*
X1666123Y1497362D03*
X1665940Y1512862D03*
X1666110Y1504662D03*
X1666123Y1524862D03*
Y1537862D03*
Y1541862D03*
Y1553557D03*
X1666198Y1565557D03*
Y1585321D03*
X1678155Y16999D03*
Y21991D03*
X1683111Y16999D03*
Y21991D03*
X1676155Y19495D03*
X1685111D03*
X1676006Y23935D03*
X1685223D03*
X1678006Y25931D03*
X1683223D03*
X1677035Y37106D03*
X1684122D03*
X1677035Y48720D03*
X1684122D03*
X1688156Y69297D03*
X1674978D03*
X1677156Y75297D03*
X1686112D03*
X1684112Y77793D03*
Y72801D03*
X1679156Y77793D03*
Y72801D03*
X1676300Y219762D03*
X1681900Y227962D03*
X1682810Y465940D03*
X1676040Y569627D03*
X1688301Y722158D03*
X1683121D03*
X1680401D03*
X1686135Y1394418D03*
X1687860Y1415179D03*
X1689210Y1417679D03*
X1687860Y1412579D03*
X1685190Y1417923D03*
X1676446Y1417907D03*
X1679046D03*
X1682246D03*
X1676446Y1421014D03*
X1685190Y1421030D03*
X1673846Y1417907D03*
Y1421014D03*
X1676646Y1424121D03*
X1685159Y1424153D03*
X1675559Y1427753D03*
Y1433353D03*
X1674046Y1424121D03*
X1675621Y1445150D03*
X1679508Y1503421D03*
Y1522921D03*
Y1543921D03*
Y1563380D03*
Y1583880D03*
X1692328Y16999D03*
Y21991D03*
X1697284Y16999D03*
Y21991D03*
X1690328Y19495D03*
X1699284D03*
X1690179Y23935D03*
X1692179Y25931D03*
X1691208Y37106D03*
X1698295D03*
X1705381D03*
X1698295Y48720D03*
X1691208D03*
X1705381D03*
X1697112Y69297D03*
X1690156Y66801D03*
Y71793D03*
X1695112Y66801D03*
Y71793D03*
X1699156Y75297D03*
X1701156Y77793D03*
Y72801D03*
X1695950Y96437D03*
X1697725Y205120D03*
X1700846Y455894D03*
X1702760Y478207D03*
X1696760D03*
X1702760Y490207D03*
X1696760D03*
Y484207D03*
X1696120Y506937D03*
X1703720Y509362D03*
X1696851Y515607D03*
X1693701D03*
X1702270Y552742D03*
X1698920Y698562D03*
X1695227Y722325D03*
X1699307Y722465D03*
X1698137Y718345D03*
X1701087Y719055D03*
X1695367Y719345D03*
X1691021Y722158D03*
X1698537Y766015D03*
X1690809Y1393970D03*
X1699150Y1393613D03*
X1690460Y1415179D03*
Y1412579D03*
X1691918Y1417676D03*
X1692960Y1415179D03*
Y1412579D03*
X1693404Y1421939D03*
X1699593Y1428384D03*
X1697820Y1423616D03*
X1699545Y1425868D03*
X1699437Y1431295D03*
X1699457Y1439185D03*
Y1447805D03*
X1691988Y1498303D03*
Y1517803D03*
Y1538803D03*
Y1558262D03*
X1714520Y37162D03*
X1710920Y82162D03*
X1708112Y75297D03*
X1706112Y77793D03*
Y72801D03*
X1708000Y99122D03*
X1714180Y154790D03*
X1721400Y374462D03*
X1711477Y465229D03*
Y468379D03*
X1708760Y478031D03*
Y490207D03*
Y484207D03*
X1710500Y538162D03*
X1706720Y703762D03*
X1709107Y728449D03*
X1718149Y1496270D03*
X1717149Y1505895D03*
X1720174D03*
X1717988Y1520951D03*
X1711988D03*
X1717149Y1513945D03*
X1720174D03*
X1714988Y1520951D03*
X1708988D03*
X1717988Y1530445D03*
X1714988D03*
X1708988D03*
X1711988D03*
X1727768Y3010D03*
X1732320Y28162D03*
X1728820D03*
X1725320D03*
X1729520Y61762D03*
X1729620Y57262D03*
X1730820Y76362D03*
X1726918Y101967D03*
X1733378Y134907D03*
X1736508D03*
X1723240Y185200D03*
X1737704Y183139D03*
X1737260Y368132D03*
X1732660Y372692D03*
X1725400Y372062D03*
X1725500Y383662D03*
X1737434Y398990D03*
X1727760Y420415D03*
X1747768Y3010D03*
X1754090Y16302D03*
X1748400Y37262D03*
X1753398Y48720D03*
X1745485Y119539D03*
X1747482Y121367D03*
X1741222Y151527D03*
X1747591Y171733D03*
X1751084Y190928D03*
X1745000Y299862D03*
X1746970Y1451872D03*
X1750970Y1459172D03*
Y1456172D03*
X1767768Y3010D03*
X1769900Y37732D03*
X1760485Y48720D03*
X1759700Y57662D03*
X1764400Y57462D03*
X1758063Y68637D03*
X1758573Y87107D03*
Y83607D03*
X1768168Y80497D03*
X1758568Y79697D03*
X1765068Y80397D03*
X1766278Y93627D03*
X1768483Y166260D03*
X1763731Y283817D03*
X1766725Y282981D03*
X1763731Y279517D03*
X1760398Y279548D03*
X1766765Y279433D03*
X1757439Y279611D03*
X1760398Y283848D03*
X1759509Y292434D03*
X1762549Y286704D03*
X1757439Y283911D03*
X1768045Y295238D03*
X1765053Y295188D03*
X1762285Y295137D03*
X1759629Y295164D03*
X1767309Y290994D03*
X1763045Y289691D03*
X1759529Y289864D03*
X1766655Y286531D03*
X1767455Y302651D03*
X1758563Y310478D03*
X1754963D03*
X1770520Y364148D03*
Y368148D03*
X1767300Y461393D03*
X1765670Y458012D03*
X1767300Y465893D03*
X1764112Y703948D03*
X1761612D03*
X1764112Y695648D03*
X1763570Y693192D03*
X1761612Y695648D03*
X1764072Y720508D03*
X1761572D03*
X1764112Y712248D03*
X1761612D03*
X1760160Y1476032D03*
X1763730Y1483712D03*
Y1480712D03*
X1763830Y1490782D03*
Y1487782D03*
X1785178Y86927D03*
Y89927D03*
X1784238Y150744D03*
X1786690Y234782D03*
Y231782D03*
X1771029Y295164D03*
X1771229Y291064D03*
X1772863Y310478D03*
X1782420Y443987D03*
X1773870Y438222D03*
X1776160Y592792D03*
X1787768Y3010D03*
X1794910Y44573D03*
X1797324Y161465D03*
X1803129Y362293D03*
X1802929Y385293D03*
X1795479Y408056D03*
X1795468Y421334D03*
X1800107Y1256426D03*
X1795484Y1496401D03*
X1792645Y1511423D03*
X1798450Y1524830D03*
X1801450D03*
Y1527830D03*
X1814322Y49388D03*
X1807549Y56415D03*
X1807580Y59397D03*
X1810835Y163986D03*
X1806365Y154032D03*
X1819939Y177243D03*
X1820307Y373829D03*
X1820144Y398052D03*
X1819374Y410432D03*
X1818874Y423932D03*
X1818816Y468872D03*
X1803517Y1495567D03*
X1818410Y1525815D03*
X1812250Y1521830D03*
X1811250Y1524830D03*
Y1527830D03*
X1807850D03*
X1804650D03*
Y1524830D03*
X1807850D03*
X1814370Y1528900D03*
X1814210Y1525815D03*
X1818524Y1528991D03*
X1834322Y49388D03*
X1823508Y158868D03*
X1829026Y367701D03*
X1823426Y1507916D03*
X1831994Y1525977D03*
X1835334Y1520921D03*
X1828510Y1525915D03*
X1821710D03*
X1830466Y1606658D03*
X1838910Y185772D03*
X1843134Y244362D03*
X1836750Y373632D03*
X1838020Y459121D03*
X1854096Y52383D03*
G54D42*
X335349Y985939D03*
X549278Y949619D03*
X1300207Y177799D03*
X1311491Y985939D03*
X1355761Y177798D03*
X1525420Y949619D03*
X1879155Y592848D03*
Y840748D03*
X1889155Y592848D03*
Y840748D03*
X1900275Y964708D03*
X1910275D03*
X1931395Y592868D03*
X1921395D03*
X1952395Y1205248D03*
X1942395D03*
X1963362Y593010D03*
X1973362D03*
X1984482Y1205220D03*
X1994482D03*
X2015452Y593020D03*
X2005452D03*
X2026452Y1205400D03*
X2047419Y593162D03*
X2036452Y1205400D03*
X2057419Y593162D03*
X2078539Y1205372D03*
X2068539D03*
G54D56*
X828780Y1694890D03*
Y1684890D03*
X818780Y1694890D03*
Y1684890D03*
X828780Y1704890D03*
X818780D03*
X828780Y1714890D03*
X818780D03*
X853780Y1694890D03*
Y1684890D03*
Y1704890D03*
Y1714890D03*
X863780Y1694890D03*
Y1684890D03*
Y1704890D03*
Y1714890D03*
X888780Y1684890D03*
Y1694890D03*
Y1704890D03*
Y1714890D03*
X898780Y1684890D03*
Y1694890D03*
Y1704890D03*
Y1714890D03*
X918780Y1704890D03*
X958780Y1694890D03*
Y1684890D03*
Y1704890D03*
Y1714890D03*
X968780Y1694890D03*
Y1684890D03*
Y1704890D03*
Y1714890D03*
X993780Y1684890D03*
Y1694890D03*
X1003780Y1684890D03*
Y1694890D03*
X993780Y1704890D03*
Y1714890D03*
X1003780Y1704890D03*
Y1714890D03*
X1028780Y1684890D03*
Y1694890D03*
X1038780Y1684890D03*
Y1694890D03*
X1028780Y1704890D03*
Y1714890D03*
X1038780Y1704890D03*
Y1714890D03*
G54D16*
X27699Y770144D03*
Y783530D03*
Y776837D03*
Y800263D03*
Y793570D03*
Y820341D03*
Y813648D03*
Y806955D03*
Y830381D03*
Y850459D03*
Y843766D03*
Y837074D03*
Y867192D03*
Y857152D03*
Y880577D03*
Y873885D03*
Y893963D03*
Y887270D03*
Y917389D03*
Y910696D03*
Y904003D03*
Y930774D03*
Y924081D03*
Y947507D03*
Y940814D03*
Y964239D03*
Y954200D03*
Y977625D03*
Y970932D03*
Y991011D03*
Y984318D03*
Y1031168D03*
Y1024475D03*
Y1017782D03*
Y1044554D03*
Y1037861D03*
Y1057940D03*
Y1051247D03*
Y1078018D03*
Y1071326D03*
Y1064633D03*
Y1094751D03*
Y1088058D03*
Y1108137D03*
Y1101444D03*
Y1124869D03*
Y1114829D03*
Y1144948D03*
Y1138255D03*
Y1131562D03*
Y1161680D03*
Y1151641D03*
Y1175066D03*
Y1168373D03*
Y1188452D03*
Y1181759D03*
Y1205184D03*
Y1198491D03*
Y1225263D03*
Y1218570D03*
Y1211877D03*
Y1241995D03*
Y1235302D03*
Y1248688D03*
X43841Y766798D03*
X36399Y770144D03*
X43841Y780184D03*
Y773491D03*
X36399Y783530D03*
Y776837D03*
X43841Y803609D03*
Y796916D03*
Y790223D03*
X36399Y800263D03*
Y793570D03*
X43841Y816995D03*
Y810302D03*
X36399Y820341D03*
Y813648D03*
Y806955D03*
X43841Y833727D03*
Y827034D03*
X36399Y830381D03*
X43841Y847113D03*
Y840420D03*
X36399Y850459D03*
Y843766D03*
Y837074D03*
X43841Y863845D03*
Y853806D03*
X36399Y867192D03*
Y857152D03*
X43841Y883924D03*
Y877231D03*
Y870538D03*
X36399Y880577D03*
Y873885D03*
X43841Y900656D03*
Y890617D03*
X36399Y893963D03*
Y887270D03*
X43841Y914042D03*
Y907349D03*
X36399Y917389D03*
Y910696D03*
Y904003D03*
X43841Y927428D03*
Y920735D03*
X36399Y930774D03*
Y924081D03*
X43841Y944160D03*
Y937467D03*
X36399Y947507D03*
Y940814D03*
X43841Y960892D03*
Y950853D03*
X36399Y964239D03*
Y954200D03*
X43841Y980971D03*
Y974278D03*
Y967585D03*
X36399Y977625D03*
Y970932D03*
X43841Y987664D03*
X36399Y991011D03*
Y984318D03*
X43841Y1027822D03*
Y1017782D03*
X36399Y1031168D03*
Y1024475D03*
Y1017782D03*
X43841Y1047900D03*
Y1041207D03*
Y1034515D03*
X36399Y1044554D03*
Y1037861D03*
X43841Y1061286D03*
Y1054593D03*
X36399Y1057940D03*
Y1051247D03*
X43841Y1074672D03*
Y1067979D03*
X36399Y1078018D03*
Y1071326D03*
Y1064633D03*
X43841Y1091404D03*
Y1084711D03*
X36399Y1094751D03*
Y1088058D03*
X43841Y1111483D03*
Y1104790D03*
Y1098097D03*
X36399Y1108137D03*
Y1101444D03*
X43841Y1128215D03*
Y1121522D03*
X36399Y1124869D03*
Y1114829D03*
X43841Y1141601D03*
Y1134908D03*
X36399Y1144948D03*
Y1138255D03*
Y1131562D03*
X43841Y1158333D03*
Y1148294D03*
X36399Y1161680D03*
Y1151641D03*
X43841Y1171719D03*
Y1165026D03*
X36399Y1175066D03*
Y1168373D03*
X43841Y1185105D03*
Y1178412D03*
X36399Y1188452D03*
Y1181759D03*
X43841Y1208530D03*
Y1201837D03*
Y1195144D03*
X36399Y1205184D03*
Y1198491D03*
X43841Y1221916D03*
Y1215223D03*
X36399Y1225263D03*
Y1218570D03*
Y1211877D03*
X43841Y1238648D03*
Y1231955D03*
X36399Y1241995D03*
Y1235302D03*
X43841Y1245341D03*
X36399Y1248688D03*
X36449Y1257262D03*
X33546Y1273364D03*
X30746D03*
X57399Y770144D03*
X52541Y766798D03*
X57399Y783530D03*
Y776837D03*
X52541Y780184D03*
Y773491D03*
X57399Y800263D03*
Y793570D03*
X52541Y803609D03*
Y796916D03*
Y790223D03*
X57399Y820341D03*
Y813648D03*
Y806955D03*
X52541Y816995D03*
Y810302D03*
X57399Y830381D03*
X52541Y833727D03*
Y827034D03*
X57399Y850459D03*
Y843766D03*
Y837074D03*
X52541Y847113D03*
Y840420D03*
X57399Y867192D03*
Y857152D03*
X52541Y863845D03*
Y853806D03*
X57399Y880577D03*
Y873885D03*
X52541Y883924D03*
Y877231D03*
Y870538D03*
X57399Y893963D03*
Y887270D03*
X52541Y900656D03*
Y890617D03*
X57399Y917389D03*
Y910696D03*
Y904003D03*
X52541Y914042D03*
Y907349D03*
X57399Y930774D03*
Y924081D03*
X52541Y927428D03*
Y920735D03*
X57399Y947507D03*
Y940814D03*
X52541Y944160D03*
Y937467D03*
X57399Y964239D03*
Y954200D03*
X52541Y960892D03*
Y950853D03*
X57399Y977625D03*
Y970932D03*
X52541Y980971D03*
Y974278D03*
Y967585D03*
X57399Y991011D03*
Y984318D03*
X52541Y987664D03*
X57399Y1031168D03*
Y1024475D03*
Y1017782D03*
X52541Y1027822D03*
Y1017782D03*
X57399Y1044554D03*
Y1037861D03*
X52541Y1047900D03*
Y1041207D03*
Y1034515D03*
X57399Y1057940D03*
Y1051247D03*
X52541Y1061286D03*
Y1054593D03*
X57399Y1078018D03*
Y1071326D03*
Y1064633D03*
X52541Y1074672D03*
Y1067979D03*
X57399Y1094751D03*
Y1088058D03*
X52541Y1091404D03*
Y1084711D03*
X57399Y1108137D03*
Y1101444D03*
X52541Y1111483D03*
Y1104790D03*
Y1098097D03*
X57399Y1124869D03*
Y1114829D03*
X52541Y1128215D03*
Y1121522D03*
X57399Y1144948D03*
Y1138255D03*
Y1131562D03*
X52541Y1141601D03*
Y1134908D03*
X57399Y1161680D03*
Y1151641D03*
X52541Y1158333D03*
Y1148294D03*
X57399Y1175066D03*
Y1168373D03*
X52541Y1171719D03*
Y1165026D03*
X57399Y1188452D03*
Y1181759D03*
X52541Y1185105D03*
Y1178412D03*
X57399Y1205184D03*
Y1198491D03*
X52541Y1208530D03*
Y1201837D03*
Y1195144D03*
X57399Y1225263D03*
Y1218570D03*
Y1211877D03*
X52541Y1221916D03*
Y1215223D03*
X57399Y1241995D03*
Y1235302D03*
X52541Y1238648D03*
Y1231955D03*
Y1248688D03*
X57399D03*
X52541Y1245341D03*
X60446Y1273364D03*
X49546D03*
X46746D03*
X73541Y766798D03*
X66099Y770144D03*
X73541Y780184D03*
Y773491D03*
X66099Y783530D03*
Y776837D03*
X73541Y803609D03*
Y796916D03*
Y790223D03*
X66099Y800263D03*
Y793570D03*
X73541Y816995D03*
Y810302D03*
X66099Y820341D03*
Y813648D03*
Y806955D03*
X73541Y833727D03*
Y827034D03*
X66099Y830381D03*
X73541Y847113D03*
Y840420D03*
X66099Y850459D03*
Y843766D03*
Y837074D03*
X73541Y863845D03*
Y853806D03*
X66099Y867192D03*
Y857152D03*
X73541Y883924D03*
Y877231D03*
Y870538D03*
X66099Y880577D03*
Y873885D03*
X73541Y900656D03*
Y890617D03*
X66099Y893963D03*
Y887270D03*
X73541Y914042D03*
Y907349D03*
X66099Y917389D03*
Y910696D03*
Y904003D03*
X73541Y927428D03*
Y920735D03*
X66099Y930774D03*
Y924081D03*
X73541Y944160D03*
Y937467D03*
X66099Y947507D03*
Y940814D03*
X73541Y960892D03*
Y950853D03*
X66099Y964239D03*
Y954200D03*
X73541Y980971D03*
Y974278D03*
Y967585D03*
X66099Y977625D03*
Y970932D03*
X73541Y987664D03*
X66099Y991011D03*
Y984318D03*
X73541Y1027822D03*
Y1017782D03*
X66099Y1031168D03*
Y1024475D03*
Y1017782D03*
X73541Y1047900D03*
Y1041207D03*
Y1034515D03*
X66099Y1044554D03*
Y1037861D03*
X73541Y1061286D03*
Y1054593D03*
X66099Y1057940D03*
Y1051247D03*
X73541Y1074672D03*
Y1067979D03*
X66099Y1078018D03*
Y1071326D03*
Y1064633D03*
X73541Y1091404D03*
Y1084711D03*
X66099Y1094751D03*
Y1088058D03*
X73541Y1111483D03*
Y1104790D03*
Y1098097D03*
X66099Y1108137D03*
Y1101444D03*
X73541Y1128215D03*
Y1121522D03*
X66099Y1124869D03*
Y1114829D03*
X73541Y1141601D03*
Y1134908D03*
X66099Y1144948D03*
Y1138255D03*
Y1131562D03*
X73541Y1158333D03*
Y1148294D03*
X66099Y1161680D03*
Y1151641D03*
X73541Y1171719D03*
Y1165026D03*
X66099Y1175066D03*
Y1168373D03*
X73541Y1185105D03*
Y1178412D03*
X66099Y1188452D03*
Y1181759D03*
X73541Y1208530D03*
Y1201837D03*
Y1195144D03*
X66099Y1205184D03*
Y1198491D03*
X73541Y1221916D03*
Y1215223D03*
X66099Y1225263D03*
Y1218570D03*
Y1211877D03*
X73541Y1238648D03*
Y1231955D03*
X66099Y1241995D03*
Y1235302D03*
X66189Y1257488D03*
X73541Y1245341D03*
X66099Y1248688D03*
X76446Y1273364D03*
X63246D03*
X87099Y770144D03*
X82241Y766798D03*
X87099Y783530D03*
Y776837D03*
X82241Y780184D03*
Y773491D03*
X87099Y800263D03*
Y793570D03*
X82241Y803609D03*
Y796916D03*
Y790223D03*
X87099Y820341D03*
Y813648D03*
Y806955D03*
X82241Y816995D03*
Y810302D03*
X87099Y830381D03*
X82241Y833727D03*
Y827034D03*
X87099Y850459D03*
Y843766D03*
Y837074D03*
X82241Y847113D03*
Y840420D03*
X87099Y867192D03*
Y857152D03*
X82241Y863845D03*
Y853806D03*
X87099Y880577D03*
Y873885D03*
X82241Y883924D03*
Y877231D03*
Y870538D03*
X87099Y893963D03*
Y887270D03*
X82241Y900656D03*
Y890617D03*
X87099Y917389D03*
Y910696D03*
Y904003D03*
X82241Y914042D03*
Y907349D03*
X87099Y930774D03*
Y924081D03*
X82241Y927428D03*
Y920735D03*
X87099Y947507D03*
Y940814D03*
X82241Y944160D03*
Y937467D03*
X87099Y964239D03*
Y954200D03*
X82241Y960892D03*
Y950853D03*
X87099Y977625D03*
Y970932D03*
X82241Y980971D03*
Y974278D03*
Y967585D03*
X87099Y991011D03*
Y984318D03*
X82241Y987664D03*
X87099Y1031168D03*
Y1024475D03*
Y1017782D03*
X82241Y1027822D03*
Y1017782D03*
X87099Y1044554D03*
Y1037861D03*
X82241Y1047900D03*
Y1041207D03*
Y1034515D03*
X87099Y1057940D03*
Y1051247D03*
X82241Y1061286D03*
Y1054593D03*
X87099Y1078018D03*
Y1071326D03*
Y1064633D03*
X82241Y1074672D03*
Y1067979D03*
X87099Y1094751D03*
Y1088058D03*
X82241Y1091404D03*
Y1084711D03*
X87099Y1108137D03*
Y1101444D03*
X82241Y1111483D03*
Y1104790D03*
Y1098097D03*
X87099Y1124869D03*
Y1114829D03*
X82241Y1128215D03*
Y1121522D03*
X87099Y1144948D03*
Y1138255D03*
Y1131562D03*
X82241Y1141601D03*
Y1134908D03*
X87099Y1161680D03*
Y1151641D03*
X82241Y1158333D03*
Y1148294D03*
X87099Y1175066D03*
Y1168373D03*
X82241Y1171719D03*
Y1165026D03*
X87099Y1188452D03*
Y1181759D03*
X82241Y1185105D03*
Y1178412D03*
X87099Y1205184D03*
Y1198491D03*
X82241Y1208530D03*
Y1201837D03*
Y1195144D03*
X87099Y1225263D03*
Y1218570D03*
Y1211877D03*
X82241Y1221916D03*
Y1215223D03*
X87099Y1241995D03*
Y1235302D03*
X82241Y1238648D03*
Y1231955D03*
X87099Y1248688D03*
X82241Y1245341D03*
X92946Y1273364D03*
X90146D03*
X79246D03*
X103241Y766798D03*
X95799Y770144D03*
X103241Y780184D03*
Y773491D03*
X95799Y783530D03*
Y776837D03*
X103241Y803609D03*
Y796916D03*
Y790223D03*
X95799Y800263D03*
Y793570D03*
X103241Y816995D03*
Y810302D03*
X95799Y820341D03*
Y813648D03*
Y806955D03*
X103241Y833727D03*
Y827034D03*
X95799Y830381D03*
X103241Y847113D03*
Y840420D03*
X95799Y850459D03*
Y843766D03*
Y837074D03*
X103241Y863845D03*
Y853806D03*
X95799Y867192D03*
Y857152D03*
X103241Y883924D03*
Y877231D03*
Y870538D03*
X95799Y880577D03*
Y873885D03*
X103241Y900656D03*
Y890617D03*
X95799Y893963D03*
Y887270D03*
X103241Y914042D03*
Y907349D03*
X95799Y917389D03*
Y910696D03*
Y904003D03*
X103241Y927428D03*
Y920735D03*
X95799Y930774D03*
Y924081D03*
X103241Y944160D03*
Y937467D03*
X95799Y947507D03*
Y940814D03*
X103241Y960892D03*
Y950853D03*
X95799Y964239D03*
Y954200D03*
X103241Y980971D03*
Y974278D03*
Y967585D03*
X95799Y977625D03*
Y970932D03*
X103241Y987664D03*
X95799Y991011D03*
Y984318D03*
X103241Y1027822D03*
Y1017782D03*
X95799Y1031168D03*
Y1024475D03*
Y1017782D03*
X103241Y1047900D03*
Y1041207D03*
Y1034515D03*
X95799Y1044554D03*
Y1037861D03*
X103241Y1061286D03*
Y1054593D03*
X95799Y1057940D03*
Y1051247D03*
X103241Y1074672D03*
Y1067979D03*
X95799Y1078018D03*
Y1071326D03*
Y1064633D03*
X103241Y1091404D03*
Y1084711D03*
X95799Y1094751D03*
Y1088058D03*
X103241Y1111483D03*
Y1104790D03*
Y1098097D03*
X95799Y1108137D03*
Y1101444D03*
X103241Y1128215D03*
Y1121522D03*
X95799Y1124869D03*
Y1114829D03*
X103241Y1141601D03*
Y1134908D03*
X95799Y1144948D03*
Y1138255D03*
Y1131562D03*
X103241Y1158333D03*
Y1148294D03*
X95799Y1161680D03*
Y1151641D03*
X103241Y1171719D03*
Y1165026D03*
X95799Y1175066D03*
Y1168373D03*
X103241Y1185105D03*
Y1178412D03*
X95799Y1188452D03*
Y1181759D03*
X103241Y1208530D03*
Y1201837D03*
Y1195144D03*
X95799Y1205184D03*
Y1198491D03*
X103241Y1221916D03*
Y1215223D03*
X95799Y1225263D03*
Y1218570D03*
Y1211877D03*
X103241Y1238648D03*
Y1231955D03*
X95799Y1241995D03*
Y1235302D03*
X95849Y1257262D03*
X103241Y1245341D03*
X95799Y1248688D03*
X108946Y1273364D03*
X106146D03*
X125499Y770144D03*
X116799D03*
X111941Y766798D03*
X125499Y783530D03*
X116799D03*
X125499Y776837D03*
X116799D03*
X111941Y780184D03*
Y773491D03*
X125499Y800263D03*
X116799D03*
X125499Y793570D03*
X116799D03*
X111941Y803609D03*
Y796916D03*
Y790223D03*
X125499Y820341D03*
X116799D03*
X125499Y813648D03*
X116799D03*
X125499Y806955D03*
X116799D03*
X111941Y816995D03*
Y810302D03*
X125499Y830381D03*
X116799D03*
X111941Y833727D03*
Y827034D03*
X125499Y850459D03*
X116799D03*
X125499Y843766D03*
X116799D03*
X125499Y837074D03*
X116799D03*
X111941Y847113D03*
Y840420D03*
X125499Y867192D03*
X116799D03*
X125499Y857152D03*
X116799D03*
X111941Y863845D03*
Y853806D03*
X125499Y880577D03*
X116799D03*
X125499Y873885D03*
X116799D03*
X111941Y883924D03*
Y877231D03*
Y870538D03*
X125499Y893963D03*
X116799D03*
X125499Y887270D03*
X116799D03*
X111941Y900656D03*
Y890617D03*
X125499Y917389D03*
X116799D03*
X125499Y910696D03*
X116799D03*
X125499Y904003D03*
X116799D03*
X111941Y914042D03*
Y907349D03*
X125499Y930774D03*
X116799D03*
X125499Y924081D03*
X116799D03*
X111941Y927428D03*
Y920735D03*
X125499Y947507D03*
X116799D03*
X125499Y940814D03*
X116799D03*
X111941Y944160D03*
Y937467D03*
X125499Y964239D03*
X116799D03*
X125499Y954200D03*
X116799D03*
X111941Y960892D03*
Y950853D03*
X125499Y977625D03*
X116799D03*
X125499Y970932D03*
X116799D03*
X111941Y980971D03*
Y974278D03*
Y967585D03*
X125499Y991011D03*
X116799D03*
X125499Y984318D03*
X116799D03*
X111941Y987664D03*
X125499Y1031168D03*
X116799D03*
X125499Y1024475D03*
X116799D03*
X125499Y1017782D03*
X116799D03*
X111941Y1027822D03*
Y1017782D03*
X125499Y1044554D03*
X116799D03*
X125499Y1037861D03*
X116799D03*
X111941Y1047900D03*
Y1041207D03*
Y1034515D03*
X125499Y1057940D03*
X116799D03*
X125499Y1051247D03*
X116799D03*
X111941Y1061286D03*
Y1054593D03*
X125499Y1078018D03*
X116799D03*
X125499Y1071326D03*
X116799D03*
X125499Y1064633D03*
X116799D03*
X111941Y1074672D03*
Y1067979D03*
X125499Y1094751D03*
X116799D03*
X125499Y1088058D03*
X116799D03*
X111941Y1091404D03*
Y1084711D03*
X125499Y1108137D03*
X116799D03*
X125499Y1101444D03*
X116799D03*
X111941Y1111483D03*
Y1104790D03*
Y1098097D03*
X125499Y1124869D03*
X116799D03*
X125499Y1114829D03*
X116799D03*
X111941Y1128215D03*
Y1121522D03*
X125499Y1144948D03*
X116799D03*
X125499Y1138255D03*
X116799D03*
X125499Y1131562D03*
X116799D03*
X111941Y1141601D03*
Y1134908D03*
X125499Y1161680D03*
X116799D03*
X125499Y1151641D03*
X116799D03*
X111941Y1158333D03*
Y1148294D03*
X125499Y1175066D03*
X116799D03*
X125499Y1168373D03*
X116799D03*
X111941Y1171719D03*
Y1165026D03*
X125499Y1188452D03*
X116799D03*
X125499Y1181759D03*
X116799D03*
X111941Y1185105D03*
Y1178412D03*
X125499Y1205184D03*
X116799D03*
X125499Y1198491D03*
X116799D03*
X111941Y1208530D03*
Y1201837D03*
Y1195144D03*
X125499Y1225263D03*
X116799D03*
X125499Y1218570D03*
X116799D03*
X125499Y1211877D03*
X116799D03*
X111941Y1221916D03*
Y1215223D03*
X125499Y1241995D03*
X116799D03*
X125499Y1235302D03*
X116799D03*
X111941Y1238648D03*
Y1231955D03*
X125412Y1257102D03*
X125499Y1248688D03*
X116799D03*
X111941Y1245341D03*
X119846Y1273364D03*
X122646D03*
X141641Y766798D03*
X132941D03*
X141641Y773491D03*
X132941D03*
X141641Y780184D03*
X132941D03*
X141641Y803609D03*
X132941D03*
X141641Y790223D03*
X132941D03*
X141641Y796916D03*
X132941D03*
X141641Y816995D03*
X132941D03*
X141641Y810302D03*
X132941D03*
X141641Y833727D03*
X132941D03*
X141641Y827034D03*
X132941D03*
X141641Y840420D03*
X132941D03*
X141641Y847113D03*
X132941D03*
Y863845D03*
X141641D03*
Y853806D03*
X132941D03*
Y883924D03*
X141641D03*
X132941Y870538D03*
X141641D03*
X132941Y877231D03*
X141641D03*
X132941Y900656D03*
X141641D03*
X132941Y890617D03*
X141641D03*
X132941Y907349D03*
X141641D03*
X132941Y914042D03*
X141641D03*
X132941Y920735D03*
X141641D03*
X132941Y927428D03*
X141641D03*
X132941Y937467D03*
X141641D03*
X132941Y944160D03*
X141641D03*
X132941Y960892D03*
X141641D03*
X132941Y950853D03*
X141641D03*
X132941Y980971D03*
X141641D03*
X132941Y974278D03*
X141641D03*
X132941Y967585D03*
X141641D03*
X132941Y987664D03*
X141641D03*
X132941Y1027822D03*
X141641D03*
X132941Y1017782D03*
X141641D03*
X132941Y1047900D03*
X141641D03*
X132941Y1041207D03*
X141641D03*
X132941Y1034515D03*
X141641D03*
Y1061286D03*
X132941D03*
X141641Y1054593D03*
X132941D03*
X141641Y1074672D03*
X132941D03*
X141641Y1067979D03*
X132941D03*
X141641Y1091404D03*
X132941D03*
X141641Y1084711D03*
X132941D03*
X141641Y1111483D03*
X132941D03*
X141641Y1104790D03*
X132941D03*
X141641Y1098097D03*
X132941D03*
X141641Y1128215D03*
X132941D03*
X141641Y1121522D03*
X132941D03*
X141641Y1141601D03*
X132941D03*
X141641Y1134908D03*
X132941D03*
X141641Y1158333D03*
X132941D03*
X141641Y1148294D03*
X132941D03*
X141641Y1171719D03*
X132941D03*
X141641Y1165026D03*
X132941D03*
X141641Y1185105D03*
X132941D03*
X141641Y1178412D03*
X132941D03*
X141641Y1208530D03*
X132941D03*
X141641Y1201837D03*
X132941D03*
X141641Y1195144D03*
X132941D03*
Y1221916D03*
X141641D03*
X132941Y1215223D03*
X141641D03*
X132941Y1238648D03*
X141641D03*
X132941Y1231955D03*
X141641D03*
X132941Y1245341D03*
X141641D03*
X135846Y1273364D03*
X138646D03*
X146499Y770144D03*
X155199D03*
X146499Y783530D03*
X155199D03*
X146499Y776837D03*
X155199D03*
X146499Y800263D03*
X155199D03*
X146499Y793570D03*
X155199D03*
X146499Y820341D03*
X155199D03*
X146499Y813648D03*
X155199D03*
X146499Y806955D03*
X155199D03*
X146499Y830381D03*
X155199D03*
X146499Y850459D03*
X155199D03*
X146499Y843766D03*
X155199D03*
X146499Y837074D03*
X155199D03*
Y867192D03*
X146499D03*
Y857152D03*
X155199D03*
Y880577D03*
X146499D03*
X155199Y873885D03*
X146499D03*
X155199Y893963D03*
X146499D03*
X155199Y887270D03*
X146499D03*
X155199Y917389D03*
X146499D03*
X155199Y910696D03*
X146499D03*
X155199Y904003D03*
X146499D03*
X155199Y930774D03*
X146499D03*
X155199Y924081D03*
X146499D03*
X155199Y947507D03*
X146499D03*
X155199Y940814D03*
X146499D03*
X155199Y964239D03*
X146499D03*
X155199Y954200D03*
X146499D03*
X155199Y977625D03*
X146499D03*
X155199Y970932D03*
X146499D03*
X155199Y991011D03*
X146499D03*
X155199Y984318D03*
X146499D03*
X155199Y1031168D03*
X146499D03*
X155199Y1024475D03*
X146499D03*
X155199Y1017782D03*
X146499D03*
X155199Y1044554D03*
X146499D03*
X155199Y1037861D03*
X146499D03*
X155199Y1057940D03*
X146499D03*
X155199Y1051247D03*
X146499D03*
X155199Y1078018D03*
X146499D03*
X155199Y1071326D03*
X146499D03*
X155199Y1064633D03*
X146499D03*
X155199Y1094751D03*
X146499D03*
X155199Y1088058D03*
X146499D03*
X155199Y1108137D03*
X146499D03*
X155199Y1101444D03*
X146499D03*
X155199Y1124869D03*
X146499D03*
X155199Y1114829D03*
X146499D03*
X155199Y1144948D03*
X146499D03*
X155199Y1138255D03*
X146499D03*
X155199Y1131562D03*
X146499D03*
X155199Y1161680D03*
X146499D03*
X155199Y1151641D03*
X146499D03*
X155199Y1175066D03*
X146499D03*
X155199Y1168373D03*
X146499D03*
X155199Y1188452D03*
X146499D03*
X155199Y1181759D03*
X146499D03*
X155199Y1205184D03*
X146499D03*
X155199Y1198491D03*
X146499D03*
X155199Y1225263D03*
X146499D03*
X155199Y1218570D03*
X146499D03*
X155199Y1211877D03*
X146499D03*
X155199Y1241995D03*
X146499D03*
X155199Y1235302D03*
X146499D03*
X155135Y1257134D03*
X155199Y1248688D03*
X146499D03*
X149546Y1273364D03*
X152346D03*
X176199Y770144D03*
X162641Y766798D03*
X171341D03*
X176199Y783530D03*
Y776837D03*
X162641Y780184D03*
X171341D03*
Y773491D03*
X162641D03*
X176199Y800263D03*
X162641Y803609D03*
X171341D03*
X176199Y793570D03*
X162641Y796916D03*
X171341D03*
X162641Y790223D03*
X171341D03*
X176199Y820341D03*
X162641Y816995D03*
X171341D03*
X176199Y813648D03*
Y806955D03*
X162641Y810302D03*
X171341D03*
X162641Y833727D03*
X171341D03*
X176199Y830381D03*
X162641Y827034D03*
X171341D03*
X176199Y850459D03*
Y843766D03*
Y837074D03*
X162641Y847113D03*
X171341D03*
X162641Y840420D03*
X171341D03*
X176199Y867192D03*
X171341Y863845D03*
X162641D03*
X176199Y857152D03*
X162641Y853806D03*
X171341D03*
Y883924D03*
X162641D03*
X176199Y880577D03*
Y873885D03*
X171341Y877231D03*
X162641D03*
X171341Y870538D03*
X162641D03*
X171341Y900656D03*
X162641D03*
X176199Y893963D03*
Y887270D03*
X171341Y890617D03*
X162641D03*
X176199Y917389D03*
Y910696D03*
Y904003D03*
X171341Y914042D03*
X162641D03*
X171341Y907349D03*
X162641D03*
X176199Y930774D03*
Y924081D03*
X171341Y927428D03*
X162641D03*
X171341Y920735D03*
X162641D03*
X176199Y947507D03*
Y940814D03*
X171341Y944160D03*
X162641D03*
X171341Y937467D03*
X162641D03*
X176199Y964239D03*
Y954200D03*
X171341Y960892D03*
X162641D03*
X171341Y950853D03*
X162641D03*
X171341Y980971D03*
X162641D03*
X176199Y977625D03*
Y970932D03*
X171341Y974278D03*
X162641D03*
X171341Y967585D03*
X162641D03*
X176199Y991011D03*
Y984318D03*
X171341Y987664D03*
X162641D03*
X176199Y1031168D03*
Y1024475D03*
Y1017782D03*
X171341Y1027822D03*
X162641D03*
X171341Y1017782D03*
X162641D03*
X171341Y1047900D03*
X162641D03*
X176199Y1044554D03*
Y1037861D03*
X171341Y1041207D03*
X162641D03*
X171341Y1034515D03*
X162641D03*
X176199Y1057940D03*
Y1051247D03*
X171341Y1061286D03*
X162641D03*
X171341Y1054593D03*
X162641D03*
X176199Y1078018D03*
Y1071326D03*
Y1064633D03*
X171341Y1074672D03*
X162641D03*
X171341Y1067979D03*
X162641D03*
X176199Y1094751D03*
Y1088058D03*
X171341Y1091404D03*
X162641D03*
X171341Y1084711D03*
X162641D03*
X171341Y1111483D03*
X162641D03*
X176199Y1108137D03*
Y1101444D03*
X171341Y1104790D03*
X162641D03*
X171341Y1098097D03*
X162641D03*
X171341Y1128215D03*
X162641D03*
X176199Y1124869D03*
Y1114829D03*
X171341Y1121522D03*
X162641D03*
X176199Y1144948D03*
Y1138255D03*
Y1131562D03*
X171341Y1141601D03*
X162641D03*
X171341Y1134908D03*
X162641D03*
X176199Y1161680D03*
Y1151641D03*
X171341Y1158333D03*
X162641D03*
X171341Y1148294D03*
X162641D03*
X176199Y1175066D03*
Y1168373D03*
X171341Y1171719D03*
X162641D03*
X171341Y1165026D03*
X162641D03*
X176199Y1188452D03*
Y1181759D03*
X171341Y1185105D03*
X162641D03*
X171341Y1178412D03*
X162641D03*
X176199Y1205184D03*
Y1198491D03*
X171341Y1208530D03*
X162641D03*
X171341Y1201837D03*
X162641D03*
X171341Y1195144D03*
X162641D03*
X176199Y1225263D03*
Y1218570D03*
Y1211877D03*
X162641Y1221916D03*
X171341D03*
Y1215223D03*
X162641D03*
X176199Y1241995D03*
Y1235302D03*
X171341Y1238648D03*
X162641D03*
X171341Y1231955D03*
X162641D03*
X176199Y1248688D03*
X171341Y1245341D03*
X162641D03*
X165546Y1273364D03*
X168346D03*
X192341Y766798D03*
X184899Y770144D03*
X192341Y780184D03*
Y773491D03*
X184899Y783530D03*
Y776837D03*
X192341Y803609D03*
Y796916D03*
Y790223D03*
X184899Y800263D03*
Y793570D03*
X192341Y816995D03*
Y810302D03*
X184899Y820341D03*
Y813648D03*
Y806955D03*
X192341Y833727D03*
X191491Y827034D03*
X184899Y830381D03*
X192341Y847113D03*
Y840420D03*
X184899Y850459D03*
Y843766D03*
Y837074D03*
X191491Y863845D03*
X184899Y867192D03*
X192341Y853806D03*
X184899Y857152D03*
X192341Y883924D03*
Y877231D03*
Y870538D03*
X184899Y880577D03*
Y873885D03*
X192341Y900656D03*
Y890617D03*
X184899Y893963D03*
Y887270D03*
X192341Y914042D03*
Y907349D03*
X184899Y917389D03*
Y910696D03*
Y904003D03*
X191491Y927428D03*
X192341Y920735D03*
X184899Y930774D03*
Y924081D03*
X192341Y937467D03*
Y944160D03*
X184899Y947507D03*
Y940814D03*
X192341Y960892D03*
Y950853D03*
X184899Y964239D03*
Y954200D03*
X192341Y974278D03*
Y980971D03*
Y967585D03*
X184899Y977625D03*
Y970932D03*
X192341Y987664D03*
X184899Y991011D03*
Y984318D03*
X192341Y1027822D03*
Y1017782D03*
X184899Y1031168D03*
Y1024475D03*
Y1017782D03*
X192341Y1047900D03*
Y1041207D03*
Y1034515D03*
X184899Y1044554D03*
Y1037861D03*
X192341Y1054593D03*
Y1061286D03*
X184899Y1057940D03*
Y1051247D03*
X192341Y1074672D03*
Y1067979D03*
X184899Y1078018D03*
Y1071326D03*
Y1064633D03*
X192341Y1091404D03*
X191491Y1084711D03*
X184899Y1094751D03*
Y1088058D03*
X192341Y1111483D03*
Y1104790D03*
Y1098097D03*
X184899Y1108137D03*
Y1101444D03*
X192341Y1128215D03*
Y1121522D03*
X184899Y1124869D03*
Y1114829D03*
X192341Y1141601D03*
Y1134908D03*
X184899Y1144948D03*
Y1138255D03*
Y1131562D03*
X191491Y1158333D03*
X192341Y1148294D03*
X184899Y1161680D03*
Y1151641D03*
X192341Y1171719D03*
Y1165026D03*
X184899Y1175066D03*
Y1168373D03*
X192341Y1185105D03*
Y1178412D03*
X184899Y1188452D03*
Y1181759D03*
X192341Y1208530D03*
Y1201837D03*
Y1195144D03*
X184899Y1205184D03*
Y1198491D03*
X192341Y1221916D03*
Y1215223D03*
X184899Y1225263D03*
Y1218570D03*
Y1211877D03*
X192341Y1238648D03*
X191491Y1231955D03*
X184899Y1241995D03*
Y1235302D03*
X184923Y1258871D03*
X192341Y1245341D03*
X184899Y1248688D03*
X192594Y1271262D03*
X192605Y1268774D03*
X182046Y1273364D03*
X179246D03*
X186697Y1578182D03*
Y1590094D03*
X191997Y1602380D03*
Y1614292D03*
X205899Y770144D03*
X201041Y766798D03*
X205899Y783530D03*
Y776837D03*
X201041Y780184D03*
Y773491D03*
X205899Y800263D03*
Y793570D03*
X201041Y803609D03*
Y796916D03*
Y790223D03*
X205899Y813648D03*
Y806955D03*
X205049Y820341D03*
X201041Y816995D03*
Y810302D03*
X205049Y830381D03*
X201041Y833727D03*
Y827034D03*
X205899Y850459D03*
Y837074D03*
Y843766D03*
X201041Y847113D03*
Y840420D03*
X205049Y867192D03*
X201041Y863845D03*
X205049Y857152D03*
X201041Y853806D03*
X205899Y873885D03*
Y880577D03*
X201041Y883924D03*
Y877231D03*
Y870538D03*
X205899Y893963D03*
Y887270D03*
X201041Y900656D03*
Y890617D03*
X205899Y917389D03*
Y910696D03*
Y904003D03*
X201041Y914042D03*
Y907349D03*
X205049Y930774D03*
Y924081D03*
X201041Y927428D03*
Y920735D03*
X205899Y940814D03*
Y947507D03*
X201041Y937467D03*
Y944160D03*
X205899Y964239D03*
Y954200D03*
X201041Y960892D03*
Y950853D03*
X205899Y970932D03*
Y977625D03*
X201041Y974278D03*
Y980971D03*
Y967585D03*
X205899Y991011D03*
Y984318D03*
X201041Y987664D03*
X205899Y1031168D03*
Y1017782D03*
Y1024475D03*
X201041Y1027822D03*
Y1017782D03*
X205899Y1044554D03*
Y1037861D03*
X201041Y1047900D03*
Y1041207D03*
Y1034515D03*
X205899Y1057940D03*
Y1051247D03*
X201041Y1054593D03*
Y1061286D03*
X205049Y1078018D03*
X205899Y1071326D03*
Y1064633D03*
X201041Y1074672D03*
Y1067979D03*
X205899Y1094751D03*
X205049Y1088058D03*
X201041Y1091404D03*
Y1084711D03*
X205899Y1101444D03*
Y1108137D03*
X201041Y1111483D03*
Y1104790D03*
Y1098097D03*
X205899Y1114829D03*
Y1124869D03*
X201041Y1128215D03*
Y1121522D03*
X205899Y1144948D03*
Y1138255D03*
Y1131562D03*
X201041Y1141601D03*
Y1134908D03*
X205049Y1161680D03*
Y1151641D03*
X201041Y1158333D03*
Y1148294D03*
X205899Y1168373D03*
Y1175066D03*
X201041Y1171719D03*
Y1165026D03*
X205899Y1188452D03*
Y1181759D03*
X201041Y1185105D03*
Y1178412D03*
X205899Y1205184D03*
Y1198491D03*
X201041Y1208530D03*
Y1201837D03*
Y1195144D03*
X205049Y1225263D03*
X205899Y1211877D03*
Y1218570D03*
X201041Y1221916D03*
Y1215223D03*
X205899Y1241995D03*
X205049Y1235302D03*
X201041Y1238648D03*
Y1231955D03*
X205899Y1248688D03*
X201041Y1245341D03*
X206268Y1271348D03*
X206337Y1268720D03*
X194497Y1578182D03*
X206557D03*
X198757D03*
X194497Y1590094D03*
X206557D03*
X198757D03*
X199797Y1614292D03*
Y1602380D03*
X204057Y1614292D03*
Y1602380D03*
X222041Y766798D03*
X214599Y770144D03*
X222041Y780184D03*
Y773491D03*
X214599Y783530D03*
Y776837D03*
X222041Y803609D03*
Y796916D03*
Y790223D03*
X214599Y800263D03*
Y793570D03*
X222041Y810302D03*
X221191Y816995D03*
X214599Y813648D03*
Y806955D03*
X215449Y820341D03*
X222041Y833727D03*
X221191Y827034D03*
X215449Y830381D03*
X222041Y847113D03*
Y840420D03*
X214599Y850459D03*
Y837074D03*
Y843766D03*
X221191Y863845D03*
X215449Y867192D03*
X222041Y853806D03*
X215449Y857152D03*
X222041Y877231D03*
X221191Y870538D03*
X222041Y883924D03*
X214599Y873885D03*
Y880577D03*
X222041Y900656D03*
Y890617D03*
X214599Y893963D03*
Y887270D03*
X222041Y914042D03*
Y907349D03*
X214599Y917389D03*
Y910696D03*
Y904003D03*
X221241Y927428D03*
X222041Y920735D03*
X215449Y930774D03*
Y924081D03*
X222041Y944160D03*
X221191Y937467D03*
X214599Y940814D03*
Y947507D03*
X222041Y960892D03*
Y950853D03*
X214599Y964239D03*
Y954200D03*
X222041Y980971D03*
Y974278D03*
Y967585D03*
X214599Y970932D03*
Y977625D03*
Y991011D03*
Y984318D03*
X222041Y987664D03*
Y1027822D03*
Y1017782D03*
X214599Y1031168D03*
Y1017782D03*
Y1024475D03*
X222041Y1047900D03*
Y1041207D03*
Y1034515D03*
X214599Y1044554D03*
Y1037861D03*
X222041Y1054593D03*
Y1061286D03*
X214599Y1057940D03*
Y1051247D03*
X222041Y1067979D03*
X221191Y1074672D03*
X215449Y1078018D03*
X214599Y1071326D03*
Y1064633D03*
X222041Y1091404D03*
X221191Y1084711D03*
X214599Y1094751D03*
X215449Y1088058D03*
X222041Y1111483D03*
Y1098097D03*
Y1104790D03*
X214599Y1101444D03*
Y1108137D03*
X222041Y1128215D03*
Y1121522D03*
X214599Y1114829D03*
Y1124869D03*
X222041Y1141601D03*
X221191Y1134908D03*
X214599Y1144948D03*
Y1138255D03*
Y1131562D03*
X222041Y1158333D03*
X221191Y1148294D03*
X215449Y1161680D03*
Y1151641D03*
X222041Y1165026D03*
Y1171719D03*
X214599Y1168373D03*
Y1175066D03*
X222041Y1185105D03*
Y1178412D03*
X214599Y1188452D03*
Y1181759D03*
X222041Y1208530D03*
Y1201837D03*
Y1195144D03*
X214599Y1205184D03*
Y1198491D03*
X222041Y1221916D03*
Y1215223D03*
X215449Y1225263D03*
X214599Y1211877D03*
Y1218570D03*
X221191Y1231955D03*
Y1238648D03*
X214599Y1241995D03*
X215449Y1235302D03*
X222041Y1245341D03*
X214824Y1258711D03*
X214599Y1248688D03*
X224987Y1273535D03*
X218617Y1578182D03*
X210817D03*
X222877D03*
X218617Y1590094D03*
X210817D03*
X222877D03*
X211857Y1614292D03*
Y1602380D03*
X223917Y1614292D03*
X216117D03*
X223917Y1602380D03*
X216117D03*
X235599Y770144D03*
X230741Y766798D03*
X235599Y783530D03*
Y776837D03*
X230741Y780184D03*
Y773491D03*
X235599Y800263D03*
Y793570D03*
X230741Y803609D03*
Y796916D03*
Y790223D03*
X234749Y820341D03*
Y813648D03*
X235599Y806955D03*
X230741Y810302D03*
X231006Y817554D03*
X235599Y830381D03*
X230741Y833727D03*
X231591Y827034D03*
X235599Y850459D03*
Y837074D03*
Y843766D03*
X230741Y847113D03*
Y840420D03*
X234749Y867492D03*
X231591Y863845D03*
X234749Y857152D03*
X230741Y853806D03*
X235599Y874185D03*
Y880577D03*
X230741Y877231D03*
X231059Y871084D03*
X230741Y883924D03*
X235599Y893963D03*
Y887270D03*
X230741Y900656D03*
Y890617D03*
X235599Y917389D03*
Y910696D03*
Y904003D03*
X230741Y914042D03*
Y907349D03*
X235599Y930774D03*
Y924081D03*
X231541Y927428D03*
X230741Y920735D03*
X235599Y947507D03*
X234859Y940814D03*
X230741Y944660D03*
X231591Y937467D03*
X235599Y964239D03*
Y954200D03*
X230741Y960892D03*
Y950853D03*
X235599Y977625D03*
Y970932D03*
X230741Y980971D03*
Y974278D03*
Y967585D03*
X235599Y991011D03*
X230741Y987664D03*
X235599Y984318D03*
Y1031168D03*
X230741Y1027822D03*
Y1017782D03*
X235599D03*
Y1024475D03*
Y1044554D03*
Y1037861D03*
X230741Y1047900D03*
Y1041207D03*
Y1034515D03*
X235599Y1051247D03*
Y1057940D03*
X230741Y1054593D03*
Y1061286D03*
X234749Y1078018D03*
X235599Y1071326D03*
Y1064633D03*
X230741Y1067979D03*
X231591Y1074672D03*
X235599Y1094751D03*
X234749Y1088058D03*
X230741Y1091404D03*
Y1084711D03*
X235599Y1108137D03*
Y1101444D03*
X230741Y1111483D03*
Y1098097D03*
Y1104790D03*
X234749Y1124869D03*
X235599Y1114829D03*
X230741Y1128215D03*
Y1121522D03*
X235599Y1144948D03*
Y1138255D03*
X234749Y1131562D03*
X230741Y1141601D03*
X231591Y1134908D03*
X235599Y1151641D03*
Y1161680D03*
X230741Y1158333D03*
X231591Y1148294D03*
X235599Y1175066D03*
Y1168373D03*
X230741Y1165026D03*
Y1171719D03*
X235599Y1188452D03*
Y1181759D03*
X230741Y1185105D03*
Y1178412D03*
X235599Y1205184D03*
Y1198491D03*
X230741Y1208530D03*
Y1201837D03*
Y1195144D03*
X234749Y1225263D03*
X235599Y1218570D03*
Y1211877D03*
X230741Y1221916D03*
Y1215223D03*
X235599Y1241995D03*
X235186Y1234977D03*
X231591Y1231955D03*
Y1238648D03*
X235599Y1248688D03*
X230741Y1245341D03*
X227746Y1273364D03*
X240966Y1273143D03*
X238971Y1274353D03*
X230677Y1578182D03*
X234937D03*
X230677Y1590094D03*
X234937D03*
X228177Y1614292D03*
X235977D03*
X228177Y1602380D03*
X235977D03*
X240237D03*
Y1614292D03*
X233268Y1679920D03*
Y1675383D03*
X241142Y1679320D03*
X233268Y1698627D03*
Y1694093D03*
Y1689556D03*
Y1684454D03*
X241142Y1683857D03*
Y1688391D03*
Y1693493D03*
Y1698030D03*
X233268Y1712800D03*
Y1708266D03*
Y1703729D03*
X241142Y1702564D03*
Y1707666D03*
Y1712203D03*
X233268Y1717903D03*
Y1722440D03*
Y1726974D03*
X241142Y1716737D03*
Y1730911D03*
Y1726377D03*
Y1721840D03*
X251741Y766798D03*
X244299Y770144D03*
X251741Y780184D03*
Y773491D03*
X244299Y783530D03*
Y776837D03*
X251741Y803609D03*
Y796916D03*
Y790223D03*
X244299Y800263D03*
Y793570D03*
X250891Y816995D03*
X251741Y810302D03*
X245149Y820341D03*
Y813648D03*
X244299Y806955D03*
X251741Y833727D03*
X250891Y827034D03*
X244299Y830381D03*
X251741Y847113D03*
Y840420D03*
X244299Y850459D03*
Y837074D03*
Y843766D03*
X250891Y863845D03*
Y853806D03*
X245149Y867192D03*
Y857152D03*
X251741Y870538D03*
Y883924D03*
Y877231D03*
X244299Y873885D03*
Y880577D03*
X250891Y900656D03*
X251741Y890617D03*
X244299Y893963D03*
Y887270D03*
X251741Y914042D03*
Y907349D03*
X244299Y917389D03*
Y910696D03*
Y904003D03*
X250891Y927428D03*
X251741Y920735D03*
X245149Y930774D03*
X244299Y924081D03*
X251741Y944160D03*
X250891Y937467D03*
X244299Y947507D03*
X245149Y940814D03*
X251741Y960892D03*
Y950853D03*
X244299Y964239D03*
Y954200D03*
X251741Y980971D03*
Y974278D03*
Y967585D03*
X244299Y977625D03*
Y970932D03*
X251741Y987664D03*
X244299Y991011D03*
Y984318D03*
Y1031168D03*
X251741Y1027822D03*
Y1017782D03*
X244299D03*
Y1024475D03*
X251741Y1047900D03*
Y1041207D03*
Y1034515D03*
X244299Y1044554D03*
Y1037861D03*
X251741Y1061286D03*
Y1054593D03*
X244299Y1051247D03*
Y1057940D03*
X250891Y1074672D03*
Y1067979D03*
X245149Y1078018D03*
X244299Y1071326D03*
Y1064633D03*
X251741Y1091404D03*
Y1084711D03*
X244299Y1094751D03*
X245149Y1088058D03*
X251741Y1104790D03*
X250891Y1111483D03*
X251741Y1098097D03*
X244299Y1108137D03*
Y1101444D03*
X251741Y1128215D03*
X250891Y1121522D03*
X245149Y1124869D03*
X244299Y1114829D03*
X251741Y1134908D03*
Y1141601D03*
X244299Y1144948D03*
Y1138255D03*
X245149Y1131562D03*
X251741Y1158333D03*
Y1148294D03*
X244299Y1151641D03*
Y1161680D03*
X251741Y1171719D03*
Y1165026D03*
X244299Y1175066D03*
Y1168373D03*
X251741Y1185105D03*
Y1178412D03*
X244299Y1188452D03*
Y1181759D03*
X251741Y1208530D03*
Y1201837D03*
X250891Y1195144D03*
X244299Y1205184D03*
Y1198491D03*
X250891Y1221916D03*
X251741Y1215223D03*
X245149Y1225263D03*
X244299Y1218570D03*
Y1211877D03*
X250891Y1231955D03*
X244299Y1241995D03*
X245149Y1235302D03*
X251741Y1238648D03*
X244299Y1248688D03*
X251741Y1245341D03*
X244789Y1260093D03*
X254897Y1274040D03*
X257197Y1273640D03*
X242737Y1578182D03*
X246997D03*
X254797D03*
X242737Y1590094D03*
X246997D03*
X254797D03*
X248037Y1602380D03*
Y1614292D03*
X252297Y1602380D03*
Y1614292D03*
X249016Y1675383D03*
Y1679920D03*
X256890Y1679320D03*
X249016Y1684454D03*
Y1689556D03*
Y1694093D03*
Y1698627D03*
X256890Y1683857D03*
Y1688391D03*
Y1693493D03*
Y1698030D03*
X249016Y1703729D03*
Y1708266D03*
Y1712800D03*
X256890Y1702564D03*
Y1707666D03*
Y1712203D03*
X249016Y1726974D03*
Y1722440D03*
Y1717903D03*
X256890Y1716737D03*
Y1730911D03*
Y1726377D03*
Y1721840D03*
X260441Y766798D03*
Y780184D03*
Y773491D03*
Y803609D03*
Y796916D03*
Y790223D03*
X261291Y816995D03*
X260441Y810302D03*
Y833727D03*
X261291Y827034D03*
X260441Y847113D03*
Y840420D03*
X261291Y863845D03*
Y853806D03*
X260441Y870538D03*
Y883924D03*
Y877231D03*
Y900656D03*
Y890617D03*
Y914042D03*
Y907349D03*
X261291Y927428D03*
X260441Y920735D03*
Y944160D03*
X261291Y937467D03*
X260441Y960892D03*
Y950853D03*
Y980971D03*
Y974278D03*
Y967585D03*
Y987664D03*
Y1027822D03*
Y1017782D03*
Y1047900D03*
Y1041207D03*
Y1034515D03*
Y1061286D03*
Y1054593D03*
X261291Y1074672D03*
Y1067979D03*
X260441Y1091404D03*
Y1084711D03*
Y1104790D03*
X261291Y1111483D03*
X260441Y1098097D03*
Y1128215D03*
X261291Y1121522D03*
X260441Y1134908D03*
Y1141601D03*
Y1158333D03*
Y1148294D03*
Y1171719D03*
Y1165026D03*
Y1185105D03*
Y1178412D03*
Y1208530D03*
Y1201837D03*
Y1195144D03*
X261291Y1221916D03*
X260441Y1215223D03*
X261291Y1231955D03*
X260441Y1238648D03*
Y1245341D03*
X266857Y1578182D03*
X259057D03*
X271117D03*
X266857Y1590094D03*
X259057D03*
X271117D03*
X260097Y1602380D03*
Y1614292D03*
X272157Y1602380D03*
Y1614292D03*
X264357D03*
Y1602380D03*
X264764Y1675383D03*
Y1679920D03*
X272638Y1679320D03*
X264764Y1684454D03*
Y1689556D03*
Y1694093D03*
Y1698627D03*
X272638Y1683857D03*
Y1688391D03*
Y1693493D03*
Y1698030D03*
X264764Y1703729D03*
Y1708266D03*
Y1712800D03*
X272638Y1702564D03*
Y1707666D03*
Y1712203D03*
X264764Y1726974D03*
Y1722440D03*
Y1717903D03*
X272638Y1716737D03*
Y1730911D03*
Y1726377D03*
Y1721840D03*
X278917Y1578182D03*
X283177D03*
X278917Y1590094D03*
X283177D03*
X284217Y1602380D03*
Y1614292D03*
X276417D03*
Y1602380D03*
X288477Y1614292D03*
Y1602380D03*
X280512Y1675383D03*
Y1679920D03*
Y1684454D03*
Y1689556D03*
Y1694093D03*
Y1698627D03*
Y1703729D03*
Y1708266D03*
Y1712800D03*
Y1726974D03*
Y1722440D03*
Y1717903D03*
X290977Y1578182D03*
X295237D03*
X303037D03*
X290977Y1590094D03*
X295237D03*
X303037D03*
X296277Y1614292D03*
Y1602380D03*
X300537D03*
Y1614292D03*
X300197Y1679920D03*
Y1675383D03*
Y1698627D03*
Y1694093D03*
Y1689556D03*
Y1684454D03*
Y1712800D03*
Y1708266D03*
Y1703729D03*
Y1717903D03*
Y1722440D03*
Y1726974D03*
X315097Y1578182D03*
X307297D03*
X319357D03*
X315097Y1590094D03*
X307297D03*
X319357D03*
X308337Y1602380D03*
Y1614292D03*
X320397D03*
X312597D03*
X320397Y1602380D03*
X312597D03*
X308071Y1679320D03*
X315945Y1679920D03*
Y1675383D03*
X308071Y1683857D03*
Y1698030D03*
Y1693493D03*
Y1688391D03*
X315945Y1698627D03*
Y1694093D03*
Y1689556D03*
Y1684454D03*
X308071Y1702564D03*
Y1712203D03*
Y1707666D03*
X315945Y1712800D03*
Y1708266D03*
Y1703729D03*
X308071Y1716737D03*
Y1721840D03*
Y1726377D03*
Y1730911D03*
X315945Y1717903D03*
Y1722440D03*
Y1726974D03*
X327157Y1578182D03*
X331417D03*
X327157Y1590094D03*
X331417D03*
X324657Y1602380D03*
X332457D03*
X324657Y1614292D03*
X332457D03*
X336717Y1602380D03*
Y1614292D03*
X323819Y1679320D03*
X331693Y1679920D03*
Y1675383D03*
X323819Y1683857D03*
Y1698030D03*
Y1693493D03*
Y1688391D03*
X331693Y1698627D03*
Y1694093D03*
Y1689556D03*
Y1684454D03*
X323819Y1702564D03*
Y1712203D03*
Y1707666D03*
X331693Y1712800D03*
Y1708266D03*
Y1703729D03*
X323819Y1716737D03*
Y1721840D03*
Y1726377D03*
Y1730911D03*
X331693Y1717903D03*
Y1722440D03*
Y1726974D03*
X352579Y854584D03*
X347029Y870606D03*
Y889832D03*
X343707Y1091513D03*
X339217Y1578182D03*
X343477D03*
X351277D03*
X339217Y1590094D03*
X343477D03*
X351277D03*
X344517Y1602380D03*
Y1614292D03*
X348777Y1602380D03*
Y1614292D03*
X339567Y1679320D03*
X347441Y1679920D03*
Y1675383D03*
X355315Y1679320D03*
X339567Y1683857D03*
Y1698030D03*
Y1693493D03*
Y1688391D03*
X347441Y1698627D03*
Y1694093D03*
Y1689556D03*
Y1684454D03*
X355315Y1683857D03*
Y1698030D03*
Y1693493D03*
Y1688391D03*
X339567Y1702564D03*
Y1712203D03*
Y1707666D03*
X347441Y1712800D03*
Y1708266D03*
Y1703729D03*
X355315Y1702564D03*
Y1712203D03*
Y1707666D03*
X339567Y1716737D03*
Y1721840D03*
Y1726377D03*
Y1730911D03*
X347441Y1717903D03*
Y1722440D03*
Y1726974D03*
X355315Y1716737D03*
Y1721840D03*
Y1726377D03*
Y1730911D03*
X359979Y841467D03*
X367379D03*
X365529Y851380D03*
X369229D03*
X359979Y880219D03*
Y899445D03*
X371078D03*
X359979Y918670D03*
X365529Y941100D03*
X359979Y937896D03*
X371078D03*
X369662Y1006093D03*
X365962Y1076587D03*
X363337Y1578088D03*
X355537Y1578182D03*
X367597D03*
X363337Y1590094D03*
X355537D03*
X367597D03*
X356577Y1602380D03*
Y1614292D03*
X368637D03*
X360837D03*
X368637Y1602286D03*
X360837Y1602380D03*
X382179Y841467D03*
X374779D03*
X380329Y851380D03*
X376629D03*
X372929D03*
X384029D03*
X387729D03*
X378478Y931488D03*
X378911Y1060565D03*
X375397Y1578182D03*
Y1590094D03*
X372897Y1602380D03*
X380697D03*
X372897Y1614292D03*
X380697D03*
X389579Y841467D03*
X396978Y899445D03*
Y937896D03*
X415185Y985580D03*
X417575D03*
X415185Y1014540D03*
X417575D03*
X435829Y851380D03*
Y864197D03*
Y877014D03*
Y889832D03*
Y902649D03*
X428429Y921875D03*
X430279Y937897D03*
X433979D03*
X433980Y944305D03*
Y957123D03*
Y950714D03*
Y963531D03*
Y976348D03*
Y969940D03*
Y982757D03*
X434411Y1009298D03*
X434412Y1002889D03*
X434411Y1028524D03*
Y1022115D03*
X434412Y1015706D03*
Y1034932D03*
X434411Y1092608D03*
X450629Y851380D03*
Y877014D03*
X437678Y912262D03*
X441379Y937897D03*
X445079D03*
X437679D03*
X446929Y941101D03*
X446930Y947510D03*
Y960327D03*
Y953918D03*
Y966736D03*
Y979553D03*
Y973144D03*
X447362Y1006094D03*
Y999685D03*
Y1012502D03*
Y1025319D03*
Y1018911D03*
Y1031728D03*
X456178Y912262D03*
X461729Y921875D03*
X462261Y942152D03*
X464561D03*
X466861D03*
X454423Y949139D03*
X454393Y963829D03*
Y966129D03*
X463874Y956540D03*
X466272D03*
X454423Y951439D03*
X466272Y971100D03*
X463874Y971140D03*
X454263Y981209D03*
Y978909D03*
X454463Y995299D03*
Y992999D03*
X466272Y985580D03*
X463874D03*
X466272Y1014540D03*
X463874D03*
X454443Y1009409D03*
Y1007109D03*
X466272Y1000060D03*
X463874D03*
X468895Y1014550D03*
X465862Y1057361D03*
X458462Y1063770D03*
X465862D03*
X456611Y1073383D03*
X454762Y1070178D03*
X467711Y1073383D03*
Y1066974D03*
X474678Y899445D03*
Y912262D03*
X480229Y921875D03*
X471204Y1014540D03*
X475111Y1060565D03*
X484361Y1057361D03*
X475111Y1066974D03*
X473262Y1070178D03*
X478811Y1073383D03*
X484361Y1076587D03*
X482512Y1066974D03*
X478812Y1079791D03*
X475111D03*
X482911Y1578182D03*
X478651D03*
X470851D03*
X482911Y1590094D03*
X478651D03*
X470851D03*
X483951Y1614292D03*
Y1602380D03*
X476151D03*
Y1614292D03*
X489478Y912262D03*
X495462Y1057361D03*
X499162Y1063770D03*
X495462Y1076587D03*
X493612Y1073383D03*
X486211D03*
X497311Y1066974D03*
X495462Y1108630D03*
X493611Y1111834D03*
X494971Y1578182D03*
X490711D03*
X494971Y1590094D03*
X490711D03*
X500271Y1614292D03*
Y1602380D03*
X488211Y1614292D03*
Y1602380D03*
X496011D03*
Y1614292D03*
X497441Y1675383D03*
Y1679920D03*
Y1684454D03*
Y1689556D03*
Y1694093D03*
Y1698627D03*
Y1703729D03*
Y1708266D03*
Y1712800D03*
Y1726974D03*
Y1722440D03*
Y1717903D03*
X507978Y937896D03*
X509829Y947509D03*
X510262Y1057361D03*
X506562Y1063770D03*
X510262Y1076587D03*
X512111Y1073383D03*
X508411Y1066974D03*
X515811D03*
X508411Y1079791D03*
X515811Y1086200D03*
X507031Y1578182D03*
X514831D03*
X502771D03*
X507031Y1590094D03*
X514831D03*
X502771D03*
X512331Y1614292D03*
Y1602380D03*
X508071Y1614292D03*
Y1602380D03*
X513189Y1675383D03*
Y1679920D03*
X505315Y1679320D03*
X513189Y1684454D03*
Y1689556D03*
Y1694093D03*
Y1698627D03*
X505315Y1688391D03*
Y1693493D03*
Y1698030D03*
Y1683857D03*
X513189Y1703729D03*
Y1708266D03*
Y1712800D03*
X505315Y1707666D03*
Y1712203D03*
Y1702564D03*
X513189Y1726974D03*
Y1722440D03*
Y1717903D03*
X505315Y1730911D03*
Y1726377D03*
Y1721840D03*
Y1716737D03*
X521362Y1057361D03*
X525061Y1063770D03*
X532462D03*
X521362Y1076587D03*
X519512Y1073383D03*
X523211Y1066974D03*
X534311D03*
X531151Y1578182D03*
X519091D03*
X526891D03*
X531151Y1590094D03*
X519091D03*
X526891D03*
X532191Y1614292D03*
Y1602380D03*
X524391Y1614292D03*
Y1602380D03*
X520131D03*
Y1614292D03*
X528937Y1675383D03*
Y1679920D03*
X521063Y1679320D03*
X528937Y1684454D03*
Y1689556D03*
Y1694093D03*
Y1698627D03*
X521063Y1688391D03*
Y1693493D03*
Y1698030D03*
Y1683857D03*
X528937Y1703729D03*
Y1708266D03*
Y1712800D03*
X521063Y1707666D03*
Y1712203D03*
Y1702564D03*
X528937Y1726974D03*
Y1722440D03*
Y1717903D03*
X521063Y1730911D03*
Y1726377D03*
Y1721840D03*
Y1716737D03*
X543129Y928283D03*
X539429D03*
X537578Y925079D03*
X535729Y928283D03*
X548678Y925079D03*
X537578Y944304D03*
X548678D03*
X536161Y1057361D03*
X549422Y1064850D03*
X541711Y1073383D03*
X545411Y1066974D03*
X536161Y1076587D03*
X536162Y1070178D03*
X538011Y1073383D03*
X547262Y1070178D03*
X543211Y1578182D03*
X538951D03*
X543211Y1590094D03*
X538951D03*
X548511Y1614292D03*
Y1602380D03*
X536451D03*
Y1614292D03*
X544251Y1602380D03*
Y1614292D03*
X544685Y1675383D03*
Y1679920D03*
X536811Y1679320D03*
X544685Y1684454D03*
Y1689556D03*
Y1694093D03*
Y1698627D03*
X536811Y1688391D03*
Y1693493D03*
Y1698030D03*
Y1683857D03*
X544685Y1703729D03*
Y1708266D03*
Y1712800D03*
X536811Y1707666D03*
Y1712203D03*
Y1702564D03*
X544685Y1726974D03*
Y1722440D03*
Y1717903D03*
X536811Y1730911D03*
Y1726377D03*
Y1721840D03*
Y1716737D03*
X555271Y1578182D03*
X563071D03*
X551011D03*
X555271Y1590094D03*
X563071D03*
X551011D03*
X560571Y1602380D03*
X556311Y1614292D03*
Y1602380D03*
X552559Y1679320D03*
X564370Y1675383D03*
Y1679920D03*
X552559Y1688391D03*
Y1693493D03*
Y1698030D03*
Y1683857D03*
X564370Y1684454D03*
Y1689556D03*
Y1694093D03*
Y1698627D03*
X552559Y1707666D03*
Y1712203D03*
Y1702564D03*
X564370Y1703729D03*
Y1708266D03*
Y1712800D03*
X552559Y1730911D03*
Y1726377D03*
Y1721840D03*
Y1716737D03*
X564370Y1726974D03*
Y1722440D03*
Y1717903D03*
X579391Y1578182D03*
X567331D03*
X575131D03*
X579391Y1590094D03*
X567331D03*
X575131D03*
X580431Y1614292D03*
X572631D03*
Y1602380D03*
X568371D03*
Y1614292D03*
X580118Y1675383D03*
Y1679920D03*
X572244Y1679320D03*
X580118Y1684454D03*
Y1689556D03*
Y1694093D03*
Y1698627D03*
X572244Y1688391D03*
Y1693493D03*
Y1698030D03*
Y1683857D03*
X580118Y1703729D03*
Y1708266D03*
Y1712800D03*
X572244Y1707666D03*
Y1712203D03*
Y1702564D03*
X580118Y1726974D03*
Y1722440D03*
Y1717903D03*
X572244Y1730911D03*
Y1726377D03*
Y1721840D03*
Y1716737D03*
X599251Y1578182D03*
X591451D03*
X587191D03*
X599251Y1590094D03*
X591451D03*
X587191D03*
X596751Y1614292D03*
Y1602380D03*
X584691D03*
Y1614292D03*
X592491Y1602380D03*
Y1614292D03*
X595866Y1675383D03*
Y1679920D03*
X587992Y1679320D03*
X595866Y1684454D03*
Y1689556D03*
Y1694093D03*
Y1698627D03*
X587992Y1688391D03*
Y1693493D03*
Y1698030D03*
Y1683857D03*
X595866Y1703729D03*
Y1708266D03*
Y1712800D03*
X587992Y1707666D03*
Y1712203D03*
Y1702564D03*
X595866Y1726974D03*
Y1722440D03*
Y1717903D03*
X587992Y1730911D03*
Y1726377D03*
Y1721840D03*
Y1716737D03*
X615571Y1578182D03*
X603511D03*
X611311D03*
X615571Y1590094D03*
X603511D03*
X611311D03*
X608811Y1602380D03*
Y1614292D03*
X604551Y1602380D03*
Y1614292D03*
X611614Y1675383D03*
Y1679920D03*
X603740Y1679320D03*
X611614Y1684454D03*
Y1689556D03*
Y1694093D03*
Y1698627D03*
X603740Y1688391D03*
Y1693493D03*
Y1698030D03*
Y1683857D03*
X611614Y1703729D03*
Y1708266D03*
Y1712800D03*
X603740Y1707666D03*
Y1712203D03*
Y1702564D03*
X611614Y1726974D03*
Y1722440D03*
Y1717903D03*
X603740Y1730911D03*
Y1726377D03*
Y1721840D03*
Y1716737D03*
X629599Y770144D03*
X620899D03*
X629599Y783530D03*
X620899D03*
X629599Y776837D03*
X620899D03*
X620846Y800263D03*
X629599D03*
Y793570D03*
X620899D03*
Y820341D03*
X629599D03*
X620076Y813648D03*
X630593D03*
X619632Y806955D03*
X630792D03*
X620899Y830381D03*
X629599D03*
X620005Y850459D03*
X630754D03*
X620899Y843766D03*
X629599D03*
Y837074D03*
X620899D03*
Y867192D03*
X629599D03*
X620058Y857152D03*
X630481D03*
X620899Y880577D03*
X629599D03*
X620899Y873885D03*
X629599D03*
X630756Y893963D03*
X620899D03*
X629599Y887270D03*
X620899D03*
Y910696D03*
X629599D03*
Y917389D03*
X620899D03*
X629599Y904003D03*
X620899D03*
X630399Y930697D03*
X619905Y930774D03*
X620899Y924081D03*
X629599D03*
Y947507D03*
X620899D03*
X619964Y940814D03*
X630777D03*
X629599Y964239D03*
X620899D03*
X629599Y954200D03*
X620899D03*
Y977625D03*
X629599D03*
Y970932D03*
X620899D03*
Y991011D03*
X629599D03*
Y984318D03*
X620899D03*
Y1031168D03*
X629599D03*
X620899Y1017782D03*
X629599D03*
X620899Y1024475D03*
X629599D03*
X620899Y1044554D03*
X629599D03*
X620899Y1037861D03*
X629599D03*
X620899Y1057940D03*
X629599D03*
Y1051247D03*
X620899D03*
Y1078018D03*
X629599D03*
X630399Y1071326D03*
X619999D03*
X620899Y1064633D03*
X629599D03*
X620899Y1088058D03*
X629599D03*
Y1094751D03*
X620899D03*
Y1108137D03*
X629599D03*
Y1101444D03*
X620899D03*
X630363Y1124674D03*
X620369Y1124969D03*
X630399Y1114829D03*
X620099D03*
X620899Y1131562D03*
X629599D03*
Y1144948D03*
X620899D03*
X629599Y1138255D03*
X620899D03*
X620511Y1161680D03*
X629833Y1161581D03*
X629599Y1151641D03*
X620899D03*
X629599Y1175066D03*
X620899D03*
X629599Y1168373D03*
X620899D03*
X630623Y1188452D03*
X620899D03*
X629599Y1181759D03*
X620899D03*
X629599Y1205184D03*
X620899D03*
Y1198491D03*
X629599D03*
X620899Y1225263D03*
X629599D03*
Y1218570D03*
X620899D03*
X629599Y1211877D03*
X620899D03*
X629599Y1241995D03*
X620899D03*
X630922Y1235302D03*
X620036D03*
X620899Y1248688D03*
X629599D03*
X625246Y1273164D03*
X627646D03*
X627631Y1578182D03*
X623371D03*
X627631Y1590094D03*
X623371D03*
X628671Y1602380D03*
Y1614292D03*
X620871D03*
Y1602380D03*
X616611Y1614292D03*
Y1602380D03*
X619488Y1679320D03*
Y1688391D03*
Y1693493D03*
Y1698030D03*
Y1683857D03*
Y1707666D03*
Y1712203D03*
Y1702564D03*
Y1730911D03*
Y1726377D03*
Y1721840D03*
Y1716737D03*
X637041Y766798D03*
X645741D03*
Y773491D03*
X637041D03*
X645741Y780184D03*
X637041D03*
Y803609D03*
X645741D03*
X637041Y796916D03*
X645741D03*
Y790223D03*
X637041D03*
X636221Y810302D03*
X646844D03*
X646774Y816995D03*
X637041D03*
X645741Y833727D03*
X637041D03*
Y827034D03*
X645741D03*
X637041Y847113D03*
X645801D03*
X637041Y840420D03*
X645741D03*
X646819Y853806D03*
X636332Y853955D03*
X645918Y863845D03*
X636266D03*
X637041Y877231D03*
X645741D03*
X637041Y870538D03*
X645741D03*
Y883924D03*
X637041D03*
Y900656D03*
X645741D03*
X637041Y890617D03*
X645741D03*
X637041Y914042D03*
X645741D03*
Y907349D03*
X637041D03*
X646393Y927526D03*
X636026Y927428D03*
X645741Y920735D03*
X637041D03*
X645741Y944160D03*
X637041D03*
X636170Y937467D03*
X646703D03*
X645741Y960892D03*
X637041D03*
Y950853D03*
X645741D03*
X637041Y980971D03*
X645741D03*
X637041Y974278D03*
X645741D03*
X637041Y967585D03*
X645741D03*
X637041Y987664D03*
X645741D03*
X637041Y1027822D03*
X645741D03*
Y1017782D03*
X637041D03*
X645741Y1047900D03*
X637041D03*
Y1041207D03*
X645741D03*
X637041Y1034515D03*
X645741D03*
X637041Y1061286D03*
X645741D03*
Y1054593D03*
X637041D03*
X636141Y1074672D03*
X646541D03*
X645741Y1067979D03*
X636841D03*
X637041Y1091404D03*
X645741D03*
Y1084711D03*
X636241D03*
X645741Y1111483D03*
X637041D03*
X645741Y1098097D03*
X637041D03*
X645741Y1104790D03*
X637041D03*
Y1121522D03*
X645741D03*
X637041Y1128915D03*
X645741Y1128215D03*
X646584Y1135108D03*
X635744Y1134908D03*
X645741Y1141601D03*
X637041D03*
X645741Y1148294D03*
X637041D03*
X645741Y1158333D03*
X637041D03*
Y1171719D03*
X645741D03*
Y1165026D03*
X637041D03*
Y1185105D03*
X645741D03*
Y1178412D03*
X637041D03*
X645741Y1208530D03*
X637041D03*
X645741Y1201837D03*
X637041D03*
Y1195144D03*
X645741D03*
X636005Y1221916D03*
X646570D03*
X645741Y1215223D03*
X637041D03*
X645741Y1238648D03*
X637041D03*
X635995Y1231862D03*
X646539Y1231955D03*
X645741Y1245341D03*
X637041D03*
X634213Y1258679D03*
X642746Y1273364D03*
X639946D03*
X647491Y1578088D03*
X639691Y1578182D03*
X635431D03*
X647491Y1590094D03*
X639691D03*
X635431D03*
X644991Y1614292D03*
Y1602380D03*
X632931D03*
Y1614292D03*
X640731D03*
Y1602380D03*
X650599Y770144D03*
X659299D03*
X650599Y783530D03*
X659299D03*
X650599Y776837D03*
X659299D03*
Y800263D03*
X650599D03*
Y793570D03*
X659299D03*
Y806955D03*
X650599D03*
X660432Y813648D03*
X650599D03*
X660199Y820341D03*
X650599D03*
X659299Y830381D03*
X650599D03*
X659299Y850459D03*
X650599D03*
X659299Y843766D03*
X650599D03*
Y837074D03*
X659299D03*
Y857152D03*
X650599D03*
X649563Y867192D03*
X660299D03*
X659299Y873885D03*
X650599D03*
Y880577D03*
X659299D03*
X650599Y893963D03*
X659299D03*
X650599Y887270D03*
X659299D03*
Y917389D03*
X650599D03*
X659299Y910696D03*
X650599D03*
Y904003D03*
X659299D03*
X660504Y924081D03*
X650599D03*
X660174Y930774D03*
X649661D03*
X659299Y947507D03*
X650599D03*
X659299Y940814D03*
X650599D03*
X659299Y964239D03*
X650599D03*
Y954200D03*
X659299D03*
Y977625D03*
X650599D03*
X659299Y970932D03*
X650599D03*
X659299Y991011D03*
X650599D03*
X659299Y984318D03*
X650599D03*
X659299Y1031168D03*
X650599D03*
X659299Y1017782D03*
X650599D03*
X659299Y1024475D03*
X650599D03*
X659299Y1044554D03*
X650599D03*
X659299Y1037861D03*
X650599D03*
X659299Y1051247D03*
X650599D03*
Y1057940D03*
X659299D03*
X660099Y1078018D03*
X649799D03*
X659299Y1071326D03*
X650599D03*
X659299Y1064633D03*
X650599D03*
X659299Y1094751D03*
X650599D03*
X660099Y1088058D03*
X649799D03*
X650599Y1108137D03*
X659299D03*
X650599Y1101444D03*
X659299D03*
X660199Y1124869D03*
X649932Y1124640D03*
X659299Y1114829D03*
X650599D03*
X659299Y1130762D03*
X650599D03*
X659299Y1138255D03*
X650599D03*
X659299Y1144948D03*
X650599D03*
X659299Y1151641D03*
X650599D03*
Y1161680D03*
X659299D03*
X650599Y1175066D03*
X659299D03*
X650599Y1168373D03*
X659299D03*
X650599Y1188452D03*
X659299D03*
X650599Y1181759D03*
X659299D03*
X650599Y1205184D03*
X659299D03*
X650599Y1198491D03*
X659299D03*
X660070Y1225263D03*
X649913D03*
X659299Y1218570D03*
X650599D03*
X659299Y1211877D03*
X650599D03*
X659299Y1241995D03*
X650599D03*
X660234Y1235302D03*
X649701D03*
X650599Y1248688D03*
X659299D03*
X659546Y1257664D03*
X656446Y1273364D03*
X653646D03*
X651751Y1578182D03*
X659551D03*
X651751Y1590094D03*
X659551D03*
X657051Y1602380D03*
Y1614292D03*
X652791Y1602286D03*
Y1614292D03*
X680299Y770144D03*
X675441Y766798D03*
X666741D03*
X680299Y783530D03*
Y776837D03*
X666741Y773491D03*
X675441D03*
X666741Y780184D03*
X675441D03*
Y803609D03*
X666741D03*
X680299Y800263D03*
Y793570D03*
X666741Y796916D03*
X675441D03*
X666741Y790223D03*
X675441D03*
X676403Y816995D03*
X665803D03*
X675441Y810302D03*
X666741D03*
X680299Y820341D03*
Y813648D03*
Y806955D03*
X675441Y833727D03*
X666741D03*
X676625Y827034D03*
X665876D03*
X680299Y830381D03*
X675441Y847113D03*
X666741D03*
X680299Y850459D03*
Y843766D03*
Y837074D03*
X666741Y840420D03*
X675441D03*
X676417Y853806D03*
X665890D03*
X680299Y867192D03*
Y857152D03*
X665916Y863845D03*
X676600D03*
X675441Y877231D03*
X666741D03*
X675441Y870538D03*
X666741D03*
Y883924D03*
X675441D03*
X680299Y880577D03*
Y873885D03*
X666741Y900656D03*
X675441D03*
X680299Y893963D03*
Y887270D03*
X666741Y890617D03*
X675441D03*
Y914042D03*
X666741D03*
X680299Y917389D03*
Y910696D03*
Y904003D03*
X666741Y907349D03*
X675441D03*
X676488Y927428D03*
X665896D03*
X675441Y920735D03*
X666741D03*
X680299Y930774D03*
Y924081D03*
X675441Y944160D03*
X666741D03*
X676359Y937467D03*
X665923D03*
X680299Y947507D03*
Y940814D03*
Y964239D03*
X675441Y960892D03*
X666741D03*
X680299Y954200D03*
X666741Y950853D03*
X675441D03*
Y980971D03*
X666741D03*
X680299Y970932D03*
X675441Y974278D03*
X666741D03*
X675441Y967585D03*
X666741D03*
X680299Y977625D03*
X675441Y987664D03*
X666741D03*
X680299Y991011D03*
Y984318D03*
Y1031168D03*
Y1024475D03*
X675441Y1027822D03*
X666741D03*
X675441Y1017782D03*
X666741D03*
X680299D03*
X675441Y1047900D03*
X666741D03*
X680299Y1037861D03*
X675441Y1041207D03*
X666741D03*
X675441Y1034515D03*
X666741D03*
X680299Y1044554D03*
Y1057940D03*
Y1051247D03*
X675441Y1054593D03*
X666741D03*
Y1061286D03*
X675441D03*
X676341Y1074672D03*
X665841D03*
X675441Y1067979D03*
X666741D03*
X680299Y1078018D03*
Y1071326D03*
Y1064633D03*
X675441Y1091404D03*
X666741D03*
X676241Y1084711D03*
X665941D03*
X680299Y1094751D03*
Y1088058D03*
X666741Y1111483D03*
X675441D03*
X680299Y1108137D03*
Y1101444D03*
X666741Y1104790D03*
X675441D03*
X666741Y1098097D03*
X675441D03*
X666741Y1128215D03*
X675441D03*
X680299Y1124869D03*
Y1114829D03*
X666741Y1121522D03*
X675441D03*
X680299Y1144948D03*
Y1138255D03*
Y1131562D03*
X666741Y1141601D03*
X675441D03*
X666741Y1134908D03*
X675441D03*
X676652Y1148294D03*
X665602D03*
X676241Y1158333D03*
X665941D03*
X680299Y1161680D03*
Y1151641D03*
X675441Y1165026D03*
X666741D03*
X680299Y1175066D03*
Y1168373D03*
X666741Y1171719D03*
X675441D03*
X680299Y1188452D03*
Y1181759D03*
X666741Y1185105D03*
X675441D03*
X666741Y1178412D03*
X675441D03*
X680299Y1205184D03*
Y1198491D03*
X666741Y1208530D03*
X675441D03*
X666741Y1201837D03*
X675441D03*
X666741Y1195144D03*
X675441D03*
X680299Y1218570D03*
Y1225263D03*
X676448Y1221916D03*
X665651D03*
X675441Y1215223D03*
X666741D03*
X680299Y1211877D03*
X675441Y1238648D03*
X666741D03*
X676462Y1231955D03*
X665912D03*
X680299Y1241995D03*
Y1235302D03*
X675441Y1245341D03*
X666741D03*
X676046Y1257964D03*
X680299Y1248688D03*
X672446Y1273364D03*
X669646D03*
X664851Y1602380D03*
Y1614292D03*
X696441Y766798D03*
X688999Y770144D03*
X696441Y773491D03*
Y780184D03*
X688999Y783530D03*
Y776837D03*
X696441Y803609D03*
Y796916D03*
Y790223D03*
X688999Y800263D03*
Y793570D03*
X696441Y816995D03*
Y810302D03*
X689888Y820341D03*
X688999Y813648D03*
Y806955D03*
X696441Y833727D03*
Y827034D03*
X688999Y830381D03*
X696441Y847113D03*
X688999Y850459D03*
X696441Y840420D03*
X688999Y843766D03*
Y837074D03*
X696441Y863845D03*
Y853806D03*
X688999Y867192D03*
X689896Y857152D03*
X696441Y883924D03*
Y877231D03*
Y870538D03*
X688999Y880577D03*
Y873885D03*
X696441Y900656D03*
Y890617D03*
X688999Y893963D03*
Y887270D03*
X696441Y914042D03*
Y907349D03*
X688999Y917389D03*
Y910696D03*
Y904003D03*
X696441Y927428D03*
Y920735D03*
X690104Y930774D03*
X688999Y924081D03*
X696441Y944160D03*
Y937467D03*
X688999Y947507D03*
Y940814D03*
X696441Y960892D03*
Y950853D03*
X688999Y964239D03*
Y954200D03*
X696441Y980971D03*
Y974278D03*
Y967585D03*
X688999Y970932D03*
Y977625D03*
X696441Y987664D03*
X688999Y991011D03*
Y984318D03*
X696441Y1027822D03*
Y1017782D03*
X688999Y1031168D03*
Y1024475D03*
Y1017782D03*
X696441Y1047900D03*
Y1041207D03*
Y1034515D03*
X688999Y1037861D03*
Y1044554D03*
X696441Y1054593D03*
Y1061286D03*
X688999Y1057940D03*
X696441Y1074672D03*
Y1067979D03*
X688999Y1077118D03*
Y1071326D03*
Y1064633D03*
X696441Y1091404D03*
Y1084711D03*
X688999Y1094751D03*
Y1088058D03*
X696441Y1111483D03*
Y1104790D03*
Y1098097D03*
X688999Y1108137D03*
Y1101444D03*
X696441Y1128215D03*
Y1121522D03*
X688999Y1124869D03*
Y1114829D03*
X696441Y1141601D03*
Y1134908D03*
X688999Y1144948D03*
Y1138255D03*
Y1131562D03*
X696441Y1158333D03*
Y1148294D03*
X688999Y1161680D03*
X689999Y1151641D03*
X696441Y1171719D03*
Y1165026D03*
X688999Y1175066D03*
Y1168373D03*
X696441Y1185105D03*
Y1178412D03*
X688999Y1188452D03*
Y1181759D03*
X696441Y1208530D03*
Y1201837D03*
Y1195144D03*
X688999Y1205184D03*
Y1198491D03*
X696441Y1221916D03*
Y1215223D03*
X688999Y1218570D03*
X689799Y1225263D03*
X688999Y1211877D03*
X696441Y1238648D03*
Y1231955D03*
X688999Y1241995D03*
Y1235302D03*
X688916Y1256964D03*
X696441Y1245341D03*
X688999Y1248688D03*
X686146Y1273364D03*
X683346D03*
X709999Y770144D03*
X705141Y766798D03*
X709999Y783530D03*
Y776837D03*
X705141Y773491D03*
Y780184D03*
X709999Y800263D03*
Y793570D03*
X705141Y803609D03*
Y796916D03*
Y790223D03*
X709999Y820341D03*
Y813648D03*
Y806955D03*
X705141Y816995D03*
Y810302D03*
X709999Y830381D03*
X705141Y833727D03*
Y827034D03*
Y847113D03*
X709999Y850459D03*
Y843766D03*
Y837074D03*
X705141Y840420D03*
Y863845D03*
Y853806D03*
X709999Y867192D03*
Y857152D03*
X705141Y883924D03*
Y877231D03*
Y870538D03*
X709999Y880577D03*
Y873885D03*
X705141Y900656D03*
Y890617D03*
X709999Y893963D03*
Y887270D03*
X705141Y914042D03*
Y907349D03*
X709999Y917389D03*
Y910696D03*
Y904003D03*
X705141Y927428D03*
Y920735D03*
X709999Y930774D03*
Y924081D03*
X705141Y944160D03*
Y937467D03*
X709999Y947507D03*
Y940814D03*
X705141Y960892D03*
Y950853D03*
X709999Y964239D03*
Y954200D03*
X705141Y980971D03*
Y974278D03*
Y967585D03*
X709999Y977625D03*
Y970932D03*
X705141Y987664D03*
X709999Y991011D03*
Y984318D03*
X705141Y1027822D03*
Y1017782D03*
X709999Y1031168D03*
Y1024475D03*
Y1017782D03*
X705141Y1047900D03*
Y1041207D03*
Y1034515D03*
X709999Y1044554D03*
Y1037861D03*
X705141Y1054593D03*
Y1061286D03*
X709999Y1057940D03*
Y1051247D03*
X705141Y1074672D03*
Y1067979D03*
X709999Y1078018D03*
Y1071326D03*
Y1064633D03*
X705141Y1091404D03*
Y1084711D03*
X709999Y1094751D03*
Y1088058D03*
X705141Y1111483D03*
Y1104790D03*
Y1098097D03*
X709999Y1108137D03*
Y1101444D03*
X705141Y1128215D03*
Y1121522D03*
X709999Y1124869D03*
Y1114829D03*
X705141Y1141601D03*
Y1134908D03*
X709999Y1144948D03*
Y1138255D03*
Y1131562D03*
X705141Y1158333D03*
Y1148294D03*
X709999Y1161680D03*
Y1151641D03*
X705141Y1171719D03*
Y1165026D03*
X709999Y1175066D03*
Y1168373D03*
X705141Y1185105D03*
Y1178412D03*
X709999Y1188452D03*
Y1181759D03*
X705141Y1208530D03*
Y1201837D03*
Y1195144D03*
X709999Y1205184D03*
Y1198491D03*
X705141Y1221916D03*
Y1215223D03*
X709999Y1225263D03*
Y1218570D03*
Y1211877D03*
X705141Y1238648D03*
Y1231955D03*
X709999Y1241995D03*
Y1235302D03*
X705141Y1245341D03*
X709999Y1248688D03*
X713046Y1273364D03*
X702146D03*
X699346D03*
X726141Y766798D03*
X718699Y770144D03*
X726141Y773491D03*
Y780184D03*
X718699Y783530D03*
Y776837D03*
X726141Y803609D03*
Y796916D03*
Y790223D03*
X718699Y800263D03*
Y793570D03*
X726141Y816995D03*
Y810302D03*
X718699Y820341D03*
Y813648D03*
Y806955D03*
X726141Y833727D03*
Y827034D03*
X718699Y830381D03*
X726141Y847113D03*
Y840420D03*
X718699Y850459D03*
Y843766D03*
Y837074D03*
X726141Y863845D03*
Y853806D03*
X718699Y867192D03*
Y857152D03*
X726141Y883924D03*
Y877231D03*
Y870538D03*
X718699Y880577D03*
Y873885D03*
X726141Y900656D03*
Y890617D03*
X718699Y893963D03*
Y887270D03*
X726141Y914042D03*
Y907349D03*
X718699Y917389D03*
Y910696D03*
Y904003D03*
X726141Y927428D03*
Y920735D03*
X718699Y930774D03*
Y924081D03*
X726141Y944160D03*
Y937467D03*
X718699Y947507D03*
Y940814D03*
X726141Y960892D03*
Y950853D03*
X718699Y964239D03*
Y954200D03*
X726141Y980971D03*
Y974278D03*
Y967585D03*
X718699Y977625D03*
Y970932D03*
X726141Y987664D03*
X718699Y991011D03*
Y984318D03*
X726141Y1027822D03*
Y1017782D03*
X718699Y1031168D03*
Y1024475D03*
Y1017782D03*
X726141Y1047900D03*
Y1041207D03*
Y1034515D03*
X718699Y1044554D03*
Y1037861D03*
X726141Y1061286D03*
Y1054593D03*
X718699Y1057940D03*
Y1051247D03*
X726141Y1074672D03*
Y1067979D03*
X718699Y1078018D03*
Y1071326D03*
Y1064633D03*
X726141Y1091404D03*
Y1084711D03*
X718699Y1094751D03*
Y1088058D03*
X726141Y1111483D03*
Y1104790D03*
Y1098097D03*
X718699Y1108137D03*
Y1101444D03*
X726141Y1128215D03*
Y1121522D03*
X718699Y1124869D03*
Y1114829D03*
X726141Y1141601D03*
Y1134908D03*
X718699Y1144948D03*
Y1138255D03*
Y1131562D03*
X726141Y1158333D03*
Y1148294D03*
X718699Y1161680D03*
Y1151641D03*
X726141Y1171719D03*
Y1165026D03*
X718699Y1175066D03*
Y1168373D03*
X726141Y1185105D03*
Y1178412D03*
X718699Y1188452D03*
Y1181759D03*
X726141Y1208530D03*
Y1201837D03*
Y1195144D03*
X718699Y1205184D03*
Y1198491D03*
X726141Y1221916D03*
Y1215223D03*
X718699Y1225263D03*
Y1218570D03*
Y1211877D03*
X726141Y1238648D03*
Y1231955D03*
X718699Y1241995D03*
Y1235302D03*
X726141Y1245341D03*
X719046Y1257064D03*
X718699Y1248688D03*
X729046Y1273364D03*
X715846D03*
X739699Y770144D03*
X734841Y766798D03*
X739699Y783530D03*
Y776837D03*
X734841Y773491D03*
Y780184D03*
X739699Y800263D03*
Y793570D03*
X734841Y803609D03*
Y796916D03*
Y790223D03*
X739699Y820341D03*
Y813648D03*
Y806955D03*
X734841Y816995D03*
Y810302D03*
X739699Y830381D03*
X734841Y833727D03*
Y827034D03*
X739699Y850459D03*
Y843766D03*
Y837074D03*
X734841Y847113D03*
Y840420D03*
X739699Y867192D03*
Y857152D03*
X734841Y863845D03*
Y853806D03*
X739699Y880577D03*
Y873885D03*
X734841Y883924D03*
Y877231D03*
Y870538D03*
X739699Y893963D03*
Y887270D03*
X734841Y900656D03*
Y890617D03*
X739699Y917389D03*
Y910696D03*
Y904003D03*
X734841Y914042D03*
Y907349D03*
X739699Y930774D03*
Y924081D03*
X734841Y927428D03*
Y920735D03*
X739699Y947507D03*
Y940814D03*
X734841Y944160D03*
Y937467D03*
X739699Y964239D03*
Y954200D03*
X734841Y960892D03*
Y950853D03*
X739699Y977625D03*
Y970932D03*
X734841Y980971D03*
Y974278D03*
Y967585D03*
X739699Y991011D03*
Y984318D03*
X734841Y987664D03*
X739699Y1031168D03*
Y1024475D03*
Y1017782D03*
X734841Y1027822D03*
Y1017782D03*
X739699Y1044554D03*
Y1037861D03*
X734841Y1047900D03*
Y1041207D03*
Y1034515D03*
X739699Y1057940D03*
Y1051247D03*
X734841Y1061286D03*
Y1054593D03*
X739699Y1078018D03*
Y1071326D03*
Y1064633D03*
X734841Y1074672D03*
Y1067979D03*
X739699Y1094751D03*
Y1088058D03*
X734841Y1091404D03*
Y1084711D03*
X739699Y1108137D03*
Y1101444D03*
X734841Y1111483D03*
Y1104790D03*
Y1098097D03*
X739699Y1124869D03*
Y1114829D03*
X734841Y1128215D03*
Y1121522D03*
X739699Y1144948D03*
Y1138255D03*
Y1131562D03*
X734841Y1141601D03*
Y1134908D03*
X739699Y1161680D03*
Y1151641D03*
X734841Y1158333D03*
Y1148294D03*
X739699Y1175066D03*
Y1168373D03*
X734841Y1171719D03*
Y1165026D03*
X739699Y1188452D03*
Y1181759D03*
X734841Y1185105D03*
Y1178412D03*
X739699Y1205184D03*
Y1198491D03*
X734841Y1208530D03*
Y1201837D03*
Y1195144D03*
X739699Y1225263D03*
Y1218570D03*
Y1211877D03*
X734841Y1221916D03*
Y1215223D03*
X739699Y1241995D03*
Y1235302D03*
X734841Y1238648D03*
Y1231955D03*
X739699Y1248688D03*
X734841Y1245341D03*
X745546Y1273364D03*
X742746D03*
X731372Y1273464D03*
X755841Y766798D03*
X748399Y770144D03*
X755841Y780184D03*
Y773491D03*
X748399Y783530D03*
Y776837D03*
X755841Y803609D03*
Y796916D03*
Y790223D03*
X748399Y800263D03*
Y793570D03*
X755841Y816995D03*
Y810302D03*
X748399Y820341D03*
Y813648D03*
Y806955D03*
X755841Y833727D03*
Y827034D03*
X748399Y830381D03*
X755841Y847113D03*
Y840420D03*
X748399Y850459D03*
Y843766D03*
Y837074D03*
X755841Y863845D03*
Y853806D03*
X748399Y867192D03*
Y857152D03*
X755841Y883924D03*
Y877231D03*
Y870538D03*
X748399Y880577D03*
Y873885D03*
X755841Y900656D03*
Y890617D03*
X748399Y893963D03*
Y887270D03*
X755841Y914042D03*
Y907349D03*
X748399Y917389D03*
Y910696D03*
Y904003D03*
X755841Y927428D03*
Y920735D03*
X748399Y930774D03*
Y924081D03*
X755841Y944160D03*
Y937467D03*
X748399Y947507D03*
Y940814D03*
X755841Y960892D03*
Y950853D03*
X748399Y964239D03*
Y954200D03*
X755841Y980971D03*
Y974278D03*
Y967585D03*
X748399Y977625D03*
Y970932D03*
X755841Y987664D03*
X748399Y991011D03*
Y984318D03*
X755841Y1027822D03*
Y1017782D03*
X748399Y1031168D03*
Y1024475D03*
Y1017782D03*
X755841Y1047900D03*
Y1041207D03*
Y1034515D03*
X748399Y1044554D03*
Y1037861D03*
X755841Y1054593D03*
Y1061286D03*
X748399Y1057940D03*
X755841Y1067979D03*
Y1074672D03*
X748399Y1078018D03*
Y1071326D03*
Y1064633D03*
X755841Y1084711D03*
Y1091404D03*
X748399Y1094751D03*
Y1088058D03*
X755841Y1111483D03*
Y1104790D03*
Y1098097D03*
X748399Y1108137D03*
Y1101444D03*
X755841Y1128215D03*
Y1121522D03*
X748399Y1124869D03*
Y1114829D03*
X755841Y1141601D03*
Y1134908D03*
X748399Y1144948D03*
Y1138255D03*
Y1131562D03*
X755841Y1158333D03*
Y1148294D03*
X748399Y1161680D03*
Y1151641D03*
X755841Y1171719D03*
Y1165026D03*
X748399Y1175066D03*
Y1168373D03*
X755841Y1185105D03*
Y1178412D03*
X748399Y1188452D03*
Y1181759D03*
X755841Y1208530D03*
Y1201837D03*
Y1195144D03*
X748399Y1205184D03*
Y1198491D03*
X755841Y1221916D03*
Y1215223D03*
X748399Y1225263D03*
Y1218570D03*
Y1211877D03*
X755841Y1238648D03*
Y1231955D03*
X748399Y1241995D03*
Y1235302D03*
X755841Y1245341D03*
X748283Y1256964D03*
X748399Y1248688D03*
X758746Y1273364D03*
X761546D03*
X769399Y770144D03*
X778099D03*
X764541Y766798D03*
X769399Y783530D03*
X778099D03*
X769399Y776837D03*
X778099D03*
X764541Y780184D03*
Y773491D03*
X769399Y800263D03*
X778099D03*
X769399Y793570D03*
X778099D03*
X764541Y803609D03*
Y796916D03*
Y790223D03*
X769399Y820341D03*
X778099D03*
X769399Y813648D03*
X778099D03*
X769399Y806955D03*
X778099D03*
X764541Y816995D03*
Y810302D03*
X769399Y830381D03*
X778099D03*
X764541Y833727D03*
Y827034D03*
X769399Y850459D03*
X778099D03*
Y843766D03*
X769399D03*
Y837074D03*
X778099D03*
X764541Y847113D03*
Y840420D03*
X778099Y867192D03*
X769399D03*
Y857152D03*
X778099D03*
X764541Y863845D03*
Y853806D03*
X769399Y880577D03*
X778099D03*
X769399Y873885D03*
X778099D03*
X764541Y883924D03*
Y877231D03*
Y870538D03*
X778099Y893963D03*
X769399D03*
Y887270D03*
X778099D03*
X764541Y900656D03*
Y890617D03*
X769399Y917389D03*
X778099D03*
X769399Y910696D03*
X778099D03*
X769399Y904003D03*
X778099D03*
X764541Y914042D03*
Y907349D03*
X769399Y930774D03*
X778099D03*
X769399Y924081D03*
X778099D03*
X764541Y927428D03*
Y920735D03*
X769399Y947507D03*
X778099D03*
X769399Y940814D03*
X778099D03*
X764541Y944160D03*
Y937467D03*
X769399Y964239D03*
X778099D03*
X769399Y954200D03*
X778099D03*
X764541Y960892D03*
Y950853D03*
X769399Y977625D03*
X778099D03*
X769399Y970932D03*
X778099D03*
X764541Y980971D03*
Y974278D03*
Y967585D03*
X769399Y991011D03*
X778099D03*
X769399Y984318D03*
X778099D03*
X764541Y987664D03*
X769399Y1031168D03*
X778099D03*
X769399Y1024475D03*
X778099D03*
X769399Y1017782D03*
X778099D03*
X764541Y1027822D03*
Y1017782D03*
X778099Y1044554D03*
X769399D03*
Y1037861D03*
X778099D03*
X764541Y1047900D03*
Y1041207D03*
Y1034515D03*
X769399Y1057940D03*
X778099D03*
X769399Y1051247D03*
X778099D03*
X764541Y1054593D03*
Y1061286D03*
X778099Y1078018D03*
X769399D03*
X778099Y1071326D03*
X769399D03*
Y1064633D03*
X778099D03*
X764541Y1067979D03*
Y1074672D03*
X778099Y1094751D03*
X769399D03*
X778099Y1088058D03*
X769399D03*
X764541Y1084711D03*
Y1091404D03*
X778099Y1108137D03*
X769399D03*
X778099Y1101444D03*
X769399D03*
X764541Y1111483D03*
Y1104790D03*
Y1098097D03*
X778099Y1124869D03*
X769399D03*
X778099Y1114829D03*
X769399D03*
X764541Y1128215D03*
Y1121522D03*
X778099Y1144948D03*
X769399D03*
X778099Y1138255D03*
X769399D03*
X778099Y1131562D03*
X769399D03*
X764541Y1141601D03*
Y1134908D03*
X778099Y1161680D03*
X769399D03*
X778099Y1151641D03*
X769399D03*
X764541Y1158333D03*
Y1148294D03*
X778099Y1175066D03*
X769399D03*
X778099Y1168373D03*
X769399D03*
X764541Y1171719D03*
Y1165026D03*
X778099Y1188452D03*
X769399D03*
X778099Y1181759D03*
X769399D03*
X764541Y1185105D03*
Y1178412D03*
X769399Y1205184D03*
X778099D03*
Y1198491D03*
X769399D03*
X764541Y1208530D03*
Y1201837D03*
Y1195144D03*
X778099Y1225263D03*
X769399D03*
X778099Y1218570D03*
X769399D03*
Y1211877D03*
X778099D03*
X764541Y1221916D03*
Y1215223D03*
X778099Y1241995D03*
X769399D03*
X778099Y1235302D03*
X769399D03*
X764541Y1238648D03*
Y1231955D03*
X778346Y1257264D03*
X778099Y1248688D03*
X769399D03*
X764541Y1245341D03*
X772446Y1273364D03*
X775246D03*
X785541Y766798D03*
X794241D03*
X785541Y773491D03*
X794241D03*
X785541Y780184D03*
X794241D03*
X785541Y803609D03*
X794241D03*
X785541Y790223D03*
X794241D03*
X785541Y796916D03*
X794241D03*
X785541Y816995D03*
X794241D03*
X785541Y810302D03*
X794241D03*
X785541Y833727D03*
X794241D03*
X785541Y827034D03*
X794241D03*
X785541Y840420D03*
X794241D03*
X785541Y847113D03*
X794241D03*
X785541Y853806D03*
X794241D03*
X785541Y863845D03*
X794241D03*
X785541Y883924D03*
X794241D03*
X785541Y870538D03*
X794241D03*
X785541Y877231D03*
X794241D03*
X785541Y900656D03*
X794241D03*
X785541Y890617D03*
X794241D03*
X785541Y907349D03*
X794241D03*
X785541Y914042D03*
X794241D03*
X785541Y920735D03*
X794241D03*
X785541Y927428D03*
X794241D03*
X785541Y937467D03*
X794241D03*
X785541Y944160D03*
X794241D03*
X785541Y960892D03*
X794241D03*
X785541Y950853D03*
X794241D03*
X785541Y980971D03*
X794241D03*
X785541Y974278D03*
X794241D03*
X785541Y967585D03*
X794241D03*
X785541Y987664D03*
X794241D03*
X785541Y1027822D03*
X794241D03*
X785541Y1017782D03*
X794241D03*
X785541Y1047900D03*
X794241D03*
X785541Y1041207D03*
X794241D03*
X785541Y1034515D03*
X794241D03*
X785541Y1054593D03*
X794241D03*
X785541Y1061286D03*
X794241D03*
X785541Y1074672D03*
X794241D03*
X785541Y1067979D03*
X794241D03*
X785541Y1091404D03*
X794241D03*
X785541Y1084711D03*
X794241D03*
X785541Y1111483D03*
X794241D03*
X785541Y1104790D03*
X794241D03*
X785541Y1098097D03*
X794241D03*
X785541Y1128215D03*
X794241D03*
X785541Y1121522D03*
X794241D03*
X785541Y1141601D03*
X794241D03*
X785541Y1134908D03*
X794241D03*
X785541Y1158333D03*
X794241D03*
X785541Y1148294D03*
X794241D03*
X785541Y1171719D03*
X794241D03*
X785541Y1165026D03*
X794241D03*
X785541Y1178412D03*
X794241D03*
X785541Y1185105D03*
X794241D03*
X785541Y1208530D03*
X794241D03*
X785541Y1195144D03*
X794241D03*
X785541Y1201837D03*
X794241D03*
X785541Y1221916D03*
X794241D03*
X785541Y1215223D03*
X794241D03*
X785541Y1238648D03*
X794241D03*
X785541Y1231955D03*
X794241D03*
X785541Y1245341D03*
X794241D03*
X788446Y1273364D03*
X791246D03*
X799099Y770144D03*
X807799D03*
X799099Y783530D03*
X807799D03*
X799099Y776837D03*
X807799D03*
X799099Y800263D03*
X807799D03*
X799099Y793570D03*
X807799D03*
X799099Y820341D03*
X807799D03*
X799099Y806955D03*
X807799D03*
X799099Y813648D03*
X807799D03*
X799099Y830381D03*
X807799D03*
X799099Y850459D03*
X807799D03*
X799099Y837074D03*
X807799D03*
X799099Y843766D03*
X807799D03*
X799099Y867192D03*
X807799D03*
X799099Y857152D03*
X807799D03*
X799099Y873885D03*
X807799D03*
X799099Y880577D03*
X807799D03*
X799099Y887270D03*
X807799D03*
X799099Y893963D03*
X807799D03*
X799099Y917389D03*
X807799D03*
X799099Y904003D03*
X807799D03*
X799099Y910696D03*
X807799D03*
X799099Y930774D03*
X807799D03*
X799099Y924081D03*
X807799D03*
X799099Y947507D03*
X807799D03*
X799099Y940814D03*
X807799D03*
X799099Y964239D03*
X807799D03*
X799099Y954200D03*
X807799D03*
X799099Y970932D03*
X807799D03*
X799099Y977625D03*
X807799D03*
X799099Y991011D03*
X807799D03*
X799099Y984318D03*
X807799D03*
X799099Y1031168D03*
X807799D03*
X799099Y1024475D03*
X807799D03*
X799099Y1017782D03*
X807799D03*
X799099Y1037861D03*
X807799D03*
X799099Y1044554D03*
X807799D03*
X799099Y1057940D03*
X807799D03*
X799099Y1051247D03*
X807799D03*
X799099Y1078018D03*
X807799D03*
X799099Y1071326D03*
X807799D03*
X799099Y1064633D03*
X807799D03*
X799099Y1094751D03*
X807799D03*
X799099Y1088058D03*
X807799D03*
X799099Y1108137D03*
X807799D03*
X799099Y1101444D03*
X807799D03*
X799099Y1124869D03*
X807799D03*
X799099Y1114829D03*
X807799D03*
X799099Y1144948D03*
X807799D03*
X799099Y1138255D03*
X807799D03*
X799099Y1131562D03*
X807799D03*
X799099Y1161680D03*
X807799D03*
X799099Y1151641D03*
X807799D03*
X799099Y1175066D03*
X807799D03*
X799099Y1168373D03*
X807799D03*
X799099Y1188452D03*
X807799D03*
X799099Y1181759D03*
X807799D03*
X799099Y1205184D03*
X807799D03*
X799099Y1198491D03*
X807799D03*
X799099Y1225263D03*
X807799D03*
X799099Y1211877D03*
X807799D03*
X799099Y1218570D03*
X807799D03*
X799099Y1241995D03*
X807799D03*
X799099Y1235302D03*
X807799D03*
X799099Y1248688D03*
X807799D03*
X808046Y1257664D03*
X804946Y1273364D03*
X802146D03*
X815241Y766798D03*
X823941D03*
X815241Y773491D03*
X823941D03*
X815241Y780184D03*
X823941D03*
X815241Y803609D03*
X823941D03*
X815241Y790223D03*
X823941D03*
X815241Y796916D03*
X823941D03*
X815241Y816995D03*
X823941D03*
X815241Y810302D03*
X823941D03*
X815241Y833727D03*
X823941D03*
X815241Y827034D03*
X823941D03*
X815241Y840420D03*
X823941D03*
X815241Y847113D03*
X823941D03*
X815241Y853806D03*
X823941D03*
X815241Y863845D03*
X823941D03*
X815241Y883924D03*
X823941D03*
X815241Y870538D03*
X823941D03*
X815241Y877231D03*
X823941D03*
X815241Y900656D03*
X823941D03*
X815241Y890617D03*
X823941D03*
X815241Y907349D03*
X823941D03*
X815241Y914042D03*
X823941D03*
X815241Y920735D03*
X823941D03*
X815241Y927428D03*
X823941D03*
X815241Y937467D03*
X823941D03*
X815241Y944160D03*
X823941D03*
X815241Y960892D03*
X823941D03*
X815241Y950853D03*
X823941D03*
X815241Y980971D03*
X823941D03*
X815241Y974278D03*
X823941D03*
X815241Y967585D03*
X823941D03*
X815241Y987664D03*
X823941D03*
X815241Y1027822D03*
X823941D03*
X815241Y1017782D03*
X823941D03*
X815241Y1047900D03*
X823941D03*
X815241Y1041207D03*
X823941D03*
X815241Y1034515D03*
X823941D03*
X815241Y1054593D03*
X823941D03*
X815241Y1061286D03*
X823941D03*
X815241Y1074672D03*
X823941D03*
X815241Y1067979D03*
X823941D03*
X815241Y1091404D03*
X823941D03*
X815241Y1084711D03*
X823941D03*
X815241Y1111483D03*
X823941D03*
X815241Y1104790D03*
X823941D03*
X815241Y1098097D03*
X823941D03*
X815241Y1128215D03*
X823941D03*
X815241Y1121522D03*
X823941D03*
X815241Y1141601D03*
X823941D03*
X815241Y1134908D03*
X823941D03*
X815241Y1158333D03*
X823941D03*
X815241Y1148294D03*
X823941D03*
X815241Y1171719D03*
X823941D03*
X815241Y1165026D03*
X823941D03*
X815241Y1178412D03*
X823941D03*
X815241Y1185105D03*
X823941D03*
X815241Y1208530D03*
X823941D03*
X815241Y1195144D03*
X823941D03*
X815241Y1201837D03*
X823941D03*
X815241Y1221916D03*
X823941D03*
X815241Y1215223D03*
X823941D03*
X815241Y1238648D03*
X823941D03*
X815241Y1231955D03*
X823941D03*
X815241Y1245341D03*
X823941D03*
X820946Y1273364D03*
X818146D03*
X828799Y770144D03*
X837499D03*
X828799Y783530D03*
X837499D03*
X828799Y776837D03*
X837499D03*
Y800263D03*
X828799D03*
X837499Y793570D03*
X828799D03*
Y820341D03*
X837499D03*
X828799Y813648D03*
X837499D03*
X828799Y806955D03*
X837499D03*
X828799Y830381D03*
X837499D03*
X828799Y850459D03*
X837499D03*
X828799Y843766D03*
X837499D03*
X828799Y837074D03*
X837499D03*
X828799Y867192D03*
X837499D03*
X828799Y857152D03*
X837499D03*
X828799Y880577D03*
X837499D03*
X828799Y873885D03*
X837499D03*
X828799Y893963D03*
X837499D03*
X828799Y887270D03*
X837499D03*
X828799Y917389D03*
X837499D03*
Y904003D03*
X828799D03*
X837499Y910696D03*
X828799D03*
Y930774D03*
X837499D03*
X828799Y924081D03*
X837499D03*
X828799Y947507D03*
X837499D03*
X828799Y940814D03*
X837499D03*
X828799Y964239D03*
X837499D03*
X828799Y954200D03*
X837499D03*
X828799Y977625D03*
X837499D03*
X828799Y970932D03*
X837499D03*
X828799Y991011D03*
X837499D03*
X828799Y984318D03*
X837499D03*
X828799Y1031168D03*
X837499D03*
X828799Y1024475D03*
X837499D03*
X828799Y1017782D03*
X837499D03*
X828799Y1044554D03*
X837499D03*
X828799Y1037861D03*
X837499D03*
X828799Y1057940D03*
X837499D03*
X828799Y1051247D03*
X837499D03*
X828799Y1078018D03*
X837499D03*
X828799Y1071326D03*
X837499D03*
X828799Y1064633D03*
X837499D03*
X828799Y1094751D03*
X837499D03*
Y1088058D03*
X828799D03*
X837499Y1108137D03*
X828799D03*
Y1101444D03*
X837499D03*
Y1124869D03*
X828799D03*
X837499Y1114829D03*
X828799D03*
X837499Y1144948D03*
X828799D03*
X837499Y1138255D03*
X828799D03*
X837499Y1131562D03*
X828799D03*
X837499Y1161680D03*
X828799D03*
X837499Y1151641D03*
X828799D03*
X837499Y1175066D03*
X828799D03*
X837499Y1168373D03*
X828799D03*
Y1188452D03*
X837499D03*
Y1181759D03*
X828799D03*
X837499Y1205184D03*
X828799D03*
X837499Y1198491D03*
X828799D03*
X837499Y1225263D03*
X828799D03*
X837499Y1218570D03*
X828799D03*
X837499Y1211877D03*
X828799D03*
X837499Y1241995D03*
X828799D03*
X837499Y1235302D03*
X828799D03*
X837499Y1248688D03*
X828799D03*
X837846Y1256964D03*
X839246Y1273064D03*
X842046D03*
X831846Y1273364D03*
X834646D03*
X844941Y766798D03*
X853641D03*
X844941Y780184D03*
X853641D03*
X844941Y773491D03*
X853641D03*
X844941Y803609D03*
X853641D03*
X844941Y796916D03*
X853641D03*
X844941Y790223D03*
X853641D03*
X844941Y816995D03*
X853641D03*
X844941Y810302D03*
X853641D03*
X844941Y833727D03*
X853641D03*
X844941Y827034D03*
X853641D03*
X844941Y847113D03*
X853641D03*
X844941Y840420D03*
X853641D03*
X844941Y863845D03*
X853641D03*
X844941Y853806D03*
X853641D03*
X844941Y883924D03*
X853641D03*
X844941Y877231D03*
X853641D03*
X844941Y870538D03*
X853641D03*
X844941Y900656D03*
X853641D03*
X844941Y890617D03*
X853641D03*
X844941Y914042D03*
X853641D03*
X844941Y907349D03*
X853641D03*
X844941Y927428D03*
X853641D03*
X844941Y920735D03*
X853641D03*
X844941Y944160D03*
X853641D03*
X844941Y937467D03*
X853641D03*
X844941Y960892D03*
X853641D03*
X844941Y950853D03*
X853641D03*
X844941Y980971D03*
X853641D03*
X844941Y974278D03*
X853641D03*
X844941Y967585D03*
X853641D03*
X844941Y987664D03*
X853641D03*
X844941Y1027822D03*
X853641D03*
X844941Y1017782D03*
X853641D03*
X844941Y1047900D03*
X853641D03*
X844941Y1041207D03*
X853641D03*
X844941Y1034515D03*
X853641D03*
X844941Y1061286D03*
X853641D03*
X844941Y1054593D03*
X853641D03*
X844941Y1074672D03*
X853641D03*
X844941Y1067979D03*
X853641D03*
X844941Y1091404D03*
X853641D03*
X844941Y1084711D03*
X853641D03*
X844941Y1111483D03*
X853641D03*
X844941Y1104790D03*
X853641D03*
X844941Y1098097D03*
X853641D03*
X844941Y1128215D03*
X853641D03*
X844941Y1121522D03*
X853641D03*
X844941Y1141601D03*
X853641D03*
X844941Y1134908D03*
X853641D03*
X844941Y1158333D03*
X853641D03*
X844941Y1148294D03*
X853641D03*
X844941Y1171719D03*
X853641D03*
X844941Y1165026D03*
X853641D03*
X844941Y1185105D03*
X853641D03*
X844941Y1178412D03*
X853641D03*
X844941Y1208530D03*
X853641D03*
X844941Y1201837D03*
X853641D03*
X844941Y1195144D03*
X853641D03*
X844941Y1221916D03*
X853641D03*
X844941Y1215223D03*
X853641D03*
X844941Y1238648D03*
X853641D03*
X844941Y1231955D03*
X853641D03*
X844941Y1245341D03*
X853641D03*
X1003841Y770144D03*
Y783530D03*
Y776837D03*
Y800263D03*
Y793570D03*
Y820341D03*
Y813648D03*
Y806955D03*
Y830381D03*
Y850459D03*
Y843766D03*
Y837074D03*
Y867192D03*
Y857152D03*
Y880577D03*
Y873885D03*
Y893963D03*
Y887270D03*
Y917389D03*
Y910696D03*
Y904003D03*
Y930774D03*
Y924081D03*
Y947507D03*
Y940814D03*
Y964239D03*
Y954200D03*
Y977625D03*
Y970932D03*
Y991011D03*
Y984318D03*
Y1031168D03*
Y1024475D03*
Y1017782D03*
Y1044554D03*
Y1037861D03*
Y1057940D03*
Y1051247D03*
Y1078018D03*
Y1071326D03*
Y1064633D03*
Y1094751D03*
Y1088058D03*
Y1108137D03*
Y1101444D03*
Y1124869D03*
Y1114829D03*
Y1144948D03*
Y1138255D03*
Y1131562D03*
Y1161680D03*
Y1151641D03*
Y1175066D03*
Y1168373D03*
Y1188452D03*
Y1181759D03*
Y1205184D03*
Y1198491D03*
Y1225263D03*
Y1218570D03*
Y1211877D03*
Y1241995D03*
Y1235302D03*
Y1248688D03*
X1019983Y766798D03*
X1012541Y770144D03*
X1019983Y780184D03*
Y773491D03*
X1012541Y783530D03*
Y776837D03*
X1019983Y803609D03*
Y796916D03*
Y790223D03*
X1012541Y800263D03*
Y793570D03*
X1019983Y816995D03*
Y810302D03*
X1012541Y820341D03*
Y813648D03*
Y806955D03*
X1019983Y833727D03*
Y827034D03*
X1012541Y830381D03*
X1019983Y847113D03*
Y840420D03*
X1012541Y850459D03*
Y843766D03*
Y837074D03*
X1019983Y863845D03*
Y853806D03*
X1012541Y867192D03*
Y857152D03*
X1019983Y883924D03*
Y877231D03*
Y870538D03*
X1012541Y880577D03*
Y873885D03*
X1019983Y900656D03*
Y890617D03*
X1012541Y893963D03*
Y887270D03*
X1019983Y914042D03*
Y907349D03*
X1012541Y917389D03*
Y910696D03*
Y904003D03*
X1019983Y927428D03*
Y920735D03*
X1012541Y930774D03*
Y924081D03*
X1019983Y944160D03*
Y937467D03*
X1012541Y947507D03*
Y940814D03*
X1019983Y960892D03*
Y950853D03*
X1012541Y964239D03*
Y954200D03*
X1019983Y980971D03*
Y974278D03*
Y967585D03*
X1012541Y977625D03*
Y970932D03*
X1019983Y987664D03*
X1012541Y991011D03*
Y984318D03*
X1019983Y1027822D03*
Y1017782D03*
X1012541Y1031168D03*
Y1024475D03*
Y1017782D03*
X1019983Y1047900D03*
Y1041207D03*
Y1034515D03*
X1012541Y1044554D03*
Y1037861D03*
X1019983Y1061286D03*
Y1054593D03*
X1012541Y1057940D03*
Y1051247D03*
X1019983Y1067979D03*
Y1074672D03*
X1012541Y1078018D03*
Y1071326D03*
Y1064633D03*
X1019983Y1091404D03*
Y1084711D03*
X1012541Y1094751D03*
Y1088058D03*
X1019983Y1111483D03*
Y1104790D03*
Y1098097D03*
X1012541Y1108137D03*
Y1101444D03*
X1019983Y1128215D03*
Y1121522D03*
X1012541Y1124869D03*
Y1114829D03*
X1019983Y1141601D03*
Y1134908D03*
X1012541Y1144948D03*
Y1138255D03*
Y1131562D03*
X1019983Y1158333D03*
Y1148294D03*
X1012541Y1161680D03*
Y1151641D03*
X1019983Y1171719D03*
Y1165026D03*
X1012541Y1175066D03*
Y1168373D03*
X1019983Y1185105D03*
Y1178412D03*
X1012541Y1188452D03*
Y1181759D03*
X1019983Y1208530D03*
Y1201837D03*
Y1195144D03*
X1012541Y1205184D03*
Y1198491D03*
X1019983Y1221916D03*
Y1215223D03*
X1012541Y1225263D03*
Y1218570D03*
Y1211877D03*
X1019983Y1238648D03*
Y1231955D03*
X1012541Y1241995D03*
Y1235302D03*
X1012543Y1257198D03*
X1019983Y1245341D03*
X1012541Y1248688D03*
X1017111Y1273299D03*
X1014111D03*
X1033541Y770144D03*
X1028683Y766798D03*
X1033541Y783530D03*
Y776837D03*
X1028683Y780184D03*
Y773491D03*
X1033541Y800263D03*
Y793570D03*
X1028683Y803609D03*
Y796916D03*
Y790223D03*
X1033541Y820341D03*
Y813648D03*
Y806955D03*
X1028683Y816995D03*
Y810302D03*
X1033541Y830381D03*
X1028683Y833727D03*
Y827034D03*
X1033541Y850459D03*
Y843766D03*
Y837074D03*
X1028683Y847113D03*
Y840420D03*
X1033541Y867192D03*
Y857152D03*
X1028683Y863845D03*
Y853806D03*
X1033541Y880577D03*
Y873885D03*
X1028683Y883924D03*
Y877231D03*
Y870538D03*
X1033541Y893963D03*
Y887270D03*
X1028683Y900656D03*
Y890617D03*
X1033541Y917389D03*
Y910696D03*
Y904003D03*
X1028683Y914042D03*
Y907349D03*
X1033541Y930774D03*
Y924081D03*
X1028683Y927428D03*
Y920735D03*
X1033541Y947507D03*
Y940814D03*
X1028683Y944160D03*
Y937467D03*
X1033541Y964239D03*
Y954200D03*
X1028683Y960892D03*
Y950853D03*
X1033541Y977625D03*
Y970932D03*
X1028683Y980971D03*
Y974278D03*
Y967585D03*
X1033541Y991011D03*
Y984318D03*
X1028683Y987664D03*
X1033541Y1031168D03*
Y1017782D03*
Y1024475D03*
X1028683Y1027822D03*
Y1017782D03*
X1033541Y1044554D03*
Y1037861D03*
X1028683Y1047900D03*
Y1041207D03*
Y1034515D03*
X1033541Y1057940D03*
Y1051247D03*
X1028683Y1061286D03*
Y1054593D03*
X1033541Y1078018D03*
Y1071326D03*
Y1064633D03*
X1028683Y1067979D03*
Y1074672D03*
X1033541Y1094751D03*
Y1088058D03*
X1028683Y1091404D03*
Y1084711D03*
X1033541Y1108137D03*
Y1101444D03*
X1028683Y1111483D03*
Y1104790D03*
Y1098097D03*
X1033541Y1114829D03*
Y1124869D03*
X1028683Y1128215D03*
Y1121522D03*
X1033541Y1144948D03*
Y1138255D03*
Y1131562D03*
X1028683Y1141601D03*
Y1134908D03*
X1033541Y1161680D03*
Y1151641D03*
X1028683Y1158333D03*
Y1148294D03*
X1033541Y1175066D03*
Y1168373D03*
X1028683Y1171719D03*
Y1165026D03*
X1033541Y1188452D03*
Y1181759D03*
X1028683Y1185105D03*
Y1178412D03*
X1033541Y1205184D03*
Y1198491D03*
X1028683Y1208530D03*
Y1201837D03*
Y1195144D03*
X1033541Y1225263D03*
Y1218570D03*
Y1211877D03*
X1028683Y1221916D03*
Y1215223D03*
X1033541Y1241995D03*
Y1235302D03*
X1028683Y1238648D03*
Y1231955D03*
X1033541Y1248688D03*
X1028683Y1245341D03*
X1036588Y1273344D03*
X1022888D03*
X1025688D03*
X1049683Y766798D03*
X1042241Y770144D03*
X1049683Y780184D03*
Y773491D03*
X1042241Y783530D03*
Y776837D03*
X1049683Y803609D03*
Y796916D03*
Y790223D03*
X1042241Y800263D03*
Y793570D03*
X1049683Y816995D03*
Y810302D03*
X1042241Y820341D03*
Y813648D03*
Y806955D03*
X1049683Y833727D03*
Y827034D03*
X1042241Y830381D03*
X1049683Y847113D03*
Y840420D03*
X1042241Y850459D03*
Y843766D03*
Y837074D03*
X1049683Y863845D03*
Y853806D03*
X1042241Y867192D03*
Y857152D03*
X1049683Y883924D03*
Y877231D03*
Y870538D03*
X1042241Y880577D03*
Y873885D03*
X1049683Y900656D03*
Y890617D03*
X1042241Y893963D03*
Y887270D03*
X1049683Y914042D03*
Y907349D03*
X1042241Y917389D03*
Y910696D03*
Y904003D03*
X1049683Y927428D03*
Y920735D03*
X1042241Y930774D03*
Y924081D03*
X1049683Y944160D03*
Y937467D03*
X1042241Y947507D03*
Y940814D03*
X1049683Y960892D03*
Y950853D03*
X1042241Y964239D03*
Y954200D03*
X1049683Y980971D03*
Y974278D03*
Y967585D03*
X1042241Y977625D03*
Y970932D03*
X1049683Y987664D03*
X1042241Y991011D03*
Y984318D03*
X1049683Y1027822D03*
Y1017782D03*
X1042241Y1031168D03*
Y1017782D03*
Y1024475D03*
X1049683Y1047900D03*
Y1041207D03*
Y1034515D03*
X1042241Y1044554D03*
Y1037861D03*
X1049683Y1061286D03*
Y1054593D03*
X1042241Y1057940D03*
Y1051247D03*
X1049683Y1074672D03*
Y1067979D03*
X1042241Y1078018D03*
Y1071326D03*
Y1064633D03*
X1049683Y1091404D03*
Y1084711D03*
X1042241Y1094751D03*
Y1088058D03*
X1049683Y1111483D03*
Y1104790D03*
Y1098097D03*
X1042241Y1108137D03*
Y1101444D03*
Y1114829D03*
X1049683Y1128215D03*
Y1121522D03*
X1042241Y1124869D03*
X1049683Y1141601D03*
Y1134908D03*
X1042241Y1144948D03*
Y1138255D03*
Y1131562D03*
Y1161680D03*
X1049683Y1158333D03*
Y1148294D03*
X1042241Y1151641D03*
X1049683Y1171719D03*
Y1165026D03*
X1042241Y1175066D03*
Y1168373D03*
X1049683Y1185105D03*
Y1178412D03*
X1042241Y1188452D03*
Y1181759D03*
X1049683Y1208530D03*
Y1201837D03*
Y1195144D03*
X1042241Y1205184D03*
Y1198491D03*
X1049683Y1215223D03*
Y1221916D03*
X1042241Y1225263D03*
Y1218570D03*
Y1211877D03*
X1049683Y1238648D03*
Y1231955D03*
X1042241Y1241995D03*
Y1235302D03*
X1042331Y1257488D03*
X1049683Y1245341D03*
X1042241Y1248688D03*
X1052588Y1273344D03*
X1039388D03*
X1063241Y770144D03*
X1058383Y766798D03*
X1063241Y783530D03*
Y776837D03*
X1058383Y780184D03*
Y773491D03*
X1063241Y800263D03*
Y793570D03*
X1058383Y803609D03*
Y796916D03*
Y790223D03*
X1063241Y820341D03*
Y813648D03*
Y806955D03*
X1058383Y816995D03*
Y810302D03*
X1063241Y830381D03*
X1058383Y833727D03*
Y827034D03*
X1063241Y850459D03*
Y843766D03*
Y837074D03*
X1058383Y847113D03*
Y840420D03*
X1063241Y867192D03*
Y857152D03*
X1058383Y863845D03*
Y853806D03*
X1063241Y880577D03*
Y873885D03*
X1058383Y883924D03*
Y877231D03*
Y870538D03*
X1063241Y893963D03*
Y887270D03*
X1058383Y900656D03*
Y890617D03*
X1063241Y917389D03*
Y910696D03*
Y904003D03*
X1058383Y914042D03*
Y907349D03*
X1063241Y930774D03*
Y924081D03*
X1058383Y927428D03*
Y920735D03*
X1063241Y947507D03*
Y940814D03*
X1058383Y944160D03*
Y937467D03*
X1063241Y964239D03*
Y954200D03*
X1058383Y960892D03*
Y950853D03*
X1063241Y977625D03*
Y970932D03*
X1058383Y980971D03*
Y974278D03*
Y967585D03*
X1063241Y991011D03*
Y984318D03*
X1058383Y987664D03*
X1063241Y1031168D03*
Y1024475D03*
Y1017782D03*
X1058383Y1027822D03*
Y1017782D03*
X1063241Y1044554D03*
Y1037861D03*
X1058383Y1047900D03*
Y1041207D03*
Y1034515D03*
X1063241Y1057940D03*
Y1051247D03*
X1058383Y1061286D03*
Y1054593D03*
X1063241Y1078018D03*
Y1071326D03*
Y1064633D03*
X1058383Y1074672D03*
Y1067979D03*
X1063241Y1094751D03*
Y1088058D03*
X1058383Y1091404D03*
Y1084711D03*
X1063241Y1108137D03*
Y1101444D03*
X1058383Y1111483D03*
Y1104790D03*
Y1098097D03*
X1063241Y1124869D03*
Y1114829D03*
X1058383Y1128215D03*
Y1121522D03*
X1063241Y1144948D03*
Y1138255D03*
Y1131562D03*
X1058383Y1141601D03*
Y1134908D03*
X1063241Y1161680D03*
Y1151641D03*
X1058383Y1158333D03*
Y1148294D03*
X1063241Y1175066D03*
Y1168373D03*
X1058383Y1171719D03*
Y1165026D03*
X1063241Y1188452D03*
Y1181759D03*
X1058383Y1185105D03*
Y1178412D03*
X1063241Y1205184D03*
Y1198491D03*
X1058383Y1208530D03*
Y1201837D03*
Y1195144D03*
X1063241Y1225263D03*
Y1218570D03*
Y1211877D03*
X1058383Y1215223D03*
Y1221916D03*
X1063241Y1241995D03*
Y1235302D03*
X1058383Y1238648D03*
Y1231955D03*
X1063241Y1248688D03*
X1058383Y1245341D03*
X1069088Y1273344D03*
X1066288D03*
X1055388D03*
X1079383Y766798D03*
X1071941Y770144D03*
X1079383Y780184D03*
Y773491D03*
X1071941Y783530D03*
Y776837D03*
X1079383Y803609D03*
Y796916D03*
Y790223D03*
X1071941Y800263D03*
Y793570D03*
X1079383Y816995D03*
Y810302D03*
X1071941Y820341D03*
Y813648D03*
Y806955D03*
X1079383Y833727D03*
Y827034D03*
X1071941Y830381D03*
X1079383Y847113D03*
Y840420D03*
X1071941Y850459D03*
Y843766D03*
Y837074D03*
X1079383Y863845D03*
Y853806D03*
X1071941Y867192D03*
Y857152D03*
X1079383Y883924D03*
Y877231D03*
Y870538D03*
X1071941Y880577D03*
Y873885D03*
X1079383Y900656D03*
Y890617D03*
X1071941Y893963D03*
Y887270D03*
X1079383Y914042D03*
Y907349D03*
X1071941Y917389D03*
Y910696D03*
Y904003D03*
X1079383Y927428D03*
Y920735D03*
X1071941Y930774D03*
Y924081D03*
X1079383Y944160D03*
Y937467D03*
X1071941Y947507D03*
Y940814D03*
X1079383Y960892D03*
Y950853D03*
X1071941Y964239D03*
Y954200D03*
X1079383Y980971D03*
Y974278D03*
Y967585D03*
X1071941Y977625D03*
Y970932D03*
X1079383Y987664D03*
X1071941Y991011D03*
Y984318D03*
X1079383Y1027822D03*
Y1017782D03*
X1071941Y1031168D03*
Y1024475D03*
Y1017782D03*
X1079383Y1047900D03*
Y1041207D03*
Y1034515D03*
X1071941Y1044554D03*
Y1037861D03*
X1079383Y1061286D03*
Y1054593D03*
X1071941Y1057940D03*
Y1051247D03*
X1079383Y1074672D03*
Y1067979D03*
X1071941Y1078018D03*
Y1071326D03*
Y1064633D03*
X1079383Y1091404D03*
Y1084711D03*
X1071941Y1094751D03*
Y1088058D03*
X1079383Y1111483D03*
Y1104790D03*
Y1098097D03*
X1071941Y1108137D03*
Y1101444D03*
X1079383Y1128215D03*
Y1121522D03*
X1071941Y1124869D03*
Y1114829D03*
X1079383Y1141601D03*
Y1134908D03*
X1071941Y1144948D03*
Y1138255D03*
Y1131562D03*
X1079383Y1158333D03*
Y1148294D03*
X1071941Y1161680D03*
Y1151641D03*
X1079383Y1171719D03*
Y1165026D03*
X1071941Y1175066D03*
Y1168373D03*
X1079383Y1185105D03*
Y1178412D03*
X1071941Y1188452D03*
Y1181759D03*
X1079383Y1208530D03*
Y1201837D03*
Y1195144D03*
X1071941Y1205184D03*
Y1198491D03*
X1079383Y1221916D03*
Y1215223D03*
X1071941Y1225263D03*
Y1218570D03*
Y1211877D03*
X1079383Y1238648D03*
Y1231955D03*
X1071941Y1241995D03*
Y1235302D03*
X1071991Y1257262D03*
X1079383Y1245341D03*
X1071941Y1248688D03*
X1085088Y1273344D03*
X1082288D03*
X1092941Y770144D03*
X1101641D03*
X1088083Y766798D03*
X1092941Y783530D03*
X1101641D03*
X1092941Y776837D03*
X1101641D03*
X1088083Y780184D03*
Y773491D03*
X1101641Y800263D03*
X1092941D03*
X1101641Y793570D03*
X1092941D03*
X1088083Y803609D03*
Y796916D03*
Y790223D03*
X1101641Y820341D03*
X1092941D03*
X1101641Y813648D03*
X1092941D03*
X1101641Y806955D03*
X1092941D03*
X1088083Y816995D03*
Y810302D03*
X1101641Y830381D03*
X1092941D03*
X1088083Y833727D03*
Y827034D03*
X1101641Y850459D03*
X1092941D03*
X1101641Y843766D03*
X1092941D03*
X1101641Y837074D03*
X1092941D03*
X1088083Y847113D03*
Y840420D03*
X1101641Y867192D03*
X1092941D03*
X1101641Y857152D03*
X1092941D03*
X1088083Y863845D03*
Y853806D03*
X1101641Y880577D03*
X1092941D03*
X1101641Y873885D03*
X1092941D03*
X1088083Y883924D03*
Y877231D03*
Y870538D03*
X1101641Y893963D03*
X1092941D03*
X1101641Y887270D03*
X1092941D03*
X1088083Y900656D03*
Y890617D03*
X1101641Y917389D03*
X1092941D03*
X1101641Y910696D03*
X1092941D03*
X1101641Y904003D03*
X1092941D03*
X1088083Y914042D03*
Y907349D03*
X1101641Y930774D03*
X1092941D03*
X1101641Y924081D03*
X1092941D03*
X1088083Y927428D03*
Y920735D03*
X1101641Y947507D03*
X1092941D03*
X1101641Y940814D03*
X1092941D03*
X1088083Y944160D03*
Y937467D03*
X1101641Y964239D03*
X1092941D03*
X1101641Y954200D03*
X1092941D03*
X1088083Y960892D03*
Y950853D03*
X1101641Y977625D03*
X1092941D03*
X1101641Y970932D03*
X1092941D03*
X1088083Y980971D03*
Y974278D03*
Y967585D03*
X1101641Y991011D03*
X1092941D03*
X1101641Y984318D03*
X1092941D03*
X1088083Y987664D03*
X1101641Y1031168D03*
X1092941D03*
X1101641Y1024475D03*
X1092941D03*
X1101641Y1017782D03*
X1092941D03*
X1088083Y1027822D03*
Y1017782D03*
X1101641Y1044554D03*
X1092941D03*
X1101641Y1037861D03*
X1092941D03*
X1088083Y1047900D03*
Y1041207D03*
Y1034515D03*
X1101641Y1057940D03*
X1092941D03*
X1101641Y1051247D03*
X1092941D03*
X1088083Y1061286D03*
Y1054593D03*
X1101641Y1078018D03*
X1092941D03*
X1101641Y1071326D03*
X1092941D03*
X1101641Y1064633D03*
X1092941D03*
X1088083Y1074672D03*
Y1067979D03*
X1101641Y1094751D03*
X1092941D03*
X1101641Y1088058D03*
X1092941D03*
X1088083Y1091404D03*
Y1084711D03*
X1101641Y1108137D03*
X1092941D03*
X1101641Y1101444D03*
X1092941D03*
X1088083Y1111483D03*
Y1104790D03*
Y1098097D03*
X1101641Y1124869D03*
X1092941D03*
X1101641Y1114829D03*
X1092941D03*
X1088083Y1128215D03*
Y1121522D03*
X1101641Y1144948D03*
X1092941D03*
X1101641Y1138255D03*
X1092941D03*
X1101641Y1131562D03*
X1092941D03*
X1088083Y1141601D03*
Y1134908D03*
X1092941Y1161680D03*
X1101641D03*
Y1151641D03*
X1092941D03*
X1088083Y1158333D03*
Y1148294D03*
X1101641Y1175066D03*
X1092941D03*
X1101641Y1168373D03*
X1092941D03*
X1088083Y1171719D03*
Y1165026D03*
X1101641Y1181759D03*
X1092941D03*
Y1188452D03*
X1101641D03*
X1088083Y1185105D03*
Y1178412D03*
X1092941Y1205184D03*
X1101641D03*
X1092941Y1198491D03*
X1101641D03*
X1088083Y1208530D03*
Y1201837D03*
Y1195144D03*
X1101641Y1225263D03*
X1092941D03*
X1101641Y1218570D03*
X1092941D03*
Y1211877D03*
X1101641D03*
X1088083Y1221916D03*
Y1215223D03*
X1101641Y1241995D03*
X1092941D03*
X1101641Y1235302D03*
X1092941D03*
X1088083Y1238648D03*
Y1231955D03*
X1101554Y1257102D03*
X1101641Y1248688D03*
X1092941D03*
X1088083Y1245341D03*
X1098788Y1273344D03*
X1095988D03*
X1109083Y766798D03*
X1117783D03*
Y780184D03*
X1109083D03*
X1117783Y773491D03*
X1109083D03*
X1117783Y803609D03*
X1109083D03*
X1117783Y796916D03*
X1109083D03*
Y790223D03*
X1117783D03*
Y816995D03*
X1109083D03*
X1117783Y810302D03*
X1109083D03*
X1117783Y833727D03*
X1109083D03*
X1117783Y827034D03*
X1109083D03*
X1117783Y847113D03*
X1109083D03*
X1117783Y840420D03*
X1109083D03*
X1117783Y863845D03*
X1109083D03*
X1117783Y853806D03*
X1109083D03*
X1117783Y883924D03*
X1109083D03*
X1117783Y877231D03*
X1109083D03*
X1117783Y870538D03*
X1109083D03*
X1117783Y900656D03*
X1109083D03*
X1117783Y890617D03*
X1109083D03*
X1117783Y914042D03*
X1109083D03*
X1117783Y907349D03*
X1109083D03*
X1117783Y927428D03*
X1109083D03*
X1117783Y920735D03*
X1109083D03*
X1117783Y944160D03*
X1109083D03*
X1117783Y937467D03*
X1109083D03*
X1117783Y960892D03*
X1109083D03*
X1117783Y950853D03*
X1109083D03*
X1117783Y980971D03*
X1109083D03*
X1117783Y974278D03*
X1109083D03*
X1117783Y967585D03*
X1109083D03*
X1117783Y987664D03*
X1109083D03*
X1117783Y1027822D03*
X1109083D03*
X1117783Y1017782D03*
X1109083D03*
X1117783Y1047900D03*
X1109083D03*
X1117783Y1041207D03*
X1109083D03*
X1117783Y1034515D03*
X1109083D03*
X1117783Y1061286D03*
X1109083D03*
X1117783Y1054593D03*
X1109083D03*
X1117783Y1074672D03*
X1109083D03*
X1117783Y1067979D03*
X1109083D03*
X1117783Y1091404D03*
X1109083D03*
X1117783Y1084711D03*
X1109083D03*
X1117783Y1111483D03*
X1109083D03*
X1117783Y1104790D03*
X1109083D03*
X1117783Y1098097D03*
X1109083D03*
X1117783Y1128215D03*
X1109083D03*
X1117783Y1121522D03*
X1109083D03*
X1117783Y1141601D03*
X1109083D03*
X1117783Y1134908D03*
X1109083D03*
X1117783Y1158333D03*
X1109083D03*
X1117783Y1148294D03*
X1109083D03*
X1117783Y1171719D03*
X1109083D03*
X1117783Y1165026D03*
X1109083D03*
X1117783Y1185105D03*
X1109083D03*
X1117783Y1178412D03*
X1109083D03*
X1117783Y1208530D03*
X1109083D03*
X1117783Y1201837D03*
X1109083D03*
X1117783Y1195144D03*
X1109083D03*
X1117783Y1221916D03*
X1109083D03*
X1117783Y1215223D03*
X1109083D03*
X1117783Y1238648D03*
X1109083D03*
X1117783Y1231955D03*
X1109083D03*
X1117783Y1245341D03*
X1109083D03*
X1111988Y1273344D03*
X1114788D03*
X1131341Y770144D03*
X1122641D03*
X1131341Y783530D03*
X1122641D03*
X1131341Y776837D03*
X1122641D03*
X1131341Y800263D03*
X1122641D03*
X1131341Y793570D03*
X1122641D03*
X1131341Y820341D03*
X1122641D03*
X1131341Y813648D03*
X1122641D03*
X1131341Y806955D03*
X1122641D03*
X1131341Y830381D03*
X1122641D03*
X1131341Y850459D03*
X1122641D03*
X1131341Y843766D03*
X1122641D03*
X1131341Y837074D03*
X1122641D03*
X1131341Y867192D03*
X1122641D03*
X1131341Y857152D03*
X1122641D03*
X1131341Y880577D03*
X1122641D03*
X1131341Y873885D03*
X1122641D03*
X1131341Y893963D03*
X1122641D03*
X1131341Y887270D03*
X1122641D03*
X1131341Y917389D03*
X1122641D03*
X1131341Y910696D03*
X1122641D03*
X1131341Y904003D03*
X1122641D03*
X1131341Y930774D03*
X1122641D03*
X1131341Y924081D03*
X1122641D03*
Y947507D03*
X1131341D03*
Y940814D03*
X1122641D03*
X1131341Y964239D03*
X1122641D03*
X1131341Y954200D03*
X1122641D03*
X1131341Y977625D03*
X1122641D03*
X1131341Y970932D03*
X1122641D03*
X1131341Y991011D03*
X1122641D03*
X1131341Y984318D03*
X1122641D03*
X1131341Y1031168D03*
X1122641D03*
X1131341Y1024475D03*
X1122641D03*
X1131341Y1017782D03*
X1122641D03*
X1131341Y1044554D03*
X1122641D03*
X1131341Y1037861D03*
X1122641D03*
X1131341Y1057940D03*
X1122641D03*
X1131341Y1051247D03*
X1122641D03*
X1131341Y1078018D03*
X1122641D03*
X1131341Y1071326D03*
X1122641D03*
X1131341Y1064633D03*
X1122641D03*
X1131341Y1094751D03*
X1122641D03*
X1131341Y1088058D03*
X1122641D03*
X1131341Y1108137D03*
X1122641D03*
X1131341Y1101444D03*
X1122641D03*
X1131341Y1124869D03*
X1122641D03*
X1131341Y1114829D03*
X1122641D03*
X1131341Y1144948D03*
X1122641D03*
X1131341Y1138255D03*
X1122641D03*
X1131341Y1131562D03*
X1122641D03*
X1131341Y1161680D03*
X1122641D03*
X1131341Y1151641D03*
X1122641D03*
X1131341Y1175066D03*
X1122641D03*
X1131341Y1168373D03*
X1122641D03*
X1131341Y1188452D03*
X1122641D03*
X1131341Y1181759D03*
X1122641D03*
X1131341Y1205184D03*
X1122641D03*
X1131341Y1198491D03*
X1122641D03*
X1131341Y1225263D03*
X1122641D03*
X1131341Y1218570D03*
X1122641D03*
X1131341Y1211877D03*
X1122641D03*
X1131341Y1241995D03*
X1122641D03*
X1131341Y1235302D03*
X1122641D03*
X1131434Y1257291D03*
X1122641Y1248688D03*
X1131341D03*
X1126188Y1273344D03*
X1128988D03*
X1152341Y770144D03*
X1147483Y766798D03*
X1138783D03*
X1152341Y783530D03*
Y776837D03*
X1147483Y780184D03*
X1138783D03*
Y773491D03*
X1147483D03*
X1152341Y800263D03*
X1147483Y803609D03*
X1138783D03*
X1152341Y793570D03*
X1147483Y796916D03*
X1138783D03*
X1147483Y790223D03*
X1138783D03*
X1152341Y820341D03*
X1147483Y816995D03*
X1138783D03*
X1152341Y813648D03*
Y806955D03*
X1147483Y810302D03*
X1138783D03*
X1147483Y833727D03*
X1138783D03*
X1152341Y830381D03*
X1147483Y827034D03*
X1138783D03*
X1152341Y850459D03*
Y843766D03*
Y837074D03*
X1147483Y847113D03*
X1138783D03*
X1147483Y840420D03*
X1138783D03*
X1152341Y867192D03*
Y857152D03*
X1147483Y863845D03*
X1138783D03*
X1147483Y853806D03*
X1138783D03*
X1152341Y880577D03*
Y873885D03*
X1147483Y883924D03*
X1138783D03*
X1147483Y877231D03*
X1138783D03*
X1147483Y870538D03*
X1138783D03*
X1152341Y893963D03*
Y887270D03*
X1138783Y900656D03*
X1147483D03*
X1138783Y890617D03*
X1147483D03*
X1152341Y917389D03*
Y910696D03*
Y904003D03*
X1147483Y914042D03*
X1138783D03*
X1147483Y907349D03*
X1138783D03*
X1152341Y930774D03*
Y924081D03*
X1147483Y927428D03*
X1138783D03*
X1147483Y920735D03*
X1138783D03*
X1152341Y947507D03*
Y940814D03*
X1147483Y944160D03*
X1138783D03*
X1147483Y937467D03*
X1138783D03*
X1152341Y964239D03*
Y954200D03*
X1147483Y960892D03*
X1138783D03*
X1147483Y950853D03*
X1138783D03*
X1152341Y977625D03*
Y970932D03*
X1147483Y980971D03*
X1138783D03*
X1147483Y974278D03*
X1138783D03*
X1147483Y967585D03*
X1138783D03*
X1152341Y991011D03*
Y984318D03*
X1147483Y987664D03*
X1138783D03*
X1152341Y1031168D03*
Y1024475D03*
Y1017782D03*
X1147483Y1027822D03*
X1138783D03*
X1147483Y1017782D03*
X1138783D03*
X1152341Y1044554D03*
Y1037861D03*
X1138783Y1047900D03*
X1147483D03*
Y1041207D03*
X1138783D03*
X1147483Y1034515D03*
X1138783D03*
X1152341Y1057940D03*
Y1051247D03*
X1147483Y1061286D03*
X1138783D03*
X1147483Y1054593D03*
X1138783D03*
X1152341Y1078018D03*
Y1071326D03*
Y1064633D03*
X1147483Y1074672D03*
X1138783D03*
X1147483Y1067979D03*
X1138783D03*
X1152341Y1094751D03*
Y1088058D03*
X1147483Y1091404D03*
X1138783D03*
X1147483Y1084711D03*
X1138783D03*
X1152341Y1108137D03*
Y1101444D03*
X1147483Y1111483D03*
X1138783D03*
X1147483Y1104790D03*
X1138783D03*
X1147483Y1098097D03*
X1138783D03*
X1152341Y1124869D03*
Y1114829D03*
X1147483Y1128215D03*
X1138783D03*
X1147483Y1121522D03*
X1138783D03*
X1152341Y1144948D03*
Y1138255D03*
Y1131562D03*
X1147483Y1141601D03*
X1138783D03*
X1147483Y1134908D03*
X1138783D03*
X1152341Y1161680D03*
Y1151641D03*
X1147483Y1158333D03*
X1138783D03*
Y1148294D03*
X1147483D03*
X1152341Y1175066D03*
Y1168373D03*
X1147483Y1171719D03*
X1138783D03*
X1147483Y1165026D03*
X1138783D03*
X1152341Y1188452D03*
Y1181759D03*
X1147483Y1185105D03*
X1138783D03*
X1147483Y1178412D03*
X1138783D03*
X1152341Y1205184D03*
Y1198491D03*
X1147483Y1208530D03*
X1138783D03*
X1147483Y1201837D03*
X1138783D03*
X1147483Y1195144D03*
X1138783D03*
X1152341Y1225263D03*
Y1218570D03*
Y1211877D03*
X1147483Y1221916D03*
X1138783D03*
X1147483Y1215223D03*
X1138783D03*
X1152341Y1241995D03*
Y1235302D03*
X1147483Y1238648D03*
X1138783D03*
X1147483Y1231955D03*
X1138783D03*
X1152341Y1248688D03*
X1147483Y1245341D03*
X1138783D03*
X1152381Y1269684D03*
X1147681D03*
X1138201Y1270277D03*
X1168483Y766798D03*
X1161041Y770144D03*
X1168483Y780184D03*
Y773491D03*
X1161041Y783530D03*
Y776837D03*
X1168483Y803609D03*
Y796916D03*
Y790223D03*
X1161041Y800263D03*
Y793570D03*
X1168483Y816995D03*
Y810302D03*
X1161041Y820341D03*
Y813648D03*
Y806955D03*
X1168483Y833727D03*
X1167633Y827034D03*
X1161041Y830381D03*
X1168483Y847113D03*
Y840420D03*
X1161041Y850459D03*
Y843766D03*
Y837074D03*
X1167633Y863845D03*
X1161041Y867192D03*
X1168483Y853806D03*
X1161041Y857152D03*
X1168483Y883924D03*
Y877231D03*
Y870538D03*
X1161041Y880577D03*
Y873885D03*
X1168483Y900656D03*
Y890617D03*
X1161041Y893963D03*
Y887270D03*
X1168483Y914042D03*
Y907349D03*
X1161041Y917389D03*
Y910696D03*
Y904003D03*
X1167633Y927428D03*
X1168483Y920735D03*
X1161041Y930774D03*
Y924081D03*
X1168483Y937467D03*
Y944160D03*
X1161041Y947507D03*
Y940814D03*
X1168483Y960892D03*
Y950853D03*
X1161041Y964239D03*
Y954200D03*
X1168483Y974278D03*
Y980971D03*
Y967585D03*
X1161041Y977625D03*
Y970932D03*
X1168483Y987664D03*
X1161041Y991011D03*
Y984318D03*
X1168483Y1027822D03*
Y1017782D03*
X1161041Y1031168D03*
Y1024475D03*
Y1017782D03*
X1168483Y1047900D03*
Y1041207D03*
Y1034515D03*
X1161041Y1044554D03*
Y1037861D03*
X1168483Y1054593D03*
Y1061286D03*
X1161041Y1057940D03*
Y1051247D03*
X1168483Y1074672D03*
Y1067979D03*
X1161041Y1078018D03*
Y1071326D03*
Y1064633D03*
X1168483Y1091404D03*
X1167633Y1084711D03*
X1161041Y1094751D03*
Y1088058D03*
X1168483Y1111483D03*
Y1104790D03*
Y1098097D03*
X1161041Y1108137D03*
Y1101444D03*
X1168483Y1128215D03*
Y1121522D03*
X1161041Y1124869D03*
Y1114829D03*
X1168483Y1141601D03*
Y1134908D03*
X1161041Y1144948D03*
Y1138255D03*
Y1131562D03*
X1167633Y1158333D03*
X1168483Y1148294D03*
X1161041Y1161680D03*
Y1151641D03*
X1168483Y1171719D03*
Y1165026D03*
X1161041Y1175066D03*
Y1168373D03*
X1168483Y1185105D03*
Y1178412D03*
X1161041Y1188452D03*
Y1181759D03*
X1168483Y1208530D03*
Y1201837D03*
Y1195144D03*
X1161041Y1205184D03*
Y1198491D03*
X1168483Y1221916D03*
Y1215223D03*
X1161041Y1225263D03*
Y1218570D03*
Y1211877D03*
X1168483Y1238648D03*
X1167633Y1231955D03*
X1161041Y1241995D03*
Y1235302D03*
X1161065Y1258871D03*
X1168483Y1245341D03*
X1161041Y1248688D03*
X1161781Y1269684D03*
X1182041Y770144D03*
X1177183Y766798D03*
X1182041Y783530D03*
Y776837D03*
X1177183Y780184D03*
Y773491D03*
X1182041Y800263D03*
Y793570D03*
X1177183Y803609D03*
Y796916D03*
Y790223D03*
X1182041Y813648D03*
Y806955D03*
X1181191Y820341D03*
X1177183Y816995D03*
Y810302D03*
X1181191Y830381D03*
X1177183Y833727D03*
Y827034D03*
X1182041Y850459D03*
Y837074D03*
Y843766D03*
X1177183Y847113D03*
Y840420D03*
X1181191Y867192D03*
X1177183Y863845D03*
X1181191Y857152D03*
X1177183Y853806D03*
X1182041Y873885D03*
Y880577D03*
X1177183Y883924D03*
Y877231D03*
Y870538D03*
X1182041Y893963D03*
Y887270D03*
X1177183Y900656D03*
Y890617D03*
X1182041Y917389D03*
Y910696D03*
Y904003D03*
X1177183Y914042D03*
Y907349D03*
X1181191Y930774D03*
Y924081D03*
X1177183Y927428D03*
Y920735D03*
X1182041Y940814D03*
Y947507D03*
X1177183Y937467D03*
Y944160D03*
X1182041Y964239D03*
Y954200D03*
X1177183Y960892D03*
Y950853D03*
X1182041Y970932D03*
Y977625D03*
X1177183Y974278D03*
Y980971D03*
Y967585D03*
X1182041Y991011D03*
Y984318D03*
X1177183Y987664D03*
X1182041Y1031168D03*
Y1017782D03*
Y1024475D03*
X1177183Y1027822D03*
Y1017782D03*
X1182041Y1044554D03*
Y1037861D03*
X1177183Y1047900D03*
Y1041207D03*
Y1034515D03*
X1182041Y1057940D03*
Y1051247D03*
X1177183Y1054593D03*
Y1061286D03*
X1181191Y1078018D03*
X1182041Y1071326D03*
Y1064633D03*
X1177183Y1074672D03*
Y1067979D03*
X1182041Y1094751D03*
X1181191Y1088058D03*
X1177183Y1091404D03*
Y1084711D03*
X1182041Y1101444D03*
Y1108137D03*
X1177183Y1111483D03*
Y1104790D03*
Y1098097D03*
X1182041Y1114829D03*
Y1124869D03*
X1177183Y1128215D03*
Y1121522D03*
X1182041Y1144948D03*
Y1138255D03*
Y1131562D03*
X1177183Y1141601D03*
Y1134908D03*
X1181191Y1161680D03*
Y1151641D03*
X1177183Y1158333D03*
Y1148294D03*
X1182041Y1168373D03*
Y1175066D03*
X1177183Y1171719D03*
Y1165026D03*
X1182041Y1188452D03*
Y1181759D03*
X1177183Y1185105D03*
Y1178412D03*
X1182041Y1205184D03*
Y1198491D03*
X1177183Y1208530D03*
Y1201837D03*
Y1195144D03*
X1181191Y1225263D03*
X1182041Y1211877D03*
Y1218570D03*
X1177183Y1221916D03*
Y1215223D03*
X1182041Y1241995D03*
X1181191Y1235302D03*
X1177183Y1238648D03*
Y1231955D03*
X1182041Y1248688D03*
X1177183Y1245341D03*
X1176867Y1270029D03*
X1198183Y766798D03*
X1190741Y770144D03*
X1198183Y780184D03*
Y773491D03*
X1190741Y783530D03*
Y776837D03*
X1198183Y803609D03*
Y796916D03*
Y790223D03*
X1190741Y800263D03*
Y793570D03*
X1197333Y816995D03*
X1198183Y810302D03*
X1190741Y813648D03*
Y806955D03*
X1191591Y820341D03*
X1198183Y833727D03*
X1197333Y827034D03*
X1191591Y830381D03*
X1198183Y847113D03*
Y840420D03*
X1190741Y850459D03*
Y837074D03*
Y843766D03*
X1197333Y863845D03*
X1191591Y867192D03*
X1198183Y853806D03*
X1191591Y857152D03*
X1198183Y877231D03*
X1197333Y870538D03*
X1198183Y883924D03*
X1190741Y873885D03*
Y880577D03*
X1198183Y900656D03*
Y890617D03*
X1190741Y893963D03*
Y887270D03*
X1198183Y914042D03*
Y907349D03*
X1190741Y917389D03*
Y910696D03*
Y904003D03*
X1197383Y927428D03*
X1198183Y920735D03*
X1191591Y930774D03*
Y924081D03*
X1198183Y944160D03*
X1197333Y937467D03*
X1190741Y940814D03*
Y947507D03*
X1198183Y960892D03*
Y950853D03*
X1190741Y964239D03*
Y954200D03*
X1198183Y980971D03*
Y974278D03*
Y967585D03*
X1190741Y970932D03*
Y977625D03*
X1198183Y987664D03*
X1190741Y991011D03*
Y984318D03*
X1198183Y1027822D03*
Y1017782D03*
X1190741Y1031168D03*
Y1017782D03*
Y1024475D03*
X1198183Y1047900D03*
Y1041207D03*
Y1034515D03*
X1190741Y1044554D03*
Y1037861D03*
X1198183Y1054593D03*
Y1061286D03*
X1190741Y1057940D03*
Y1051247D03*
X1197333Y1074672D03*
X1198183Y1067979D03*
X1191591Y1078018D03*
X1190741Y1071326D03*
Y1064633D03*
X1198183Y1091404D03*
X1197333Y1084711D03*
X1190741Y1094751D03*
X1191591Y1088058D03*
X1198183Y1111483D03*
Y1098097D03*
Y1104790D03*
X1190741Y1101444D03*
Y1108137D03*
X1198183Y1128215D03*
Y1121522D03*
X1190741Y1114829D03*
Y1124869D03*
X1198183Y1141601D03*
X1197333Y1134908D03*
X1190741Y1144948D03*
Y1138255D03*
Y1131562D03*
X1198183Y1158333D03*
X1197333Y1148294D03*
X1191591Y1161680D03*
Y1151641D03*
X1198183Y1165026D03*
Y1171719D03*
X1190741Y1168373D03*
Y1175066D03*
X1198183Y1185105D03*
Y1178412D03*
X1190741Y1188452D03*
Y1181759D03*
X1198183Y1208530D03*
Y1201837D03*
Y1195144D03*
X1190741Y1205184D03*
Y1198491D03*
X1198183Y1221916D03*
Y1215223D03*
X1191591Y1225263D03*
X1190741Y1211877D03*
Y1218570D03*
X1197333Y1238648D03*
Y1231955D03*
X1190741Y1241995D03*
X1191591Y1235302D03*
X1198183Y1245341D03*
X1190966Y1258711D03*
X1190741Y1248688D03*
X1191538Y1270004D03*
X1194572Y1578182D03*
Y1590094D03*
X1199872Y1614292D03*
Y1602380D03*
X1211741Y770144D03*
X1206883Y766798D03*
X1211741Y783530D03*
Y776837D03*
X1206883Y780184D03*
Y773491D03*
X1211741Y800263D03*
Y793570D03*
X1206883Y803609D03*
Y796916D03*
Y790223D03*
X1210891Y820341D03*
Y813648D03*
X1211741Y806955D03*
X1207148Y817554D03*
X1206883Y810302D03*
X1211741Y830381D03*
X1206883Y833727D03*
X1207733Y827034D03*
X1211741Y850459D03*
Y837074D03*
Y843766D03*
X1206883Y847113D03*
Y840420D03*
X1210891Y867492D03*
X1207733Y863845D03*
X1210891Y857152D03*
X1206883Y853806D03*
X1211741Y874185D03*
Y880577D03*
X1206883Y877231D03*
X1207201Y871084D03*
X1206883Y883924D03*
X1211741Y893963D03*
Y887270D03*
X1206883Y900656D03*
Y890617D03*
X1211741Y917389D03*
Y910696D03*
Y904003D03*
X1206883Y914042D03*
Y907349D03*
X1211741Y930774D03*
Y924081D03*
X1207683Y927428D03*
X1206883Y920735D03*
X1211741Y947507D03*
X1211001Y940814D03*
X1206883Y944660D03*
X1207733Y937467D03*
X1211741Y964239D03*
Y954200D03*
X1206883Y960892D03*
Y950853D03*
X1211741Y977625D03*
Y970932D03*
X1206883Y980971D03*
Y974278D03*
Y967585D03*
X1211741Y991011D03*
X1206883Y987664D03*
X1211741Y984318D03*
Y1031168D03*
X1206883Y1027822D03*
Y1017782D03*
X1211741D03*
Y1024475D03*
Y1044554D03*
Y1037861D03*
X1206883Y1047900D03*
Y1041207D03*
Y1034515D03*
X1211741Y1051247D03*
Y1057940D03*
X1206883Y1054593D03*
Y1061286D03*
X1210891Y1078018D03*
X1211741Y1064633D03*
Y1071326D03*
X1207733Y1074672D03*
X1206883Y1067979D03*
X1211741Y1094751D03*
X1210891Y1088058D03*
X1206883Y1091404D03*
Y1084711D03*
X1211741Y1108137D03*
Y1101444D03*
X1206883Y1111483D03*
Y1098097D03*
Y1104790D03*
X1210891Y1124869D03*
X1211741Y1114829D03*
X1206883Y1128215D03*
Y1121522D03*
X1211741Y1144948D03*
Y1138255D03*
X1210891Y1131562D03*
X1206883Y1141601D03*
X1207733Y1134908D03*
X1211741Y1151641D03*
Y1161680D03*
X1206883Y1158333D03*
X1207733Y1148294D03*
X1211741Y1175066D03*
Y1168373D03*
X1206883Y1165026D03*
Y1171719D03*
X1211741Y1188452D03*
Y1181759D03*
X1206883Y1185105D03*
Y1178412D03*
X1211741Y1205184D03*
Y1198491D03*
X1206883Y1208530D03*
Y1201837D03*
Y1195144D03*
X1210891Y1225263D03*
X1211741Y1218570D03*
Y1211877D03*
X1206883Y1221916D03*
Y1215223D03*
X1211741Y1241995D03*
X1211328Y1234977D03*
X1207733Y1238648D03*
Y1231955D03*
X1206883Y1245341D03*
X1211741Y1248688D03*
X1204608Y1273119D03*
X1202043Y1273123D03*
X1202372Y1578182D03*
X1214432D03*
X1206632D03*
X1202372Y1590094D03*
X1214432D03*
X1206632D03*
X1207672Y1602380D03*
Y1614292D03*
X1211932D03*
Y1602380D03*
X1227883Y766798D03*
X1220441Y770144D03*
X1227883Y780184D03*
Y773491D03*
X1220441Y783530D03*
Y776837D03*
X1227883Y803609D03*
Y796916D03*
Y790223D03*
X1220441Y800263D03*
Y793570D03*
X1227033Y816995D03*
X1227883Y810302D03*
X1221291Y820341D03*
Y813648D03*
X1220441Y806955D03*
X1227883Y833727D03*
X1227033Y827034D03*
X1220441Y830381D03*
X1227883Y847113D03*
Y840420D03*
X1220441Y850459D03*
Y837074D03*
Y843766D03*
X1227033Y863845D03*
X1221291Y867192D03*
X1227033Y853806D03*
X1221291Y857152D03*
X1227883Y870538D03*
Y883924D03*
Y877231D03*
X1220441Y873885D03*
Y880577D03*
X1227033Y900656D03*
X1227883Y890617D03*
X1220441Y893963D03*
Y887270D03*
X1227883Y914042D03*
Y907349D03*
X1220441Y917389D03*
Y910696D03*
Y904003D03*
X1227033Y927428D03*
X1227883Y920735D03*
X1221291Y930774D03*
X1220441Y924081D03*
X1227883Y944160D03*
X1227033Y937467D03*
X1220441Y947507D03*
X1221291Y940814D03*
X1227883Y960892D03*
Y950853D03*
X1220441Y964239D03*
Y954200D03*
X1227883Y974278D03*
Y967585D03*
X1220441Y977625D03*
Y970932D03*
X1227883Y980971D03*
Y987664D03*
X1220441Y991011D03*
Y984318D03*
X1227883Y1027822D03*
X1220441Y1031168D03*
X1227883Y1017782D03*
X1220441D03*
Y1024475D03*
X1227883Y1047900D03*
Y1041207D03*
Y1034515D03*
X1220441Y1044554D03*
Y1037861D03*
X1227883Y1061286D03*
Y1054593D03*
X1220441Y1051247D03*
Y1057940D03*
X1227033Y1074672D03*
Y1067979D03*
X1221291Y1078018D03*
X1220441Y1064633D03*
Y1071326D03*
X1227883Y1091404D03*
Y1084711D03*
X1220441Y1094751D03*
X1221291Y1088058D03*
X1227883Y1104790D03*
X1227033Y1111483D03*
X1227883Y1098097D03*
X1220441Y1108137D03*
Y1101444D03*
X1227883Y1128215D03*
X1227033Y1121522D03*
X1221291Y1124869D03*
X1220441Y1114829D03*
X1227883Y1134908D03*
Y1141601D03*
X1220441Y1144948D03*
Y1138255D03*
X1221291Y1131562D03*
X1227883Y1158333D03*
Y1148294D03*
X1220441Y1151641D03*
Y1161680D03*
X1227883Y1171719D03*
Y1165026D03*
X1220441Y1175066D03*
Y1168373D03*
X1227883Y1185105D03*
Y1178412D03*
X1220441Y1188452D03*
Y1181759D03*
X1227883Y1208530D03*
Y1201837D03*
X1227033Y1195144D03*
X1220441Y1205184D03*
Y1198491D03*
X1227033Y1221916D03*
X1227883Y1215223D03*
X1221291Y1225263D03*
X1220441Y1218570D03*
Y1211877D03*
X1227883Y1238648D03*
X1227033Y1231955D03*
X1220441Y1241995D03*
X1221291Y1235302D03*
X1220441Y1248688D03*
X1227883Y1245341D03*
X1220601Y1269684D03*
X1220931Y1260093D03*
X1233327Y1274515D03*
X1231377Y1275855D03*
X1218692Y1578182D03*
X1226492D03*
X1230752D03*
X1218692Y1590094D03*
X1226492D03*
X1230752D03*
X1219732Y1614292D03*
Y1602380D03*
X1231792Y1614292D03*
Y1602380D03*
X1223992D03*
Y1614292D03*
X1236583Y766798D03*
Y780184D03*
Y773491D03*
Y803609D03*
Y796916D03*
Y790223D03*
X1237433Y816995D03*
X1236583Y810302D03*
Y833727D03*
X1237433Y827034D03*
X1236583Y847113D03*
Y840420D03*
X1237433Y863845D03*
Y853806D03*
X1236583Y870538D03*
Y883924D03*
Y877231D03*
Y900656D03*
Y890617D03*
Y914042D03*
Y907349D03*
X1237433Y927428D03*
X1236583Y920735D03*
Y944160D03*
X1237433Y937467D03*
X1236583Y960892D03*
Y950853D03*
Y974278D03*
Y967585D03*
Y980971D03*
Y987664D03*
Y1027822D03*
Y1017782D03*
Y1047900D03*
Y1041207D03*
Y1034515D03*
Y1061286D03*
Y1054593D03*
X1237433Y1074672D03*
Y1067979D03*
X1236583Y1091404D03*
Y1084711D03*
Y1104790D03*
X1237433Y1111483D03*
X1236583Y1098097D03*
Y1128215D03*
X1237433Y1121522D03*
X1236583Y1134908D03*
Y1141601D03*
Y1158333D03*
Y1148294D03*
Y1171719D03*
Y1165026D03*
Y1185105D03*
Y1178412D03*
Y1208530D03*
Y1201837D03*
Y1195144D03*
X1237433Y1221916D03*
X1236583Y1215223D03*
Y1238648D03*
X1237433Y1231955D03*
X1236583Y1245341D03*
X1238552Y1578182D03*
X1242812D03*
X1238552Y1590094D03*
X1242812D03*
X1236052Y1602380D03*
Y1614292D03*
X1243852D03*
Y1602380D03*
X1248112D03*
Y1614292D03*
X1241142Y1675383D03*
Y1679920D03*
X1249016Y1679320D03*
X1241142Y1684454D03*
Y1689556D03*
Y1694093D03*
Y1698627D03*
X1249016Y1688391D03*
Y1693493D03*
Y1698030D03*
Y1683857D03*
X1241142Y1703729D03*
Y1708266D03*
Y1712800D03*
X1249016Y1707666D03*
Y1712203D03*
Y1702564D03*
X1241142Y1726974D03*
Y1722440D03*
Y1717903D03*
X1249016Y1730911D03*
Y1726377D03*
Y1721840D03*
Y1716737D03*
X1250612Y1578182D03*
X1262672D03*
X1254872D03*
X1250612Y1590094D03*
X1262672D03*
X1254872D03*
X1255912Y1614292D03*
Y1602380D03*
X1260172D03*
Y1614292D03*
X1256890Y1675383D03*
Y1679920D03*
X1264764Y1679320D03*
X1256890Y1684454D03*
Y1689556D03*
Y1694093D03*
Y1698627D03*
X1264764Y1688391D03*
Y1693493D03*
Y1698030D03*
Y1683857D03*
X1256890Y1703729D03*
Y1708266D03*
Y1712800D03*
X1264764Y1707666D03*
Y1712203D03*
Y1702564D03*
X1256890Y1726974D03*
Y1722440D03*
Y1717903D03*
X1264764Y1730911D03*
Y1726377D03*
Y1721840D03*
Y1716737D03*
X1266932Y1578182D03*
X1274732D03*
X1278992D03*
X1266932Y1590094D03*
X1274732D03*
X1278992D03*
X1267972Y1614292D03*
Y1602380D03*
X1272232D03*
Y1614292D03*
X1280032D03*
Y1602380D03*
X1272638Y1675383D03*
Y1679920D03*
X1280512Y1679320D03*
X1272638Y1684454D03*
Y1689556D03*
Y1694093D03*
Y1698627D03*
X1280512Y1688391D03*
Y1693493D03*
Y1698030D03*
Y1683857D03*
X1272638Y1703729D03*
Y1708266D03*
Y1712800D03*
X1280512Y1707666D03*
Y1712203D03*
Y1702564D03*
X1272638Y1726974D03*
Y1722440D03*
Y1717903D03*
X1280512Y1730911D03*
Y1726377D03*
Y1721840D03*
Y1716737D03*
X1286792Y1578182D03*
X1298852D03*
X1291052D03*
X1286792Y1590094D03*
X1298852D03*
X1291052D03*
X1284292Y1602380D03*
Y1614292D03*
X1292092D03*
Y1602380D03*
X1296352D03*
Y1614292D03*
X1296260Y1679320D03*
X1288386Y1675383D03*
Y1679920D03*
X1296260Y1688391D03*
Y1693493D03*
Y1698030D03*
Y1683857D03*
X1288386Y1684454D03*
Y1689556D03*
Y1694093D03*
Y1698627D03*
X1296260Y1707666D03*
Y1712203D03*
Y1702564D03*
X1288386Y1703729D03*
Y1708266D03*
Y1712800D03*
X1296260Y1730911D03*
Y1726377D03*
Y1721840D03*
Y1716737D03*
X1288386Y1726974D03*
Y1722440D03*
Y1717903D03*
X1314353Y1124651D03*
X1303112Y1578182D03*
X1310912D03*
X1315172D03*
X1303112Y1590094D03*
X1310912D03*
X1315172D03*
X1304152Y1602380D03*
Y1614292D03*
X1308412Y1602380D03*
Y1614292D03*
X1308071Y1675383D03*
Y1679920D03*
Y1684454D03*
Y1689556D03*
Y1694093D03*
Y1698627D03*
Y1703729D03*
Y1708266D03*
Y1712800D03*
Y1726974D03*
Y1722440D03*
Y1717903D03*
X1328721Y854584D03*
X1323171Y870606D03*
Y889832D03*
X1319849Y1091513D03*
X1318053Y1124651D03*
X1321753Y1131060D03*
X1322972Y1578182D03*
X1327232D03*
X1322972Y1590094D03*
X1327232D03*
X1316212Y1614292D03*
Y1602380D03*
X1328272D03*
Y1614292D03*
X1320472Y1602380D03*
Y1614292D03*
X1323819Y1675383D03*
Y1679920D03*
X1315945Y1679320D03*
X1323819Y1684454D03*
Y1689556D03*
Y1694093D03*
Y1698627D03*
X1315945Y1688391D03*
Y1693493D03*
Y1698030D03*
Y1683857D03*
X1323819Y1703729D03*
Y1708266D03*
Y1712800D03*
X1315945Y1707666D03*
Y1712203D03*
Y1702564D03*
X1323819Y1726974D03*
Y1722440D03*
Y1717903D03*
X1315945Y1730911D03*
Y1726377D03*
Y1721840D03*
Y1716737D03*
X1336121Y880219D03*
Y899445D03*
X1347220D03*
X1336121Y918670D03*
X1341671Y941100D03*
X1336121Y937896D03*
X1347220D03*
X1345804Y1006093D03*
X1342104Y1076587D03*
X1335032Y1578182D03*
X1347092D03*
X1339292D03*
X1335032Y1590094D03*
X1347092D03*
X1339292D03*
X1340332Y1602380D03*
Y1614292D03*
X1332532Y1602380D03*
Y1614292D03*
X1344592Y1602380D03*
Y1614292D03*
X1339567Y1675383D03*
Y1679920D03*
X1331693Y1679320D03*
X1347441D03*
X1339567Y1684454D03*
Y1689556D03*
Y1694093D03*
Y1698627D03*
X1331693Y1688391D03*
Y1693493D03*
Y1698030D03*
Y1683857D03*
X1347441Y1688391D03*
Y1693493D03*
Y1698030D03*
Y1683857D03*
X1339567Y1703729D03*
Y1708266D03*
Y1712800D03*
X1331693Y1707666D03*
Y1712203D03*
Y1702564D03*
X1347441Y1707666D03*
Y1712203D03*
Y1702564D03*
X1339567Y1726974D03*
Y1722440D03*
Y1717903D03*
X1331693Y1730911D03*
Y1726377D03*
Y1721840D03*
Y1716737D03*
X1347441Y1730911D03*
Y1726377D03*
Y1721840D03*
Y1716737D03*
X1354620Y931488D03*
X1355053Y1060565D03*
X1351352Y1578182D03*
X1359152D03*
X1363412D03*
X1351352Y1590094D03*
X1359152D03*
X1363412D03*
X1352392Y1602380D03*
Y1614292D03*
X1356652Y1602380D03*
Y1614292D03*
X1363189Y1679320D03*
X1355315Y1675383D03*
Y1679920D03*
X1363189Y1688391D03*
Y1693493D03*
Y1698030D03*
Y1683857D03*
X1355315Y1684454D03*
Y1689556D03*
Y1694093D03*
Y1698627D03*
X1363189Y1707666D03*
Y1712203D03*
Y1702564D03*
X1355315Y1703729D03*
Y1708266D03*
Y1712800D03*
X1363189Y1730911D03*
Y1726377D03*
Y1721840D03*
Y1716737D03*
X1355315Y1726974D03*
Y1722440D03*
Y1717903D03*
X1373120Y899445D03*
Y931488D03*
Y937896D03*
X1371212Y1578088D03*
X1375472Y1578182D03*
X1371212Y1590094D03*
X1375472D03*
X1364452Y1602380D03*
Y1614292D03*
X1376512Y1602286D03*
Y1614292D03*
X1368712Y1602380D03*
Y1614292D03*
X1393716Y985579D03*
X1391326D03*
Y1014539D03*
X1393716D03*
X1393903Y1115039D03*
X1392053Y1118243D03*
X1390203Y1121447D03*
X1388353Y1124651D03*
Y1118243D03*
X1390204Y1134264D03*
X1388354Y1131060D03*
X1383272Y1578182D03*
Y1590094D03*
X1380772Y1602380D03*
Y1614292D03*
X1388572D03*
Y1602380D03*
X1411971Y851380D03*
Y864197D03*
Y877014D03*
Y889832D03*
Y902649D03*
X1404571Y921875D03*
X1410121Y944304D03*
Y957122D03*
Y950713D03*
Y963530D03*
Y976347D03*
Y969939D03*
Y982756D03*
X1410553Y1009297D03*
Y1002888D03*
Y1028523D03*
Y1022114D03*
Y1015705D03*
X1405004Y1044544D03*
X1410553Y1034931D03*
X1406854Y1047749D03*
X1399453D03*
X1408703Y1050952D03*
X1401304Y1057361D03*
X1410553Y1060565D03*
Y1054157D03*
X1408703Y1076587D03*
X1406853Y1073383D03*
X1403153D03*
Y1066974D03*
X1401304Y1076587D03*
X1399453Y1066974D03*
X1410553Y1073383D03*
Y1066974D03*
X1403154Y1079791D03*
X1410553D03*
X1408703Y1089404D03*
Y1082995D03*
X1405003D03*
X1401304Y1089404D03*
X1410553Y1092608D03*
Y1086200D03*
X1408703Y1095813D03*
X1405003D03*
X1403153Y1099017D03*
X1401303Y1102221D03*
X1399453Y1105426D03*
X1397604Y1108630D03*
X1410553Y1105426D03*
X1399453Y1111834D03*
X1410553D03*
X1399453Y1124651D03*
Y1118243D03*
X1397604Y1115039D03*
X1410553Y1124651D03*
Y1118243D03*
X1399454Y1137469D03*
X1399453Y1131060D03*
X1410554Y1137769D03*
X1410553Y1131060D03*
X1426771Y851380D03*
Y877014D03*
X1413820Y912262D03*
X1423070Y941100D03*
X1423071Y947509D03*
Y960326D03*
Y953917D03*
Y966735D03*
Y979552D03*
Y973143D03*
X1423503Y1006093D03*
Y999684D03*
Y1012501D03*
Y1025318D03*
Y1018910D03*
Y1031727D03*
X1429053Y1041340D03*
X1423503Y1038136D03*
X1429053Y1092608D03*
X1427204Y1089404D03*
X1427203Y1095812D03*
X1429053Y1099017D03*
X1423503Y1108630D03*
Y1102221D03*
Y1121447D03*
Y1115039D03*
Y1127856D03*
Y1134264D03*
X1432320Y912262D03*
X1437871Y921875D03*
X1438402Y942151D03*
X1440702D03*
X1443002D03*
X1430564Y949138D03*
X1440015Y956539D03*
X1430564Y951438D03*
X1442413Y956539D03*
X1430534Y963828D03*
Y966128D03*
X1440015Y971139D03*
X1442413Y971099D03*
X1430404Y981208D03*
Y978908D03*
X1440015Y985579D03*
X1430604Y995298D03*
Y992998D03*
X1442413Y985579D03*
X1440015Y1014539D03*
Y1000059D03*
X1430584Y1009408D03*
Y1007108D03*
X1442413Y1014539D03*
Y1000059D03*
X1436454Y1105426D03*
X1434604Y1102221D03*
X1432753Y1099017D03*
X1440154Y1105426D03*
X1438304Y1108630D03*
X1440154Y1111834D03*
X1434604Y1121447D03*
Y1115039D03*
X1443854Y1124651D03*
X1443853Y1118243D03*
X1442004Y1121447D03*
Y1115039D03*
X1434604Y1127856D03*
Y1134264D03*
X1450820Y899445D03*
Y912262D03*
X1445703Y1115039D03*
X1447553Y1118243D03*
X1445704Y1127856D03*
X1445703Y1140973D03*
X1447554Y1137469D03*
Y1131060D03*
X1460095Y1578182D03*
Y1590094D03*
X1465620Y912262D03*
X1471604Y1108630D03*
X1469753Y1111834D03*
X1472155Y1578182D03*
X1467895D03*
X1472155Y1590094D03*
X1467895D03*
X1477455Y1602380D03*
Y1614292D03*
X1473195D03*
Y1602380D03*
X1465395D03*
Y1614292D03*
X1484120Y937896D03*
X1485971Y947509D03*
X1491953Y1086200D03*
X1492015Y1578182D03*
X1484215D03*
X1479955D03*
X1492015Y1590094D03*
X1484215D03*
X1479955D03*
X1489515Y1614292D03*
Y1602380D03*
X1485255D03*
Y1614292D03*
X1508335Y1578182D03*
X1496275D03*
X1504075D03*
X1508335Y1590094D03*
X1496275D03*
X1504075D03*
X1501575Y1614292D03*
Y1602380D03*
X1509375D03*
Y1614292D03*
X1497315Y1602380D03*
Y1614292D03*
X1505315Y1675383D03*
Y1679920D03*
Y1684454D03*
Y1689556D03*
Y1694093D03*
Y1698627D03*
Y1703729D03*
Y1708266D03*
Y1712800D03*
Y1726974D03*
Y1722440D03*
Y1717903D03*
X1511871Y928283D03*
X1519271D03*
X1515571D03*
X1524820Y925079D03*
X1513720D03*
X1524820Y944304D03*
X1513720D03*
X1520395Y1578182D03*
X1516135D03*
X1520395Y1590094D03*
X1516135D03*
X1525695Y1614292D03*
Y1602380D03*
X1521435D03*
Y1614292D03*
X1513635D03*
Y1602380D03*
X1521063Y1675383D03*
Y1679920D03*
X1513189Y1679320D03*
X1521063Y1684454D03*
Y1689556D03*
Y1694093D03*
Y1698627D03*
X1513189Y1688391D03*
Y1693493D03*
Y1698030D03*
Y1683857D03*
X1521063Y1703729D03*
Y1708266D03*
Y1712800D03*
X1513189Y1707666D03*
Y1712203D03*
Y1702564D03*
X1521063Y1726974D03*
Y1722440D03*
Y1717903D03*
X1513189Y1730911D03*
Y1726377D03*
Y1721840D03*
Y1716737D03*
X1540255Y1578182D03*
X1532455D03*
X1528195D03*
X1540255Y1590094D03*
X1532455D03*
X1528195D03*
X1537755Y1614292D03*
Y1602380D03*
X1533495D03*
Y1614292D03*
X1536811Y1675383D03*
Y1679920D03*
X1528937Y1679320D03*
X1536811Y1684454D03*
Y1689556D03*
Y1694093D03*
Y1698627D03*
X1528937Y1688391D03*
Y1693493D03*
Y1698030D03*
Y1683857D03*
X1536811Y1703729D03*
Y1708266D03*
Y1712800D03*
X1528937Y1707666D03*
Y1712203D03*
Y1702564D03*
X1536811Y1726974D03*
Y1722440D03*
Y1717903D03*
X1528937Y1730911D03*
Y1726377D03*
Y1721840D03*
Y1716737D03*
X1556575Y1578182D03*
X1544515D03*
X1552315D03*
X1556575Y1590094D03*
X1544515D03*
X1552315D03*
X1549815Y1614292D03*
Y1602380D03*
X1557615D03*
Y1614292D03*
X1545555Y1602380D03*
Y1614292D03*
X1552559Y1675383D03*
Y1679920D03*
X1544685Y1679320D03*
X1552559Y1684454D03*
Y1689556D03*
Y1694093D03*
Y1698627D03*
X1544685Y1688391D03*
Y1693493D03*
Y1698030D03*
Y1683857D03*
X1552559Y1703729D03*
Y1708266D03*
Y1712800D03*
X1544685Y1707666D03*
Y1712203D03*
Y1702564D03*
X1552559Y1726974D03*
Y1722440D03*
Y1717903D03*
X1544685Y1730911D03*
Y1726377D03*
Y1721840D03*
Y1716737D03*
X1568635Y1578182D03*
X1564375D03*
X1568635Y1590094D03*
X1564375D03*
X1573935Y1614292D03*
Y1602380D03*
X1569675Y1614292D03*
Y1602380D03*
X1561875Y1614292D03*
Y1602380D03*
X1560433Y1679320D03*
X1572244Y1675383D03*
Y1679920D03*
X1560433Y1688391D03*
Y1693493D03*
Y1698030D03*
Y1683857D03*
X1572244Y1684454D03*
Y1689556D03*
Y1694093D03*
Y1698627D03*
X1560433Y1707666D03*
Y1712203D03*
Y1702564D03*
X1572244Y1703729D03*
Y1708266D03*
Y1712800D03*
X1560433Y1730911D03*
Y1726377D03*
Y1721840D03*
Y1716737D03*
X1572244Y1726974D03*
Y1722440D03*
Y1717903D03*
X1588495Y1578182D03*
X1580695D03*
X1576435D03*
X1588495Y1590094D03*
X1580695D03*
X1576435D03*
X1585995Y1614292D03*
Y1602380D03*
X1581735D03*
Y1614292D03*
X1587992Y1675383D03*
Y1679920D03*
X1580118Y1679320D03*
X1587992Y1684454D03*
Y1689556D03*
Y1694093D03*
Y1698627D03*
X1580118Y1688391D03*
Y1693493D03*
Y1698030D03*
Y1683857D03*
X1587992Y1703729D03*
Y1708266D03*
Y1712800D03*
X1580118Y1707666D03*
Y1712203D03*
Y1702564D03*
X1587992Y1726974D03*
Y1722440D03*
Y1717903D03*
X1580118Y1730911D03*
Y1726377D03*
Y1721840D03*
Y1716737D03*
X1597041Y770144D03*
X1605741D03*
Y776837D03*
X1597041D03*
X1605741Y783530D03*
X1597041D03*
X1605741Y793570D03*
X1597041D03*
X1596988Y800263D03*
X1605741D03*
X1595774Y806955D03*
X1606934D03*
X1596218Y813648D03*
X1606735D03*
X1597041Y820341D03*
X1605741D03*
X1597041Y830381D03*
X1605741D03*
Y837074D03*
X1597041D03*
Y843766D03*
X1605741D03*
X1596147Y850459D03*
X1606896D03*
X1596200Y857152D03*
X1606623D03*
X1597041Y867192D03*
X1605741D03*
X1597041Y873885D03*
X1605741D03*
X1597041Y880577D03*
X1605741D03*
X1597041Y887270D03*
X1605741D03*
X1606898Y893963D03*
X1597041D03*
X1605741Y904003D03*
X1597041D03*
Y917389D03*
X1605741D03*
X1597041Y910696D03*
X1605741D03*
X1597041Y924081D03*
X1605741D03*
X1606541Y930697D03*
X1596047Y930774D03*
X1596106Y940814D03*
X1606919D03*
X1605741Y947507D03*
X1597041D03*
X1605741Y954200D03*
X1597041D03*
Y964239D03*
X1605741D03*
X1597041Y977625D03*
X1605741D03*
Y970932D03*
X1597041D03*
Y984318D03*
X1605741D03*
X1597041Y991011D03*
X1605741D03*
X1597041Y1024475D03*
X1605741D03*
X1597041Y1017782D03*
X1605741D03*
X1597041Y1031168D03*
X1605741D03*
X1597041Y1037861D03*
X1605741D03*
X1597041Y1044554D03*
X1605741D03*
Y1051247D03*
X1597041D03*
Y1057940D03*
X1605741D03*
X1597041Y1064633D03*
X1605741D03*
X1606541Y1071326D03*
X1596141D03*
X1597041Y1078018D03*
X1605741D03*
Y1094751D03*
X1597041D03*
Y1088058D03*
X1605741D03*
Y1101444D03*
X1597041D03*
Y1108137D03*
X1605741D03*
X1606541Y1114829D03*
X1596241D03*
X1596511Y1124969D03*
X1606505Y1124674D03*
X1605741Y1138255D03*
X1597041D03*
X1605741Y1144948D03*
X1597041D03*
Y1131562D03*
X1605741D03*
Y1151641D03*
X1597041D03*
X1596653Y1161680D03*
X1605975Y1161581D03*
X1605741Y1168373D03*
X1597041D03*
X1605741Y1175066D03*
X1597041D03*
X1605741Y1181759D03*
X1597041D03*
X1606765Y1188452D03*
X1597041D03*
Y1198491D03*
X1605741D03*
Y1205184D03*
X1597041D03*
Y1211877D03*
X1605741D03*
X1597041Y1218570D03*
X1605741D03*
X1597041Y1225263D03*
X1605741D03*
X1607064Y1235302D03*
X1596178D03*
X1605741Y1241995D03*
X1597041D03*
Y1248688D03*
X1605741D03*
X1603788Y1273144D03*
X1601388D03*
X1604815Y1578182D03*
X1592755D03*
X1600555D03*
X1604815Y1590094D03*
X1592755D03*
X1600555D03*
X1598055Y1614292D03*
Y1602380D03*
X1605855Y1614292D03*
Y1602380D03*
X1593795Y1614292D03*
Y1602380D03*
X1603740Y1675383D03*
Y1679920D03*
X1595866Y1679320D03*
X1603740Y1684454D03*
Y1689556D03*
Y1694093D03*
Y1698627D03*
X1595866Y1688391D03*
Y1693493D03*
Y1698030D03*
Y1683857D03*
X1603740Y1703729D03*
Y1708266D03*
Y1712800D03*
X1595866Y1707666D03*
Y1712203D03*
Y1702564D03*
X1603740Y1726974D03*
Y1722440D03*
Y1717903D03*
X1595866Y1730911D03*
Y1726377D03*
Y1721840D03*
Y1716737D03*
X1613183Y766798D03*
X1621883D03*
Y773491D03*
X1613183D03*
X1621883Y780184D03*
X1613183D03*
X1621883Y790223D03*
X1613183D03*
Y796916D03*
X1621883D03*
X1613183Y803609D03*
X1621883D03*
X1622916Y816995D03*
X1613183D03*
X1612363Y810302D03*
X1622986D03*
X1613183Y827034D03*
X1621883D03*
Y833727D03*
X1613183D03*
Y840420D03*
X1621883D03*
X1613183Y847113D03*
X1621943D03*
X1622060Y863845D03*
X1612408D03*
X1612474Y853955D03*
X1622961Y853806D03*
X1621883Y883924D03*
X1613183D03*
Y870538D03*
X1621883D03*
X1613183Y877231D03*
X1621883D03*
X1613183Y890617D03*
X1621883D03*
X1613183Y900656D03*
X1621883D03*
Y907349D03*
X1613183D03*
Y914042D03*
X1621883D03*
Y920735D03*
X1613183D03*
X1622535Y927526D03*
X1612168Y927428D03*
X1622845Y937467D03*
X1612312D03*
X1621883Y944160D03*
X1613183D03*
X1621883Y950853D03*
X1613183D03*
X1621883Y960892D03*
X1613183D03*
Y974278D03*
X1621883D03*
X1613183Y980971D03*
X1621883D03*
X1613183Y967585D03*
X1621883D03*
X1613183Y987664D03*
X1621883D03*
Y1017782D03*
X1613183D03*
Y1027822D03*
X1621883D03*
X1613183Y1034515D03*
X1621883D03*
X1613183Y1041207D03*
X1621883D03*
X1613183Y1047900D03*
X1621883D03*
Y1054593D03*
X1613183D03*
Y1061286D03*
X1621883D03*
Y1067979D03*
X1612983D03*
X1612283Y1074672D03*
X1622683D03*
X1621883Y1084711D03*
X1612383D03*
X1613183Y1091404D03*
X1621883D03*
Y1104790D03*
X1613183D03*
X1621883Y1098097D03*
X1613183D03*
X1621883Y1111483D03*
X1613183D03*
Y1128915D03*
X1621883Y1128215D03*
X1613183Y1121522D03*
X1621883D03*
Y1141601D03*
X1613183D03*
X1622726Y1135108D03*
X1611886Y1134908D03*
X1621883Y1158333D03*
X1613183D03*
X1621883Y1148294D03*
X1613183D03*
X1621883Y1165026D03*
X1613183D03*
Y1171719D03*
X1621883D03*
Y1178412D03*
X1613183D03*
X1621883Y1185105D03*
X1613183D03*
Y1195144D03*
X1621883D03*
Y1201837D03*
X1613183D03*
X1621883Y1208530D03*
X1613183D03*
X1621883Y1215223D03*
X1613183D03*
X1612147Y1221916D03*
X1622712D03*
X1612137Y1231862D03*
X1622681Y1231955D03*
X1621883Y1238648D03*
X1613183D03*
X1610150Y1257172D03*
X1621883Y1245341D03*
X1613183D03*
X1618888Y1273344D03*
X1616088D03*
X1616875Y1578182D03*
X1612615D03*
X1616875Y1590094D03*
X1612615D03*
X1622175Y1614292D03*
Y1602380D03*
X1617915Y1614292D03*
Y1602380D03*
X1610115Y1614292D03*
Y1602380D03*
X1619488Y1675383D03*
Y1679920D03*
X1611614Y1679320D03*
X1619488Y1684454D03*
Y1689556D03*
Y1694093D03*
Y1698627D03*
X1611614Y1688391D03*
Y1693493D03*
Y1698030D03*
Y1683857D03*
X1619488Y1703729D03*
Y1708266D03*
Y1712800D03*
X1611614Y1707666D03*
Y1712203D03*
Y1702564D03*
X1619488Y1726974D03*
Y1722440D03*
Y1717903D03*
X1611614Y1730911D03*
Y1726377D03*
Y1721840D03*
Y1716737D03*
X1626741Y770144D03*
X1635441D03*
X1626741Y776837D03*
X1635441D03*
X1626741Y783530D03*
X1635441D03*
X1626741Y793570D03*
X1635441D03*
Y800263D03*
X1626741D03*
X1636341Y820341D03*
X1626741D03*
X1636574Y813648D03*
X1626741D03*
X1635441Y806955D03*
X1626741D03*
X1635441Y830381D03*
X1626741D03*
X1635441Y837074D03*
X1626741D03*
Y843766D03*
X1635441D03*
Y850459D03*
X1626741D03*
X1625705Y867192D03*
X1636441D03*
X1635441Y857152D03*
X1626741D03*
Y880577D03*
X1635441D03*
Y873885D03*
X1626741D03*
Y887270D03*
X1635441D03*
X1626741Y893963D03*
X1635441D03*
X1626741Y904003D03*
X1635441D03*
Y910696D03*
X1626741D03*
X1635441Y917389D03*
X1626741D03*
X1636316Y930774D03*
X1625803D03*
X1636646Y924081D03*
X1626741D03*
X1635441Y940814D03*
X1626741D03*
X1635441Y947507D03*
X1626741D03*
X1635441Y954200D03*
X1626741D03*
Y964239D03*
X1635441D03*
Y977625D03*
X1626741D03*
X1635441Y970932D03*
X1626741D03*
X1635441Y984318D03*
X1626741D03*
Y991011D03*
X1635441D03*
Y1024475D03*
X1626741D03*
X1635441Y1017782D03*
X1626741D03*
X1635441Y1031168D03*
X1626741D03*
X1635441Y1037861D03*
X1626741D03*
X1635441Y1044554D03*
X1626741D03*
Y1057940D03*
X1635441D03*
Y1051247D03*
X1626741D03*
X1635441Y1064633D03*
X1626741D03*
X1635441Y1071326D03*
X1626741D03*
X1636241Y1078018D03*
X1625941D03*
Y1088058D03*
X1636241D03*
X1635441Y1094751D03*
X1626741D03*
Y1101444D03*
X1635441D03*
X1626741Y1108137D03*
X1635441D03*
X1626074Y1124640D03*
X1636341Y1124869D03*
X1635441Y1114829D03*
X1626741D03*
X1635441Y1144948D03*
X1626741D03*
X1635441Y1138255D03*
X1626741D03*
X1635441Y1130762D03*
X1626741D03*
Y1161680D03*
X1635441D03*
Y1151641D03*
X1626741D03*
Y1168373D03*
X1635441D03*
X1626741Y1175066D03*
X1635441D03*
X1626741Y1181759D03*
X1635441D03*
X1626741Y1188452D03*
X1635441D03*
X1626741Y1198491D03*
X1635441D03*
X1626741Y1205184D03*
X1635441D03*
Y1211877D03*
X1626741D03*
X1635441Y1218570D03*
X1626741D03*
X1636212Y1225263D03*
X1626055D03*
X1636376Y1235302D03*
X1625843D03*
X1635441Y1241995D03*
X1626741D03*
X1635688Y1257664D03*
X1626741Y1248688D03*
X1635441D03*
X1629788Y1273344D03*
X1632588D03*
X1625729Y1266766D03*
X1636735Y1578088D03*
X1628935Y1578182D03*
X1624675D03*
X1636735Y1590094D03*
X1628935D03*
X1624675D03*
X1634235Y1614292D03*
Y1602380D03*
X1629975Y1614292D03*
Y1602380D03*
X1627362Y1679320D03*
Y1688391D03*
Y1693493D03*
Y1698030D03*
Y1683857D03*
Y1707666D03*
Y1712203D03*
Y1702564D03*
Y1730911D03*
Y1726377D03*
Y1721840D03*
Y1716737D03*
X1651583Y766798D03*
X1642883D03*
X1656441Y770144D03*
Y776837D03*
X1642883Y773491D03*
X1651583D03*
X1642883Y780184D03*
X1651583D03*
X1656441Y783530D03*
Y793570D03*
X1642883Y790223D03*
X1651583D03*
X1642883Y796916D03*
X1651583D03*
X1656441Y800263D03*
X1651583Y803609D03*
X1642883D03*
X1656441Y806955D03*
Y813648D03*
Y820341D03*
X1651583Y810302D03*
X1642883D03*
X1652545Y816995D03*
X1641945D03*
X1656441Y830381D03*
X1652767Y827034D03*
X1642018D03*
X1651583Y833727D03*
X1642883D03*
X1656441Y837074D03*
Y843766D03*
X1642883Y840420D03*
X1651583D03*
X1656441Y850459D03*
X1651583Y847113D03*
X1642883D03*
X1642058Y863845D03*
X1652742D03*
X1656441Y857152D03*
Y867192D03*
X1652559Y853806D03*
X1642032D03*
X1656441Y873885D03*
Y880577D03*
X1642883Y883924D03*
X1651583D03*
Y870538D03*
X1642883D03*
X1651583Y877231D03*
X1642883D03*
X1656441Y887270D03*
Y893963D03*
X1642883Y890617D03*
X1651583D03*
X1642883Y900656D03*
X1651583D03*
X1656441Y904003D03*
Y910696D03*
X1642883Y907349D03*
X1651583D03*
X1656441Y917389D03*
X1651583Y914042D03*
X1642883D03*
X1656441Y924081D03*
Y930774D03*
X1652630Y927428D03*
X1642038D03*
X1651583Y920735D03*
X1642883D03*
X1656441Y940814D03*
Y947507D03*
X1652501Y937467D03*
X1642065D03*
X1651583Y944160D03*
X1642883D03*
X1656441Y954200D03*
X1642883Y950853D03*
X1651583D03*
Y960892D03*
X1642883D03*
X1656441Y964239D03*
Y977625D03*
Y970932D03*
X1651583Y967585D03*
X1642883D03*
X1651583Y974278D03*
X1642883D03*
X1651583Y980971D03*
X1642883D03*
X1656441Y984318D03*
Y991011D03*
X1651583Y987664D03*
X1642883D03*
X1651583Y1017782D03*
X1642883D03*
X1656441D03*
Y1024475D03*
X1651583Y1027822D03*
X1642883D03*
X1656441Y1031168D03*
Y1044554D03*
Y1037861D03*
X1651583Y1034515D03*
X1642883D03*
X1651583Y1041207D03*
X1642883D03*
X1651583Y1047900D03*
X1642883D03*
Y1061286D03*
X1651583D03*
X1656441Y1051247D03*
Y1057940D03*
X1651583Y1054593D03*
X1642883D03*
X1656441Y1064633D03*
Y1071326D03*
Y1078018D03*
X1652483Y1074672D03*
X1641983D03*
X1651583Y1067979D03*
X1642883D03*
X1656441Y1088058D03*
Y1094751D03*
X1652383Y1084711D03*
X1642083D03*
X1651583Y1091404D03*
X1642883D03*
X1656441Y1101444D03*
Y1108137D03*
X1642883Y1098097D03*
X1651583D03*
X1642883Y1104790D03*
X1651583D03*
X1642883Y1111483D03*
X1651583D03*
X1656441Y1114829D03*
Y1124869D03*
X1642883Y1121522D03*
X1651583D03*
X1642883Y1128215D03*
X1651583D03*
X1656441Y1131562D03*
Y1138255D03*
X1642883Y1134908D03*
X1651583D03*
X1642883Y1141601D03*
X1651583D03*
X1656441Y1144948D03*
Y1151641D03*
Y1161680D03*
X1652383Y1158333D03*
X1642083D03*
X1652794Y1148294D03*
X1641744D03*
X1656441Y1168373D03*
Y1175066D03*
X1642883Y1171719D03*
X1651583D03*
Y1165026D03*
X1642883D03*
X1656441Y1181759D03*
Y1188452D03*
X1651583Y1178412D03*
X1642883D03*
X1651583Y1185105D03*
X1642883D03*
X1656441Y1198491D03*
Y1205184D03*
X1642883Y1195144D03*
X1651583D03*
X1642883Y1201837D03*
X1651583D03*
X1642883Y1208530D03*
X1651583D03*
X1656441Y1211877D03*
X1652590Y1221916D03*
X1641793D03*
X1656441Y1225263D03*
Y1218570D03*
X1651583Y1215223D03*
X1642883D03*
X1656441Y1235302D03*
Y1241995D03*
X1652604Y1231955D03*
X1642054D03*
X1651583Y1238648D03*
X1642883D03*
X1656441Y1248688D03*
X1651583Y1245341D03*
X1642883D03*
X1648588Y1273344D03*
X1645788D03*
X1640995Y1578182D03*
X1648795D03*
X1640995Y1590094D03*
X1648795D03*
X1646295Y1614292D03*
Y1602380D03*
X1654095Y1614292D03*
Y1602380D03*
X1642035Y1614292D03*
Y1602286D03*
X1665141Y770144D03*
X1672583Y766798D03*
X1665141Y776837D03*
Y783530D03*
X1672583Y773491D03*
Y780184D03*
X1665141Y793570D03*
Y800263D03*
X1672583Y790223D03*
Y796916D03*
Y803609D03*
X1665141Y806955D03*
Y813648D03*
X1666030Y820341D03*
X1672583Y810302D03*
Y816995D03*
X1665141Y830381D03*
X1672583Y827034D03*
Y833727D03*
X1665141Y837074D03*
Y843766D03*
X1672583Y840420D03*
X1665141Y850459D03*
X1672583Y847113D03*
X1666038Y857152D03*
X1665141Y867192D03*
X1672583Y853806D03*
Y863845D03*
X1665141Y873885D03*
Y880577D03*
X1672583Y870538D03*
Y877231D03*
Y883924D03*
X1665141Y887270D03*
Y893963D03*
X1672583Y890617D03*
Y900656D03*
X1665141Y904003D03*
Y910696D03*
Y917389D03*
X1672583Y907349D03*
Y914042D03*
X1665141Y924081D03*
X1666246Y930774D03*
X1672583Y920735D03*
Y927428D03*
X1665141Y940814D03*
Y947507D03*
X1672583Y937467D03*
Y944160D03*
X1665141Y954200D03*
Y964239D03*
X1672583Y950853D03*
Y960892D03*
X1665141Y977625D03*
Y970932D03*
X1672583Y967585D03*
Y974278D03*
Y980971D03*
X1665141Y984318D03*
Y991011D03*
X1672583Y987664D03*
X1665141Y1017782D03*
Y1024475D03*
Y1031168D03*
X1672583Y1017782D03*
Y1027822D03*
X1665141Y1044554D03*
Y1037861D03*
X1672583Y1034515D03*
Y1041207D03*
Y1047900D03*
X1665141Y1057940D03*
X1672583Y1061286D03*
Y1054593D03*
X1665141Y1064633D03*
Y1071326D03*
Y1077118D03*
X1672583Y1067979D03*
Y1074672D03*
X1665141Y1088058D03*
Y1094751D03*
X1672583Y1084711D03*
Y1091404D03*
X1665141Y1101444D03*
Y1108137D03*
X1672583Y1098097D03*
Y1104790D03*
Y1111483D03*
X1665141Y1114829D03*
Y1124869D03*
X1672583Y1121522D03*
Y1128215D03*
X1665141Y1131562D03*
Y1138255D03*
Y1144948D03*
X1672583Y1134908D03*
Y1141601D03*
X1666141Y1151641D03*
X1665141Y1161680D03*
X1672583Y1148294D03*
Y1158333D03*
X1665141Y1168373D03*
Y1175066D03*
X1672583Y1165026D03*
Y1171719D03*
X1665141Y1181759D03*
Y1188452D03*
X1672583Y1178412D03*
Y1185105D03*
X1665141Y1198491D03*
Y1205184D03*
X1672583Y1195144D03*
Y1201837D03*
Y1208530D03*
X1665141Y1211877D03*
X1665941Y1225263D03*
X1665141Y1218570D03*
X1672583Y1215223D03*
Y1221916D03*
X1665141Y1235302D03*
Y1241995D03*
X1672583Y1231955D03*
Y1238648D03*
X1665141Y1248688D03*
X1672583Y1245341D03*
X1665688Y1257964D03*
X1659488Y1273344D03*
X1662288D03*
X1681283Y766798D03*
X1686141Y770144D03*
X1681283Y773491D03*
Y780184D03*
X1686141Y776837D03*
Y783530D03*
X1681283Y790223D03*
Y796916D03*
Y803609D03*
X1686141Y793570D03*
Y800263D03*
X1681283Y810302D03*
Y816995D03*
X1686141Y806955D03*
Y813648D03*
Y820341D03*
X1681283Y827034D03*
Y833727D03*
X1686141Y830381D03*
X1681283Y840420D03*
X1686141Y837074D03*
Y843766D03*
Y850459D03*
X1681283Y847113D03*
X1686141Y857152D03*
Y867192D03*
X1681283Y853806D03*
Y863845D03*
X1686141Y873885D03*
Y880577D03*
X1681283Y870538D03*
Y877231D03*
Y883924D03*
X1686141Y887270D03*
Y893963D03*
X1681283Y890617D03*
Y900656D03*
X1686141Y904003D03*
Y910696D03*
Y917389D03*
X1681283Y907349D03*
Y914042D03*
X1686141Y924081D03*
Y930774D03*
X1681283Y920735D03*
Y927428D03*
X1686141Y940814D03*
Y947507D03*
X1681283Y937467D03*
Y944160D03*
X1686141Y954200D03*
Y964239D03*
X1681283Y950853D03*
Y960892D03*
X1686141Y970932D03*
Y977625D03*
X1681283Y967585D03*
Y974278D03*
Y980971D03*
X1686141Y984318D03*
Y991011D03*
X1681283Y987664D03*
X1686141Y1017782D03*
Y1024475D03*
Y1031168D03*
X1681283Y1017782D03*
Y1027822D03*
X1686141Y1037861D03*
Y1044554D03*
X1681283Y1034515D03*
Y1041207D03*
Y1047900D03*
X1686141Y1051247D03*
Y1057940D03*
X1681283Y1061286D03*
Y1054593D03*
X1686141Y1064633D03*
Y1071326D03*
Y1078018D03*
X1681283Y1067979D03*
Y1074672D03*
X1686141Y1088058D03*
Y1094751D03*
X1681283Y1084711D03*
Y1091404D03*
X1686141Y1101444D03*
Y1108137D03*
X1681283Y1098097D03*
Y1104790D03*
Y1111483D03*
X1686141Y1114829D03*
Y1124869D03*
X1681283Y1121522D03*
Y1128215D03*
X1686141Y1131562D03*
Y1138255D03*
Y1144948D03*
X1681283Y1134908D03*
Y1141601D03*
X1686141Y1151641D03*
Y1161680D03*
X1681283Y1148294D03*
Y1158333D03*
X1686141Y1168373D03*
Y1175066D03*
X1681283Y1165026D03*
Y1171719D03*
X1686141Y1181759D03*
Y1188452D03*
X1681283Y1178412D03*
Y1185105D03*
X1686141Y1198491D03*
Y1205184D03*
X1681283Y1195144D03*
Y1201837D03*
Y1208530D03*
X1686141Y1211877D03*
Y1218570D03*
Y1225263D03*
X1681283Y1215223D03*
Y1221916D03*
Y1231955D03*
Y1238648D03*
X1686141Y1235302D03*
Y1241995D03*
X1681283Y1245341D03*
X1686141Y1248688D03*
X1675488Y1273344D03*
X1678288D03*
X1689188D03*
X1694841Y770144D03*
X1702283Y766798D03*
X1694841Y776837D03*
Y783530D03*
X1702283Y773491D03*
Y780184D03*
X1694841Y793570D03*
Y800263D03*
X1702283Y790223D03*
Y796916D03*
Y803609D03*
X1694841Y806955D03*
Y813648D03*
Y820341D03*
X1702283Y810302D03*
Y816995D03*
X1694841Y830381D03*
X1702283Y827034D03*
Y833727D03*
X1694841Y837074D03*
Y843766D03*
Y850459D03*
X1702283Y840420D03*
Y847113D03*
X1694841Y857152D03*
Y867192D03*
X1702283Y853806D03*
Y863845D03*
X1694841Y873885D03*
Y880577D03*
X1702283Y870538D03*
Y877231D03*
Y883924D03*
X1694841Y887270D03*
Y893963D03*
X1702283Y890617D03*
Y900656D03*
X1694841Y904003D03*
Y910696D03*
Y917389D03*
X1702283Y907349D03*
Y914042D03*
X1694841Y924081D03*
Y930774D03*
X1702283Y920735D03*
Y927428D03*
X1694841Y940814D03*
Y947507D03*
X1702283Y937467D03*
Y944160D03*
X1694841Y954200D03*
Y964239D03*
X1702283Y950853D03*
Y960892D03*
X1694841Y970932D03*
Y977625D03*
X1702283Y967585D03*
Y974278D03*
Y980971D03*
X1694841Y984318D03*
Y991011D03*
X1702283Y987664D03*
X1694841Y1017782D03*
Y1024475D03*
Y1031168D03*
X1702283Y1017782D03*
Y1027822D03*
X1694841Y1037861D03*
Y1044554D03*
X1702283Y1034515D03*
Y1041207D03*
Y1047900D03*
X1694841Y1051247D03*
Y1057940D03*
X1702283Y1054593D03*
Y1061286D03*
X1694841Y1064633D03*
Y1071326D03*
Y1078018D03*
X1702283Y1067979D03*
Y1074672D03*
X1694841Y1088058D03*
Y1094751D03*
X1702283Y1084711D03*
Y1091404D03*
X1694841Y1101444D03*
Y1108137D03*
X1702283Y1098097D03*
Y1104790D03*
Y1111483D03*
X1694841Y1114829D03*
Y1124869D03*
X1702283Y1121522D03*
Y1128215D03*
X1694841Y1131562D03*
Y1138255D03*
Y1144948D03*
X1702283Y1134908D03*
Y1141601D03*
X1694841Y1151641D03*
Y1161680D03*
X1702283Y1148294D03*
Y1158333D03*
X1694841Y1168373D03*
Y1175066D03*
X1702283Y1165026D03*
Y1171719D03*
X1694841Y1181759D03*
Y1188452D03*
X1702283Y1178412D03*
Y1185105D03*
X1694841Y1198491D03*
Y1205184D03*
X1702283Y1195144D03*
Y1201837D03*
Y1208530D03*
X1694841Y1211877D03*
Y1218570D03*
Y1225263D03*
X1702283Y1215223D03*
Y1221916D03*
X1694841Y1235302D03*
Y1241995D03*
X1702283Y1231955D03*
Y1238648D03*
X1694841Y1248688D03*
X1695188Y1257064D03*
X1702283Y1245341D03*
X1691988Y1273344D03*
X1705188D03*
X1710983Y766798D03*
X1715841Y770144D03*
X1710983Y773491D03*
Y780184D03*
X1715841Y783530D03*
Y776837D03*
X1710983Y790223D03*
Y796916D03*
Y803609D03*
X1715841Y793570D03*
Y800263D03*
X1710983Y810302D03*
Y816995D03*
X1715841Y806955D03*
Y813648D03*
Y820341D03*
X1710983Y827034D03*
Y833727D03*
X1715841Y830381D03*
X1710983Y840420D03*
Y847113D03*
X1715841Y837074D03*
Y843766D03*
Y850459D03*
X1710983Y853806D03*
Y863845D03*
X1715841Y857152D03*
Y867192D03*
X1710983Y870538D03*
Y877231D03*
Y883924D03*
X1715841Y873885D03*
Y880577D03*
X1710983Y890617D03*
Y900656D03*
X1715841Y893963D03*
Y887270D03*
X1710983Y907349D03*
Y914042D03*
X1715841Y904003D03*
Y910696D03*
Y917389D03*
X1710983Y920735D03*
Y927428D03*
X1715841Y924081D03*
Y930774D03*
X1710983Y937467D03*
Y944160D03*
X1715841Y940814D03*
Y947507D03*
X1710983Y950853D03*
Y960892D03*
X1715841Y954200D03*
Y964239D03*
X1710983Y967585D03*
Y974278D03*
Y980971D03*
X1715841Y970932D03*
Y977625D03*
X1710983Y987664D03*
X1715841Y984318D03*
Y991011D03*
X1710983Y1017782D03*
Y1027822D03*
X1715841Y1017782D03*
Y1024475D03*
Y1031168D03*
X1710983Y1034515D03*
Y1041207D03*
Y1047900D03*
X1715841Y1037861D03*
Y1044554D03*
X1710983Y1054593D03*
Y1061286D03*
X1715841Y1051247D03*
Y1057940D03*
X1710983Y1067979D03*
Y1074672D03*
X1715841Y1071326D03*
Y1064633D03*
Y1078018D03*
X1710983Y1084711D03*
Y1091404D03*
X1715841Y1088058D03*
Y1094751D03*
X1710983Y1098097D03*
Y1104790D03*
Y1111483D03*
X1715841Y1101444D03*
Y1108137D03*
X1710983Y1121522D03*
Y1128215D03*
X1715841Y1114829D03*
Y1124869D03*
X1710983Y1134908D03*
Y1141601D03*
X1715841Y1131562D03*
Y1138255D03*
Y1144948D03*
X1710983Y1148294D03*
Y1158333D03*
X1715841Y1151641D03*
Y1161680D03*
X1710983Y1165026D03*
Y1171719D03*
X1715841Y1168373D03*
Y1175066D03*
X1710983Y1178412D03*
Y1185105D03*
X1715841Y1181759D03*
Y1188452D03*
X1710983Y1195144D03*
Y1201837D03*
Y1208530D03*
X1715841Y1198491D03*
Y1205184D03*
X1710983Y1215223D03*
Y1221916D03*
X1715841Y1211877D03*
Y1218570D03*
Y1225263D03*
X1710983Y1231955D03*
Y1238648D03*
X1715841Y1235302D03*
Y1241995D03*
X1710983Y1245341D03*
X1715841Y1248688D03*
X1707514Y1273444D03*
X1718888Y1273344D03*
X1721688D03*
X1731983Y766798D03*
X1724541Y770144D03*
X1731983Y773491D03*
Y780184D03*
X1724541Y783530D03*
Y776837D03*
Y793570D03*
Y800263D03*
X1731983Y790223D03*
Y796916D03*
Y803609D03*
X1724541Y806955D03*
Y813648D03*
Y820341D03*
X1731983Y810302D03*
Y816995D03*
X1724541Y830381D03*
X1731983Y827034D03*
Y833727D03*
X1724541Y837074D03*
Y843766D03*
Y850459D03*
X1731983Y840420D03*
Y847113D03*
X1724541Y857152D03*
Y867192D03*
X1731983Y853806D03*
Y863845D03*
X1724541Y873885D03*
Y880577D03*
X1731983Y870538D03*
Y877231D03*
Y883924D03*
X1724541Y893963D03*
Y887270D03*
X1731983Y890617D03*
Y900656D03*
X1724541Y904003D03*
Y910696D03*
Y917389D03*
X1731983Y907349D03*
Y914042D03*
X1724541Y924081D03*
Y930774D03*
X1731983Y920735D03*
Y927428D03*
X1724541Y940814D03*
Y947507D03*
X1731983Y937467D03*
Y944160D03*
X1724541Y954200D03*
Y964239D03*
X1731983Y950853D03*
Y960892D03*
X1724541Y970932D03*
Y977625D03*
X1731983Y967585D03*
Y974278D03*
Y980971D03*
X1724541Y984318D03*
Y991011D03*
X1731983Y987664D03*
X1724541Y1017782D03*
Y1024475D03*
Y1031168D03*
X1731983Y1017782D03*
Y1027822D03*
X1724541Y1037861D03*
Y1044554D03*
X1731983Y1034515D03*
Y1041207D03*
Y1047900D03*
X1724541Y1057940D03*
X1731983Y1054593D03*
Y1061286D03*
X1724541Y1071326D03*
Y1064633D03*
Y1078018D03*
X1731983Y1074672D03*
Y1067979D03*
X1724541Y1088058D03*
Y1094751D03*
X1731983Y1084711D03*
Y1091404D03*
X1724541Y1101444D03*
Y1108137D03*
X1731983Y1098097D03*
Y1104790D03*
Y1111483D03*
X1724541Y1114829D03*
Y1124869D03*
X1731983Y1121522D03*
Y1128215D03*
X1724541Y1131562D03*
Y1138255D03*
Y1144948D03*
X1731983Y1134908D03*
Y1141601D03*
X1724541Y1151641D03*
Y1161680D03*
X1731983Y1148294D03*
Y1158333D03*
X1724541Y1168373D03*
Y1175066D03*
X1731983Y1165026D03*
Y1171719D03*
X1724541Y1181759D03*
Y1188452D03*
X1731983Y1178412D03*
Y1185105D03*
X1724541Y1198491D03*
Y1205184D03*
X1731983Y1195144D03*
Y1201837D03*
Y1208530D03*
X1724541Y1211877D03*
Y1218570D03*
Y1225263D03*
X1731983Y1215223D03*
Y1221916D03*
X1724541Y1235302D03*
Y1241995D03*
X1731983Y1231955D03*
Y1238648D03*
X1724541Y1248688D03*
X1724588Y1257164D03*
X1731983Y1245341D03*
X1734888Y1273344D03*
X1737688D03*
X1740683Y766798D03*
X1745541Y770144D03*
X1754241D03*
X1740683Y773491D03*
Y780184D03*
X1745541Y776837D03*
X1754241D03*
X1745541Y783530D03*
X1754241D03*
X1740683Y790223D03*
Y796916D03*
Y803609D03*
X1745541Y793570D03*
X1754241D03*
X1745541Y800263D03*
X1754241D03*
X1740683Y810302D03*
Y816995D03*
X1745541Y806955D03*
X1754241D03*
X1745541Y813648D03*
X1754241D03*
X1745541Y820341D03*
X1754241D03*
X1740683Y827034D03*
Y833727D03*
X1745541Y830381D03*
X1754241D03*
X1740683Y840420D03*
Y847113D03*
X1754241Y843766D03*
X1745541D03*
Y837074D03*
X1754241D03*
X1745541Y850459D03*
X1754241D03*
X1740683Y853806D03*
Y863845D03*
X1745541Y857152D03*
X1754241D03*
Y867192D03*
X1745541D03*
X1740683Y870538D03*
Y877231D03*
Y883924D03*
X1745541Y873885D03*
X1754241D03*
X1745541Y880577D03*
X1754241D03*
X1740683Y890617D03*
Y900656D03*
X1754241Y893963D03*
X1745541D03*
Y887270D03*
X1754241D03*
X1740683Y907349D03*
Y914042D03*
X1754241Y904003D03*
X1745541D03*
X1754241Y910696D03*
X1745541D03*
X1754241Y917389D03*
X1745541D03*
X1740683Y920735D03*
Y927428D03*
X1754241Y924081D03*
X1745541D03*
X1754241Y930774D03*
X1745541D03*
X1740683Y937467D03*
Y944160D03*
X1754241Y940814D03*
X1745541D03*
X1754241Y947507D03*
X1745541D03*
X1740683Y950853D03*
Y960892D03*
X1754241Y954200D03*
X1745541D03*
X1754241Y964239D03*
X1745541D03*
X1740683Y967585D03*
Y974278D03*
Y980971D03*
X1754241Y970932D03*
X1745541D03*
X1754241Y977625D03*
X1745541D03*
X1740683Y987664D03*
X1754241Y984318D03*
X1745541D03*
X1754241Y991011D03*
X1745541D03*
X1740683Y1017782D03*
Y1027822D03*
X1754241Y1017782D03*
X1745541D03*
Y1024475D03*
X1754241D03*
X1745541Y1031168D03*
X1754241D03*
X1740683Y1034515D03*
Y1041207D03*
Y1047900D03*
X1754241Y1044554D03*
X1745541D03*
Y1037861D03*
X1754241D03*
X1740683Y1054593D03*
Y1061286D03*
X1745541Y1051247D03*
X1754241D03*
X1745541Y1057940D03*
X1754241D03*
X1740683Y1074672D03*
Y1067979D03*
X1754241Y1071326D03*
X1745541D03*
Y1064633D03*
X1754241D03*
Y1078018D03*
X1745541D03*
X1740683Y1084711D03*
Y1091404D03*
X1754241Y1088058D03*
X1745541D03*
X1754241Y1094751D03*
X1745541D03*
X1740683Y1098097D03*
Y1104790D03*
Y1111483D03*
X1754241Y1101444D03*
X1745541D03*
X1754241Y1108137D03*
X1745541D03*
X1740683Y1121522D03*
Y1128215D03*
X1754241Y1114829D03*
X1745541D03*
X1754241Y1124869D03*
X1745541D03*
X1740683Y1134908D03*
Y1141601D03*
X1754241Y1131562D03*
X1745541D03*
X1754241Y1138255D03*
X1745541D03*
X1754241Y1144948D03*
X1745541D03*
X1740683Y1148294D03*
Y1158333D03*
X1754241Y1151641D03*
X1745541D03*
X1754241Y1161680D03*
X1745541D03*
X1740683Y1165026D03*
Y1171719D03*
X1745541Y1175066D03*
X1754241D03*
Y1168373D03*
X1745541D03*
X1740683Y1178412D03*
Y1185105D03*
X1745541Y1181759D03*
X1754241D03*
Y1188452D03*
X1745541D03*
X1740683Y1195144D03*
Y1201837D03*
Y1208530D03*
X1754241Y1198491D03*
X1745541D03*
X1754241Y1205184D03*
X1745541D03*
X1740683Y1215223D03*
Y1221916D03*
X1754241Y1211877D03*
X1745541D03*
X1754241Y1218570D03*
X1745541D03*
X1754241Y1225263D03*
X1745541D03*
X1740683Y1231955D03*
Y1238648D03*
X1754241Y1235302D03*
X1745541D03*
X1754241Y1241995D03*
X1745541D03*
X1740683Y1245341D03*
X1754241Y1248688D03*
X1745541D03*
X1754488Y1257264D03*
X1751388Y1273344D03*
X1748588D03*
X1749088Y1310474D03*
X1746288D03*
X1770383Y766798D03*
X1761683D03*
X1770383Y773491D03*
X1761683D03*
Y780184D03*
X1770383D03*
X1761683Y790223D03*
X1770383D03*
X1761683Y796916D03*
X1770383D03*
X1761683Y803609D03*
X1770383D03*
X1761683Y810302D03*
X1770383D03*
X1761683Y816995D03*
X1770383D03*
X1761683Y827034D03*
X1770383D03*
X1761683Y833727D03*
X1770383D03*
X1761683Y840420D03*
X1770383D03*
X1761683Y847113D03*
X1770383D03*
X1761683Y853806D03*
X1770383D03*
X1761683Y863845D03*
X1770383D03*
X1761683Y870538D03*
X1770383D03*
X1761683Y877231D03*
X1770383D03*
X1761683Y883924D03*
X1770383D03*
X1761683Y890617D03*
X1770383D03*
X1761683Y900656D03*
X1770383D03*
X1761683Y907349D03*
X1770383D03*
X1761683Y914042D03*
X1770383D03*
Y927428D03*
X1761683D03*
Y920735D03*
X1770383D03*
X1761683Y937467D03*
X1770383D03*
X1761683Y944160D03*
X1770383D03*
X1761683Y950853D03*
X1770383D03*
X1761683Y960892D03*
X1770383D03*
X1761683Y967585D03*
X1770383D03*
X1761683Y974278D03*
X1770383D03*
X1761683Y980971D03*
X1770383D03*
X1761683Y987664D03*
X1770383D03*
X1761683Y1017782D03*
X1770383D03*
X1761683Y1027822D03*
X1770383D03*
X1761683Y1034515D03*
X1770383D03*
X1761683Y1041207D03*
X1770383D03*
X1761683Y1047900D03*
X1770383D03*
X1761683Y1054593D03*
X1770383D03*
X1761683Y1061286D03*
X1770383D03*
X1761683Y1067979D03*
X1770383D03*
X1761683Y1074672D03*
X1770383D03*
X1761683Y1084711D03*
X1770383D03*
X1761683Y1091404D03*
X1770383D03*
Y1098097D03*
X1761683D03*
Y1104790D03*
X1770383D03*
X1761683Y1111483D03*
X1770383D03*
X1761683Y1121522D03*
X1770383D03*
X1761683Y1128215D03*
X1770383D03*
X1761683Y1134908D03*
X1770383D03*
X1761683Y1141601D03*
X1770383D03*
X1761683Y1148294D03*
X1770383D03*
X1761683Y1158333D03*
X1770383D03*
X1761683Y1165026D03*
X1770383D03*
X1761683Y1171719D03*
X1770383D03*
X1761683Y1178412D03*
X1770383D03*
X1761683Y1185105D03*
X1770383D03*
X1761683Y1195144D03*
X1770383D03*
X1761683Y1201837D03*
X1770383D03*
X1761683Y1208530D03*
X1770383D03*
X1761683Y1215223D03*
X1770383D03*
X1761683Y1221916D03*
X1770383D03*
X1761683Y1231955D03*
X1770383D03*
X1761683Y1238648D03*
X1770383D03*
X1761683Y1245341D03*
X1770383D03*
X1767388Y1273344D03*
X1764588D03*
X1775241Y770144D03*
X1783941D03*
X1775241Y776837D03*
X1783941D03*
X1775241Y783530D03*
X1783941D03*
X1775241Y793570D03*
X1783941D03*
X1775241Y800263D03*
X1783941D03*
X1775241Y806955D03*
X1783941D03*
X1775241Y813648D03*
X1783941D03*
X1775241Y820341D03*
X1783941D03*
Y830381D03*
X1775241D03*
Y837074D03*
X1783941D03*
X1775241Y843766D03*
X1783941D03*
X1775241Y850459D03*
X1783941D03*
X1775241Y857152D03*
X1783941D03*
X1775241Y867192D03*
X1783941D03*
X1775241Y873885D03*
X1783941D03*
X1775241Y880577D03*
X1783941D03*
X1775241Y887270D03*
X1783941D03*
X1775241Y893963D03*
X1783941D03*
X1775241Y904003D03*
X1783941D03*
X1775241Y910696D03*
X1783941D03*
X1775241Y917389D03*
X1783941D03*
X1775241Y924081D03*
X1783941D03*
X1775241Y930774D03*
X1783941D03*
X1775241Y940814D03*
X1783941D03*
X1775241Y947507D03*
X1783941D03*
X1775241Y954200D03*
X1783941D03*
X1775241Y964239D03*
X1783941D03*
X1775241Y970932D03*
X1783941D03*
X1775241Y977625D03*
X1783941D03*
X1775241Y984318D03*
X1783941D03*
X1775241Y991011D03*
X1783941D03*
X1775241Y1017782D03*
X1783941D03*
X1775241Y1024475D03*
X1783941D03*
X1775241Y1031168D03*
X1783941D03*
X1775241Y1037861D03*
X1783941D03*
X1775241Y1044554D03*
X1783941D03*
X1775241Y1051247D03*
X1783941D03*
X1775241Y1057940D03*
X1783941D03*
X1775241Y1064633D03*
X1783941D03*
X1775241Y1071326D03*
X1783941D03*
X1775241Y1078018D03*
X1783941D03*
X1775241Y1088058D03*
X1783941D03*
X1775241Y1094751D03*
X1783941D03*
X1775241Y1101444D03*
X1783941D03*
X1775241Y1108137D03*
X1783941D03*
X1775241Y1114829D03*
X1783941D03*
X1775241Y1124869D03*
X1783941D03*
X1775241Y1131562D03*
X1783941D03*
X1775241Y1138255D03*
X1783941D03*
X1775241Y1144948D03*
X1783941D03*
Y1151641D03*
X1775241D03*
Y1161680D03*
X1783941D03*
X1775241Y1168373D03*
X1783941D03*
X1775241Y1175066D03*
X1783941D03*
X1775241Y1181759D03*
X1783941D03*
X1775241Y1188452D03*
X1783941D03*
X1775241Y1198491D03*
X1783941D03*
X1775241Y1205184D03*
X1783941D03*
X1775241Y1211877D03*
X1783941D03*
X1775241Y1218570D03*
X1783941D03*
X1775241Y1225263D03*
X1783941D03*
X1775241Y1235302D03*
X1783941D03*
X1775241Y1241995D03*
X1783941D03*
X1784188Y1257664D03*
X1775241Y1248688D03*
X1783941D03*
X1781088Y1273344D03*
X1778288D03*
X1791383Y766798D03*
X1800083D03*
X1791383Y773491D03*
X1800083D03*
X1791383Y780184D03*
X1800083D03*
X1791383Y790223D03*
X1800083D03*
X1791383Y796916D03*
X1800083D03*
X1791383Y803609D03*
X1800083D03*
X1791383Y810302D03*
X1800083D03*
X1791383Y816995D03*
X1800083D03*
X1791383Y827034D03*
X1800083D03*
Y833727D03*
X1791383D03*
Y840420D03*
X1800083D03*
X1791383Y847113D03*
X1800083D03*
X1791383Y853806D03*
X1800083D03*
X1791383Y863845D03*
X1800083D03*
X1791383Y870538D03*
X1800083D03*
X1791383Y877231D03*
X1800083D03*
X1791383Y883924D03*
X1800083D03*
X1791383Y890617D03*
X1800083D03*
X1791383Y900656D03*
X1800083D03*
X1791383Y907349D03*
X1800083D03*
X1791383Y914042D03*
X1800083D03*
X1791383Y920735D03*
X1800083D03*
X1791383Y927428D03*
X1800083D03*
X1791383Y937467D03*
X1800083D03*
X1791383Y944160D03*
X1800083D03*
Y950853D03*
X1791383D03*
Y960892D03*
X1800083D03*
X1791383Y967585D03*
X1800083D03*
X1791383Y974278D03*
X1800083D03*
X1791383Y980971D03*
X1800083D03*
X1791383Y987664D03*
X1800083D03*
X1791383Y1017782D03*
X1800083D03*
X1791383Y1027822D03*
X1800083D03*
X1791383Y1034515D03*
X1800083D03*
X1791383Y1041207D03*
X1800083D03*
X1791383Y1047900D03*
X1800083D03*
X1791383Y1054593D03*
X1800083D03*
X1791383Y1061286D03*
X1800083D03*
X1791383Y1067979D03*
X1800083D03*
X1791383Y1074672D03*
X1800083D03*
X1791383Y1084711D03*
X1800083D03*
X1791383Y1091404D03*
X1800083D03*
X1791383Y1098097D03*
X1800083D03*
X1791383Y1104790D03*
X1800083D03*
X1791383Y1111483D03*
X1800083D03*
X1791383Y1121522D03*
X1800083D03*
X1791383Y1128215D03*
X1800083D03*
Y1134908D03*
X1791383D03*
Y1141601D03*
X1800083D03*
X1791383Y1148294D03*
X1800083D03*
X1791383Y1158333D03*
X1800083D03*
X1791383Y1165026D03*
X1800083D03*
X1791383Y1171719D03*
X1800083D03*
X1791383Y1178412D03*
X1800083D03*
X1791383Y1185105D03*
X1800083D03*
X1791383Y1195144D03*
X1800083D03*
X1791383Y1201837D03*
X1800083D03*
X1791383Y1208530D03*
X1800083D03*
X1791383Y1215223D03*
X1800083D03*
X1791383Y1221916D03*
X1800083D03*
X1791383Y1231955D03*
X1800083D03*
X1791383Y1238648D03*
X1800083D03*
X1791383Y1245341D03*
X1800083D03*
X1797088Y1273344D03*
X1794288D03*
X1804941Y770144D03*
X1813641D03*
X1804941Y776837D03*
X1813641D03*
X1804941Y783530D03*
X1813641D03*
X1804941Y793570D03*
X1813641D03*
X1804941Y800263D03*
X1813641D03*
X1804941Y806955D03*
X1813641D03*
X1804941Y813648D03*
X1813641D03*
X1804941Y820341D03*
X1813641D03*
X1804941Y830381D03*
X1813641D03*
X1804941Y843766D03*
X1813641D03*
X1804941Y837074D03*
X1813641D03*
X1804941Y850459D03*
X1813641D03*
X1804941Y857152D03*
X1813641D03*
Y867192D03*
X1804941D03*
Y873885D03*
X1813641D03*
X1804941Y880577D03*
X1813641D03*
X1804941Y887270D03*
X1813641D03*
X1804941Y893963D03*
X1813641D03*
X1804941Y904003D03*
X1813641D03*
X1804941Y910696D03*
X1813641D03*
X1804941Y917389D03*
X1813641D03*
X1804941Y924081D03*
X1813641D03*
X1804941Y930774D03*
X1813641D03*
X1804941Y940814D03*
X1813641D03*
X1804941Y947507D03*
X1813641D03*
X1804941Y954200D03*
X1813641D03*
X1804941Y964239D03*
X1813641D03*
X1804941Y970932D03*
X1813641D03*
X1804941Y977625D03*
X1813641D03*
X1804941Y984318D03*
X1813641D03*
X1804941Y991011D03*
X1813641D03*
X1804941Y1017782D03*
X1813641D03*
X1804941Y1024475D03*
X1813641D03*
X1804941Y1031168D03*
X1813641D03*
X1804941Y1037861D03*
X1813641D03*
X1804941Y1044554D03*
X1813641D03*
Y1057940D03*
X1804941D03*
Y1051247D03*
X1813641D03*
X1804941Y1064633D03*
X1813641D03*
Y1071326D03*
X1804941D03*
X1813641Y1078018D03*
X1804941D03*
X1813641Y1088058D03*
X1804941D03*
X1813641Y1094751D03*
X1804941D03*
X1813641Y1101444D03*
X1804941D03*
X1813641Y1108137D03*
X1804941D03*
X1813641Y1114829D03*
X1804941D03*
X1813641Y1124869D03*
X1804941D03*
X1813641Y1131562D03*
X1804941D03*
X1813641Y1138255D03*
X1804941D03*
X1813641Y1144948D03*
X1804941D03*
X1813641Y1151641D03*
X1804941D03*
X1813641Y1161680D03*
X1804941D03*
X1813641Y1168373D03*
X1804941D03*
X1813641Y1175066D03*
X1804941D03*
X1813641Y1181759D03*
X1804941D03*
X1813641Y1188452D03*
X1804941D03*
X1813641Y1198491D03*
X1804941D03*
X1813641Y1205184D03*
X1804941D03*
X1813641Y1211877D03*
X1804941D03*
X1813641Y1218570D03*
X1804941D03*
X1813641Y1225263D03*
X1804941D03*
X1813641Y1235302D03*
X1804941D03*
X1813641Y1241995D03*
X1804941D03*
X1813641Y1248688D03*
X1804941D03*
X1819054Y1253986D03*
X1818188Y1273044D03*
X1810788Y1273344D03*
X1807988D03*
X1815388Y1273044D03*
X1829783Y766798D03*
X1821083D03*
X1829783Y773491D03*
X1821083D03*
X1829783Y780184D03*
X1821083D03*
X1829783Y790223D03*
X1821083D03*
X1829783Y796916D03*
X1821083D03*
X1829783Y803609D03*
X1821083D03*
X1829783Y810302D03*
X1821083D03*
X1829783Y816995D03*
X1821083D03*
X1829783Y827034D03*
X1821083D03*
X1829783Y833727D03*
X1821083D03*
Y847113D03*
X1829783D03*
Y840420D03*
X1821083D03*
X1829783Y853806D03*
X1821083D03*
X1829783Y863845D03*
X1821083D03*
X1829783Y870538D03*
X1821083D03*
X1829783Y877231D03*
X1821083D03*
X1829783Y883924D03*
X1821083D03*
X1829783Y890617D03*
X1821083D03*
X1829783Y900656D03*
X1821083D03*
X1829783Y907349D03*
X1821083D03*
X1829783Y914042D03*
X1821083D03*
X1829783Y920735D03*
X1821083D03*
X1829783Y927428D03*
X1821083D03*
X1829783Y937467D03*
X1821083D03*
X1829783Y944160D03*
X1821083D03*
X1829783Y950853D03*
X1821083D03*
X1829783Y960892D03*
X1821083D03*
X1829783Y967585D03*
X1821083D03*
X1829783Y974278D03*
X1821083D03*
X1829783Y980971D03*
X1821083D03*
X1829783Y987664D03*
X1821083D03*
X1829783Y1017782D03*
X1821083D03*
X1829783Y1027822D03*
X1821083D03*
X1829783Y1034515D03*
X1821083D03*
X1829783Y1041207D03*
X1821083D03*
X1829783Y1047900D03*
X1821083D03*
X1829783Y1054593D03*
X1821083D03*
X1829783Y1061286D03*
X1821083D03*
X1829783Y1067979D03*
X1821083D03*
Y1074672D03*
X1829783D03*
X1821083Y1084711D03*
X1829783D03*
X1821083Y1091404D03*
X1829783D03*
X1821083Y1098097D03*
X1829783D03*
X1821083Y1104790D03*
X1829783D03*
X1821083Y1111483D03*
X1829783D03*
X1821083Y1121522D03*
X1829783D03*
X1821083Y1128215D03*
X1829783D03*
X1821083Y1134908D03*
X1829783D03*
X1821083Y1141601D03*
X1829783D03*
X1821083Y1148294D03*
X1829783D03*
X1821083Y1158333D03*
X1829783D03*
X1821083Y1165026D03*
X1829783D03*
X1821083Y1171719D03*
X1829783D03*
X1821083Y1178412D03*
X1829783D03*
X1821083Y1185105D03*
X1829783D03*
X1821083Y1195144D03*
X1829783D03*
X1821083Y1201837D03*
X1829783D03*
X1821083Y1208530D03*
X1829783D03*
X1821083Y1215223D03*
X1829783D03*
X1821083Y1221916D03*
X1829783D03*
X1821083Y1231955D03*
X1829783D03*
X1821083Y1238648D03*
X1829783D03*
Y1245341D03*
X1821083D03*
G54D57*
X841240Y1420330D03*
X1016240D03*
G54D63*
X986642Y-27947D03*
X986627Y-25432D03*
Y-21558D03*
X986642Y-17918D03*
X986627Y-15403D03*
Y-11529D03*
X986642Y-7889D03*
X986627Y-5374D03*
Y4655D03*
X986642Y2140D03*
X986627Y14684D03*
X986642Y12169D03*
X986627Y8529D03*
X986642Y22698D03*
X989910Y22684D03*
X986627Y19058D03*
Y25213D03*
X989895Y25199D03*
X1296019Y-35472D03*
Y-31598D03*
X1296034Y-37987D03*
Y-27958D03*
X1296019Y-25443D03*
Y-21569D03*
X1296034Y-17929D03*
X1296019Y-15414D03*
Y-11540D03*
X1296034Y-7900D03*
X1296019Y-5385D03*
Y4644D03*
X1296034Y2129D03*
X1296019Y-1511D03*
Y14673D03*
X1296034Y12158D03*
X1296019Y8518D03*
X1296034Y22687D03*
X1296019Y19047D03*
Y25202D03*
X1299302Y22673D03*
X1299287Y25188D03*
X1488393Y-27958D03*
X1488378Y-25443D03*
X1488393Y-37987D03*
X1488378Y-35472D03*
Y-31598D03*
X1488393Y-17929D03*
X1488378Y-15414D03*
Y-11540D03*
Y-21569D03*
X1488393Y2129D03*
X1488378Y4644D03*
X1488393Y-7900D03*
X1488378Y-5385D03*
Y-1511D03*
Y14673D03*
X1488393Y12158D03*
Y22687D03*
X1491661Y22673D03*
X1488378Y8518D03*
Y19047D03*
Y25202D03*
X1491646Y25188D03*
G54D71*
X1879155Y344948D03*
Y592848D03*
X1900275Y-19342D03*
X1889155Y344948D03*
Y592848D03*
X1900275Y716808D03*
X1910275Y-19342D03*
Y716808D03*
X1931395Y592868D03*
X1921395D03*
X1952395Y-19152D03*
X1942395D03*
X1963362Y593010D03*
X1984482Y-19180D03*
X1973362Y593010D03*
X1994482Y-19180D03*
X2015452Y593020D03*
X2005452D03*
X2026452Y-19000D03*
X2036452D03*
X2047419Y593162D03*
X2057419D03*
G54D25*
X57646Y12480D03*
X137272D03*
X186622D03*
X266858D03*
X315598D03*
X502528Y33268D03*
X582154D03*
X631504D03*
X711740D03*
X760480D03*
X1532055Y12480D03*
X1611681D03*
X1661031D03*
X1741267D03*
X1790007D03*
G54D64*
X1077638Y133866D03*
G54D46*
X460000Y278543D03*
G54D69*
X1771457Y1634646D03*
G54D58*
X900196Y175197D03*
X944684Y155216D03*
G54D78*
X1903086Y1318228D03*
X1902402Y1683256D03*
X1950484Y1683497D03*
X1993147Y1682875D03*
G54D76*
X1880836Y1317164D03*
X1881165Y1682207D03*
X1929695Y1683220D03*
X1971555Y1683130D03*
%LPC*%
G75*
G54D79*
G01X-6350Y-464479D02*
Y-539479D01*
X493650D01*
Y-464479D01*
X-6350D01*
G01X5650Y-529479D02*
Y-534479D01*
G01X4193Y-529479D02*
X7107D01*
G01X12017Y-534479D02*
X9483D01*
Y-529479D01*
X12017D01*
G01X11003Y-531896D02*
X9483D01*
G01X14583Y-529479D02*
Y-534479D01*
X17117D01*
G01X20950Y-534646D02*
X20823Y-534562D01*
Y-534396D01*
X20950Y-534312D01*
X21077Y-534396D01*
Y-534562D01*
X20950Y-534646D01*
G01Y-532396D02*
X20823Y-532312D01*
Y-532146D01*
X20950Y-532062D01*
X21077Y-532146D01*
Y-532312D01*
X20950Y-532396D01*
G01X25733Y-536146D02*
X25100Y-535312D01*
X24783Y-534479D01*
Y-531146D01*
X25100Y-530312D01*
X25733Y-529479D01*
G01X31150D02*
X30643Y-529646D01*
X30263Y-530062D01*
X30010Y-530562D01*
X29820Y-531229D01*
X29757Y-531979D01*
X29820Y-532729D01*
X30010Y-533396D01*
X30263Y-533896D01*
X30643Y-534312D01*
X31150Y-534479D01*
X31657Y-534312D01*
X32037Y-533896D01*
X32290Y-533396D01*
X32480Y-532729D01*
X32543Y-531979D01*
X32480Y-531229D01*
X32290Y-530562D01*
X32037Y-530062D01*
X31657Y-529646D01*
X31150Y-529479D01*
G01X34857Y-533479D02*
X35237Y-534062D01*
X35743Y-534396D01*
X36313Y-534479D01*
X36820Y-534396D01*
X37327Y-533979D01*
X37643Y-533479D01*
X37707Y-532979D01*
X37580Y-532396D01*
X37137Y-531979D01*
X36693Y-531812D01*
X36123D01*
G01X36693D02*
X37073Y-531562D01*
X37390Y-531146D01*
X37517Y-530646D01*
X37390Y-530146D01*
X37073Y-529729D01*
X36503Y-529479D01*
X35933Y-529562D01*
X35363Y-529896D01*
G01X41667Y-536146D02*
X42300Y-535312D01*
X42617Y-534479D01*
Y-531146D01*
X42300Y-530312D01*
X41667Y-529479D01*
G01X45057Y-533479D02*
X45437Y-534062D01*
X45943Y-534396D01*
X46513Y-534479D01*
X47020Y-534396D01*
X47527Y-533979D01*
X47843Y-533479D01*
X47907Y-532979D01*
X47780Y-532396D01*
X47337Y-531979D01*
X46893Y-531812D01*
X46323D01*
G01X46893D02*
X47273Y-531562D01*
X47590Y-531146D01*
X47717Y-530646D01*
X47590Y-530146D01*
X47273Y-529729D01*
X46703Y-529479D01*
X46133Y-529562D01*
X45563Y-529896D01*
G01X50347Y-530312D02*
X50727Y-529812D01*
X51170Y-529562D01*
X51677Y-529479D01*
X52310Y-529646D01*
X52753Y-530062D01*
X52880Y-530562D01*
X52817Y-531062D01*
X52563Y-531479D01*
X51297Y-532312D01*
X50727Y-532896D01*
X50347Y-533729D01*
X50220Y-534479D01*
X52880D01*
G01X56523D02*
X56650Y-533396D01*
X56840Y-532479D01*
X57093Y-531646D01*
X57410Y-530729D01*
X57917Y-529479D01*
X55383D01*
G01X60927Y-532812D02*
X62573D01*
G01X65647Y-530312D02*
X66027Y-529812D01*
X66470Y-529562D01*
X66977Y-529479D01*
X67610Y-529646D01*
X68053Y-530062D01*
X68180Y-530562D01*
X68117Y-531062D01*
X67863Y-531479D01*
X66597Y-532312D01*
X66027Y-532896D01*
X65647Y-533729D01*
X65520Y-534479D01*
X68180D01*
G01X70557Y-533479D02*
X70937Y-534062D01*
X71443Y-534396D01*
X72013Y-534479D01*
X72520Y-534396D01*
X73027Y-533979D01*
X73343Y-533479D01*
X73407Y-532979D01*
X73280Y-532396D01*
X72837Y-531979D01*
X72393Y-531812D01*
X71823D01*
G01X72393D02*
X72773Y-531562D01*
X73090Y-531146D01*
X73217Y-530646D01*
X73090Y-530146D01*
X72773Y-529729D01*
X72203Y-529479D01*
X71633Y-529562D01*
X71063Y-529896D01*
G01X77810Y-534479D02*
Y-529479D01*
X75467Y-533062D01*
X78633D01*
G01X80757Y-533729D02*
X81137Y-534146D01*
X81580Y-534396D01*
X82150Y-534479D01*
X82720Y-534312D01*
X83163Y-533979D01*
X83480Y-533396D01*
X83543Y-532729D01*
X83417Y-532062D01*
X83100Y-531646D01*
X82657Y-531312D01*
X82213Y-531229D01*
X81770Y-531312D01*
X81200Y-531646D01*
X81390Y-529479D01*
X83100D01*
G01X91147Y-534479D02*
Y-529479D01*
X93553D01*
G01X92667Y-531896D02*
X91147D01*
G01X95867Y-534479D02*
X97450Y-529479D01*
X99033Y-534479D01*
G01X98463Y-532729D02*
X96437D01*
G01X101220Y-534479D02*
X103880Y-529479D01*
G01X101220D02*
X103880Y-534479D01*
G01X107650Y-534646D02*
X107523Y-534562D01*
Y-534396D01*
X107650Y-534312D01*
X107777Y-534396D01*
Y-534562D01*
X107650Y-534646D01*
G01Y-532396D02*
X107523Y-532312D01*
Y-532146D01*
X107650Y-532062D01*
X107777Y-532146D01*
Y-532312D01*
X107650Y-532396D01*
G01X112433Y-536146D02*
X111800Y-535312D01*
X111483Y-534479D01*
Y-531146D01*
X111800Y-530312D01*
X112433Y-529479D01*
G01X117850D02*
X117343Y-529646D01*
X116963Y-530062D01*
X116710Y-530562D01*
X116520Y-531229D01*
X116457Y-531979D01*
X116520Y-532729D01*
X116710Y-533396D01*
X116963Y-533896D01*
X117343Y-534312D01*
X117850Y-534479D01*
X118357Y-534312D01*
X118737Y-533896D01*
X118990Y-533396D01*
X119180Y-532729D01*
X119243Y-531979D01*
X119180Y-531229D01*
X118990Y-530562D01*
X118737Y-530062D01*
X118357Y-529646D01*
X117850Y-529479D01*
G01X121557Y-533479D02*
X121937Y-534062D01*
X122443Y-534396D01*
X123013Y-534479D01*
X123520Y-534396D01*
X124027Y-533979D01*
X124343Y-533479D01*
X124407Y-532979D01*
X124280Y-532396D01*
X123837Y-531979D01*
X123393Y-531812D01*
X122823D01*
G01X123393D02*
X123773Y-531562D01*
X124090Y-531146D01*
X124217Y-530646D01*
X124090Y-530146D01*
X123773Y-529729D01*
X123203Y-529479D01*
X122633Y-529562D01*
X122063Y-529896D01*
G01X128367Y-536146D02*
X129000Y-535312D01*
X129317Y-534479D01*
Y-531146D01*
X129000Y-530312D01*
X128367Y-529479D01*
G01X131757Y-533479D02*
X132137Y-534062D01*
X132643Y-534396D01*
X133213Y-534479D01*
X133720Y-534396D01*
X134227Y-533979D01*
X134543Y-533479D01*
X134607Y-532979D01*
X134480Y-532396D01*
X134037Y-531979D01*
X133593Y-531812D01*
X133023D01*
G01X133593D02*
X133973Y-531562D01*
X134290Y-531146D01*
X134417Y-530646D01*
X134290Y-530146D01*
X133973Y-529729D01*
X133403Y-529479D01*
X132833Y-529562D01*
X132263Y-529896D01*
G01X137173Y-533896D02*
X137617Y-534312D01*
X138123Y-534479D01*
X138630Y-534312D01*
X139073Y-533812D01*
X139390Y-533062D01*
X139517Y-532312D01*
Y-531396D01*
X139390Y-530646D01*
X139073Y-529979D01*
X138693Y-529646D01*
X138250Y-529479D01*
X137743Y-529646D01*
X137363Y-529979D01*
X137110Y-530479D01*
X136983Y-531146D01*
X137110Y-531729D01*
X137427Y-532312D01*
X137807Y-532646D01*
X138250Y-532729D01*
X138757Y-532562D01*
X139137Y-532146D01*
X139517Y-531396D01*
G01X143223Y-534479D02*
X143350Y-533396D01*
X143540Y-532479D01*
X143793Y-531646D01*
X144110Y-530729D01*
X144617Y-529479D01*
X142083D01*
G01X147627Y-532812D02*
X149273D01*
G01X152157Y-533479D02*
X152537Y-534062D01*
X153043Y-534396D01*
X153613Y-534479D01*
X154120Y-534396D01*
X154627Y-533979D01*
X154943Y-533479D01*
X155007Y-532979D01*
X154880Y-532396D01*
X154437Y-531979D01*
X153993Y-531812D01*
X153423D01*
G01X153993D02*
X154373Y-531562D01*
X154690Y-531146D01*
X154817Y-530646D01*
X154690Y-530146D01*
X154373Y-529729D01*
X153803Y-529479D01*
X153233Y-529562D01*
X152663Y-529896D01*
G01X157447Y-532396D02*
X157890Y-531812D01*
X158270Y-531479D01*
X158777Y-531312D01*
X159220Y-531479D01*
X159537Y-531812D01*
X159790Y-532312D01*
X159853Y-532896D01*
X159790Y-533396D01*
X159537Y-533896D01*
X159157Y-534312D01*
X158713Y-534479D01*
X158207Y-534312D01*
X157763Y-533812D01*
X157510Y-533062D01*
X157447Y-532229D01*
X157573Y-531146D01*
X157763Y-530562D01*
X158080Y-529979D01*
X158523Y-529562D01*
X158967Y-529479D01*
X159410Y-529646D01*
X159727Y-530062D01*
G01X163750Y-534479D02*
Y-529479D01*
X162990Y-530479D01*
G01Y-534479D02*
X164510D01*
G01X169610D02*
Y-529479D01*
X167267Y-533062D01*
X170433D01*
G01X188650Y-464479D02*
Y-539479D01*
G01Y-514479D02*
X291650D01*
Y-489479D01*
G01X188650D02*
X291650D01*
G01Y-464479D02*
Y-539479D01*
G01X293650Y-464479D02*
Y-539479D01*
G01X299157Y-524479D02*
Y-519479D01*
X300423D01*
X300930Y-519729D01*
X301310Y-520062D01*
X301627Y-520562D01*
X301880Y-521146D01*
X301943Y-521979D01*
X301880Y-522812D01*
X301627Y-523396D01*
X301310Y-523896D01*
X300930Y-524229D01*
X300423Y-524479D01*
X299157D01*
G01X304067D02*
X305650Y-519479D01*
X307233Y-524479D01*
G01X306663Y-522729D02*
X304637D01*
G01X310750Y-519479D02*
Y-524479D01*
G01X309293Y-519479D02*
X312207D01*
G01X317117Y-524479D02*
X314583D01*
Y-519479D01*
X317117D01*
G01X316103Y-521896D02*
X314583D01*
G01X320950Y-524646D02*
X320823Y-524562D01*
Y-524396D01*
X320950Y-524312D01*
X321077Y-524396D01*
Y-524562D01*
X320950Y-524646D01*
G01Y-522396D02*
X320823Y-522312D01*
Y-522146D01*
X320950Y-522062D01*
X321077Y-522146D01*
Y-522312D01*
X320950Y-522396D01*
G01X299283Y-499479D02*
Y-494479D01*
X300803D01*
X301310Y-494729D01*
X301690Y-495312D01*
X301817Y-495979D01*
X301690Y-496646D01*
X301373Y-497146D01*
X300803Y-497396D01*
X299283D01*
G01X304510Y-499646D02*
X306790Y-494479D01*
G01X309293Y-499479D02*
Y-494479D01*
X312207Y-499479D01*
Y-494479D01*
G01X315850Y-499646D02*
X315723Y-499562D01*
Y-499396D01*
X315850Y-499312D01*
X315977Y-499396D01*
Y-499562D01*
X315850Y-499646D01*
G01Y-497396D02*
X315723Y-497312D01*
Y-497146D01*
X315850Y-497062D01*
X315977Y-497146D01*
Y-497312D01*
X315850Y-497396D01*
G01X293650Y-514479D02*
X493650D01*
G01X293650Y-489479D02*
X493650D01*
G01X299283Y-474479D02*
Y-469479D01*
X300803D01*
X301310Y-469729D01*
X301690Y-470312D01*
X301817Y-470979D01*
X301690Y-471646D01*
X301373Y-472146D01*
X300803Y-472396D01*
X299283D01*
G01X304383Y-474479D02*
Y-469479D01*
X305967D01*
X306473Y-469729D01*
X306790Y-470062D01*
X306917Y-470729D01*
X306790Y-471396D01*
X306410Y-471812D01*
X305967Y-472062D01*
X304383D01*
G01X305967D02*
X306917Y-474479D01*
G01X310750D02*
X310243Y-474396D01*
X309800Y-474062D01*
X309420Y-473562D01*
X309167Y-472979D01*
X309040Y-472312D01*
Y-471646D01*
X309167Y-470979D01*
X309420Y-470396D01*
X309800Y-469896D01*
X310243Y-469562D01*
X310750Y-469479D01*
X311257Y-469562D01*
X311700Y-469896D01*
X312080Y-470396D01*
X312333Y-470979D01*
X312460Y-471646D01*
Y-472312D01*
X312333Y-472979D01*
X312080Y-473562D01*
X311700Y-474062D01*
X311257Y-474396D01*
X310750Y-474479D01*
G01X314583Y-473479D02*
X314900Y-473979D01*
X315280Y-474312D01*
X315723Y-474479D01*
X316230Y-474312D01*
X316610Y-473979D01*
X316990Y-473479D01*
X317117Y-472812D01*
Y-469479D01*
G01X322217Y-474479D02*
X319683D01*
Y-469479D01*
X322217D01*
G01X321203Y-471896D02*
X319683D01*
G01X327443Y-469896D02*
X327063Y-469646D01*
X326620Y-469479D01*
X326113D01*
X325543Y-469729D01*
X325100Y-470146D01*
X324783Y-470646D01*
X324530Y-471479D01*
X324467Y-472229D01*
X324593Y-472979D01*
X324783Y-473479D01*
X325163Y-473979D01*
X325607Y-474312D01*
X326050Y-474479D01*
X326493D01*
X326937Y-474312D01*
X327317Y-474062D01*
X327633Y-473729D01*
G01X331150Y-469479D02*
Y-474479D01*
G01X329693Y-469479D02*
X332607D01*
G01X336250Y-474646D02*
X336123Y-474562D01*
Y-474396D01*
X336250Y-474312D01*
X336377Y-474396D01*
Y-474562D01*
X336250Y-474646D01*
G01Y-472396D02*
X336123Y-472312D01*
Y-472146D01*
X336250Y-472062D01*
X336377Y-472146D01*
Y-472312D01*
X336250Y-472396D01*
G01X408650Y-514479D02*
Y-539479D01*
G01X411283Y-516979D02*
Y-521979D01*
X413817D01*
G01X416890Y-516979D02*
X418410D01*
G01X417650D02*
Y-521979D01*
G01X416890D02*
X418410D01*
G01X423257Y-519312D02*
X423510Y-519062D01*
X423700Y-518646D01*
X423827Y-518062D01*
X423700Y-517562D01*
X423447Y-517229D01*
X423003Y-516979D01*
X421293D01*
Y-521979D01*
X423383D01*
X423827Y-521646D01*
X424080Y-521146D01*
X424207Y-520562D01*
X424080Y-519979D01*
X423700Y-519479D01*
X423257Y-519312D01*
X421293D01*
G01X427850Y-522146D02*
X427723Y-522062D01*
Y-521896D01*
X427850Y-521812D01*
X427977Y-521896D01*
Y-522062D01*
X427850Y-522146D01*
G01Y-519896D02*
X427723Y-519812D01*
Y-519646D01*
X427850Y-519562D01*
X427977Y-519646D01*
Y-519812D01*
X427850Y-519896D01*
G01X451650Y-514479D02*
Y-539479D01*
G01Y-489479D02*
Y-514479D01*
G01X456663Y-541646D02*
X456770Y-541521D01*
X456850Y-541312D01*
X456903Y-541021D01*
X456850Y-540771D01*
X456743Y-540604D01*
X456557Y-540479D01*
X455837D01*
Y-542979D01*
X456717D01*
X456903Y-542812D01*
X457010Y-542562D01*
X457063Y-542271D01*
X457010Y-541979D01*
X456850Y-541729D01*
X456663Y-541646D01*
X455837D01*
G01X459130Y-542979D02*
Y-541312D01*
G01Y-541604D02*
X459023Y-541437D01*
X458863Y-541354D01*
X458677Y-541312D01*
X458490Y-541396D01*
X458330Y-541562D01*
X458223Y-541812D01*
X458170Y-542146D01*
X458223Y-542479D01*
X458330Y-542729D01*
X458490Y-542896D01*
X458677Y-542979D01*
X458863Y-542937D01*
X459023Y-542812D01*
X459130Y-542646D01*
G01X460450Y-542687D02*
X460583Y-542854D01*
X460770Y-542979D01*
X460930D01*
X461090Y-542896D01*
X461197Y-542771D01*
X461250Y-542604D01*
X461223Y-542354D01*
X461117Y-542229D01*
X460637Y-541979D01*
X460530Y-541687D01*
X460583Y-541479D01*
X460690Y-541354D01*
X460850Y-541312D01*
X461010Y-541354D01*
X461170Y-541479D01*
G01X462650Y-541854D02*
X463503D01*
X463423Y-541562D01*
X463290Y-541396D01*
X463103Y-541312D01*
X462917Y-541354D01*
X462757Y-541479D01*
X462650Y-541771D01*
X462597Y-542021D01*
Y-542271D01*
X462650Y-542521D01*
X462783Y-542771D01*
X462943Y-542937D01*
X463130Y-542979D01*
X463317Y-542896D01*
X463503Y-542646D01*
G01X464770Y-542979D02*
Y-540479D01*
G01Y-541729D02*
X464903Y-541479D01*
X465063Y-541354D01*
X465223Y-541312D01*
X465463Y-541396D01*
X465623Y-541562D01*
X465730Y-541854D01*
Y-542187D01*
X465677Y-542521D01*
X465570Y-542771D01*
X465383Y-542937D01*
X465223Y-542979D01*
X465063Y-542937D01*
X464903Y-542812D01*
X464770Y-542604D01*
G01X467450Y-542979D02*
X467290Y-542937D01*
X467130Y-542771D01*
X467023Y-542479D01*
X466970Y-542146D01*
X467023Y-541812D01*
X467130Y-541521D01*
X467290Y-541354D01*
X467450Y-541312D01*
X467610Y-541354D01*
X467770Y-541521D01*
X467877Y-541812D01*
X467903Y-542146D01*
X467877Y-542479D01*
X467770Y-542771D01*
X467610Y-542937D01*
X467450Y-542979D01*
G01X470130D02*
Y-541312D01*
G01Y-541604D02*
X470023Y-541437D01*
X469863Y-541354D01*
X469677Y-541312D01*
X469490Y-541396D01*
X469330Y-541562D01*
X469223Y-541812D01*
X469170Y-542146D01*
X469223Y-542479D01*
X469330Y-542729D01*
X469490Y-542896D01*
X469677Y-542979D01*
X469863Y-542937D01*
X470023Y-542812D01*
X470130Y-542646D01*
G01X471477Y-542979D02*
Y-541312D01*
G01Y-541646D02*
X471610Y-541479D01*
X471743Y-541354D01*
X471930Y-541312D01*
X472063Y-541354D01*
X472223Y-541479D01*
G01X474530Y-540479D02*
Y-542979D01*
G01Y-542604D02*
X474423Y-542812D01*
X474263Y-542937D01*
X474077Y-542979D01*
X473863Y-542896D01*
X473703Y-542687D01*
X473597Y-542437D01*
X473570Y-542146D01*
X473597Y-541854D01*
X473703Y-541604D01*
X473863Y-541396D01*
X474077Y-541312D01*
X474263Y-541354D01*
X474397Y-541437D01*
X474530Y-541604D01*
G01X477917Y-542979D02*
Y-540479D01*
X478583D01*
X478797Y-540604D01*
X478930Y-540771D01*
X478983Y-541104D01*
X478930Y-541437D01*
X478770Y-541646D01*
X478583Y-541771D01*
X477917D01*
G01X478583D02*
X478983Y-542979D01*
G01X480250Y-541854D02*
X481103D01*
X481023Y-541562D01*
X480890Y-541396D01*
X480703Y-541312D01*
X480517Y-541354D01*
X480357Y-541479D01*
X480250Y-541771D01*
X480197Y-542021D01*
Y-542271D01*
X480250Y-542521D01*
X480383Y-542771D01*
X480543Y-542937D01*
X480730Y-542979D01*
X480917Y-542896D01*
X481103Y-542646D01*
G01X482370Y-541312D02*
X482850Y-542979D01*
X483330Y-541312D01*
G01X485050Y-543062D02*
X484997Y-543021D01*
Y-542937D01*
X485050Y-542896D01*
X485103Y-542937D01*
Y-543021D01*
X485050Y-543062D01*
G01X487250Y-542979D02*
X487437Y-542937D01*
X487650Y-542812D01*
X487783Y-542604D01*
X487837Y-542312D01*
X487783Y-542021D01*
X487623Y-541771D01*
X487383Y-541646D01*
X487117D01*
X486957Y-541562D01*
X486823Y-541354D01*
X486770Y-541062D01*
X486850Y-540771D01*
X487037Y-540562D01*
X487250Y-540479D01*
X487463Y-540562D01*
X487650Y-540771D01*
X487730Y-541062D01*
X487677Y-541354D01*
X487543Y-541562D01*
X487383Y-541646D01*
X487117D01*
X486877Y-541771D01*
X486717Y-542021D01*
X486663Y-542312D01*
X486717Y-542604D01*
X486850Y-542812D01*
X487063Y-542937D01*
X487250Y-542979D01*
G01X489663Y-541646D02*
X489770Y-541521D01*
X489850Y-541312D01*
X489903Y-541021D01*
X489850Y-540771D01*
X489743Y-540604D01*
X489557Y-540479D01*
X488837D01*
Y-542979D01*
X489717D01*
X489903Y-542812D01*
X490010Y-542562D01*
X490063Y-542271D01*
X490010Y-541979D01*
X489850Y-541729D01*
X489663Y-541646D01*
X488837D01*
G01X455550Y-516979D02*
Y-521979D01*
G01X454093Y-516979D02*
X457007D01*
G01X460650Y-521979D02*
X460270Y-521896D01*
X459890Y-521562D01*
X459637Y-520979D01*
X459510Y-520312D01*
X459637Y-519646D01*
X459890Y-519062D01*
X460270Y-518729D01*
X460650Y-518646D01*
X461030Y-518729D01*
X461410Y-519062D01*
X461663Y-519646D01*
X461727Y-520312D01*
X461663Y-520979D01*
X461410Y-521562D01*
X461030Y-521896D01*
X460650Y-521979D01*
G01X465750D02*
X465370Y-521896D01*
X464990Y-521562D01*
X464737Y-520979D01*
X464610Y-520312D01*
X464737Y-519646D01*
X464990Y-519062D01*
X465370Y-518729D01*
X465750Y-518646D01*
X466130Y-518729D01*
X466510Y-519062D01*
X466763Y-519646D01*
X466827Y-520312D01*
X466763Y-520979D01*
X466510Y-521562D01*
X466130Y-521896D01*
X465750Y-521979D01*
G01X470850D02*
Y-516979D01*
G01X475950Y-522146D02*
X475823Y-522062D01*
Y-521896D01*
X475950Y-521812D01*
X476077Y-521896D01*
Y-522062D01*
X475950Y-522146D01*
G01Y-519896D02*
X475823Y-519812D01*
Y-519646D01*
X475950Y-519562D01*
X476077Y-519646D01*
Y-519812D01*
X475950Y-519896D01*
G01X454283Y-496979D02*
Y-491979D01*
X455867D01*
X456373Y-492229D01*
X456690Y-492562D01*
X456817Y-493229D01*
X456690Y-493896D01*
X456310Y-494312D01*
X455867Y-494562D01*
X454283D01*
G01X455867D02*
X456817Y-496979D01*
G01X461917D02*
X459383D01*
Y-491979D01*
X461917D01*
G01X460903Y-494396D02*
X459383D01*
G01X464167Y-491979D02*
X465750Y-496979D01*
X467333Y-491979D01*
G01X470850Y-497146D02*
X470723Y-497062D01*
Y-496896D01*
X470850Y-496812D01*
X470977Y-496896D01*
Y-497062D01*
X470850Y-497146D01*
G01Y-494896D02*
X470723Y-494812D01*
Y-494646D01*
X470850Y-494562D01*
X470977Y-494646D01*
Y-494812D01*
X470850Y-494896D01*
G01X-984580Y-698988D02*
Y4193602D01*
X5868320D01*
Y-698988D01*
X-984580D01*
G01X7723Y-521204D02*
X7253Y-520889D01*
X6705Y-520679D01*
X6078D01*
X5373Y-520994D01*
X4825Y-521519D01*
X4433Y-522149D01*
X4120Y-523199D01*
X4042Y-524144D01*
X4198Y-525089D01*
X4433Y-525719D01*
X4903Y-526349D01*
X5452Y-526769D01*
X6000Y-526979D01*
X6548D01*
X7097Y-526769D01*
X7567Y-526454D01*
X7958Y-526034D01*
G01X11360Y-520679D02*
X13240D01*
G01X12300D02*
Y-526979D01*
G01X11360D02*
X13240D01*
G01X18600Y-520679D02*
Y-526979D01*
G01X16798Y-520679D02*
X20402D01*
G01X24900Y-526979D02*
Y-524144D01*
X23333Y-520679D01*
G01X26467D02*
X24900Y-524144D01*
G01X35777Y-525719D02*
X36247Y-526454D01*
X36873Y-526874D01*
X37578Y-526979D01*
X38205Y-526874D01*
X38832Y-526349D01*
X39223Y-525719D01*
X39302Y-525089D01*
X39145Y-524354D01*
X38597Y-523829D01*
X38048Y-523619D01*
X37343D01*
G01X38048D02*
X38518Y-523304D01*
X38910Y-522779D01*
X39067Y-522149D01*
X38910Y-521519D01*
X38518Y-520994D01*
X37813Y-520679D01*
X37108Y-520784D01*
X36403Y-521204D01*
G01X42077Y-525719D02*
X42547Y-526454D01*
X43173Y-526874D01*
X43878Y-526979D01*
X44505Y-526874D01*
X45132Y-526349D01*
X45523Y-525719D01*
X45602Y-525089D01*
X45445Y-524354D01*
X44897Y-523829D01*
X44348Y-523619D01*
X43643D01*
G01X44348D02*
X44818Y-523304D01*
X45210Y-522779D01*
X45367Y-522149D01*
X45210Y-521519D01*
X44818Y-520994D01*
X44113Y-520679D01*
X43408Y-520784D01*
X42703Y-521204D01*
G01X48377Y-525719D02*
X48847Y-526454D01*
X49473Y-526874D01*
X50178Y-526979D01*
X50805Y-526874D01*
X51432Y-526349D01*
X51823Y-525719D01*
X51902Y-525089D01*
X51745Y-524354D01*
X51197Y-523829D01*
X50648Y-523619D01*
X49943D01*
G01X50648D02*
X51118Y-523304D01*
X51510Y-522779D01*
X51667Y-522149D01*
X51510Y-521519D01*
X51118Y-520994D01*
X50413Y-520679D01*
X49708Y-520784D01*
X49003Y-521204D01*
G01X56243Y-526979D02*
X56400Y-525614D01*
X56635Y-524459D01*
X56948Y-523409D01*
X57340Y-522254D01*
X57967Y-520679D01*
X54833D01*
G01X62543Y-526979D02*
X62700Y-525614D01*
X62935Y-524459D01*
X63248Y-523409D01*
X63640Y-522254D01*
X64267Y-520679D01*
X61133D01*
G01X68843Y-528134D02*
X69157Y-526769D01*
G01X75300Y-520679D02*
Y-526979D01*
G01X73498Y-520679D02*
X77102D01*
G01X79642Y-526979D02*
X81600Y-520679D01*
X83558Y-526979D01*
G01X82853Y-524774D02*
X80347D01*
G01X86960Y-520679D02*
X88840D01*
G01X87900D02*
Y-526979D01*
G01X86960D02*
X88840D01*
G01X91850Y-520679D02*
X92947Y-526979D01*
X94200Y-520679D01*
X95453Y-526979D01*
X96550Y-520679D01*
G01X98542Y-526979D02*
X100500Y-520679D01*
X102458Y-526979D01*
G01X101753Y-524774D02*
X99247D01*
G01X104998Y-526979D02*
Y-520679D01*
X108602Y-526979D01*
Y-520679D01*
G01X119008Y-529079D02*
X118225Y-528029D01*
X117833Y-526979D01*
Y-522779D01*
X118225Y-521729D01*
X119008Y-520679D01*
G01X130433Y-526979D02*
Y-520679D01*
X132392D01*
X133018Y-520994D01*
X133410Y-521414D01*
X133567Y-522254D01*
X133410Y-523094D01*
X132940Y-523619D01*
X132392Y-523934D01*
X130433D01*
G01X132392D02*
X133567Y-526979D01*
G01X138300Y-527189D02*
X138143Y-527084D01*
Y-526874D01*
X138300Y-526769D01*
X138457Y-526874D01*
Y-527084D01*
X138300Y-527189D01*
G01X144600Y-526979D02*
X143973Y-526874D01*
X143425Y-526454D01*
X142955Y-525824D01*
X142642Y-525089D01*
X142485Y-524249D01*
Y-523409D01*
X142642Y-522569D01*
X142955Y-521834D01*
X143425Y-521204D01*
X143973Y-520784D01*
X144600Y-520679D01*
X145227Y-520784D01*
X145775Y-521204D01*
X146245Y-521834D01*
X146558Y-522569D01*
X146715Y-523409D01*
Y-524249D01*
X146558Y-525089D01*
X146245Y-525824D01*
X145775Y-526454D01*
X145227Y-526874D01*
X144600Y-526979D01*
G01X150900Y-527189D02*
X150743Y-527084D01*
Y-526874D01*
X150900Y-526769D01*
X151057Y-526874D01*
Y-527084D01*
X150900Y-527189D01*
G01X158923Y-521204D02*
X158453Y-520889D01*
X157905Y-520679D01*
X157278D01*
X156573Y-520994D01*
X156025Y-521519D01*
X155633Y-522149D01*
X155320Y-523199D01*
X155242Y-524144D01*
X155398Y-525089D01*
X155633Y-525719D01*
X156103Y-526349D01*
X156652Y-526769D01*
X157200Y-526979D01*
X157748D01*
X158297Y-526769D01*
X158767Y-526454D01*
X159158Y-526034D01*
G01X163500Y-527189D02*
X163343Y-527084D01*
Y-526874D01*
X163500Y-526769D01*
X163657Y-526874D01*
Y-527084D01*
X163500Y-527189D01*
G01X170192Y-529079D02*
X170975Y-528029D01*
X171367Y-526979D01*
Y-522779D01*
X170975Y-521729D01*
X170192Y-520679D01*
G01X6470Y-513829D02*
X8037D01*
Y-515719D01*
X7567Y-516349D01*
X7018Y-516769D01*
X6235Y-516979D01*
X5452Y-516769D01*
X4903Y-516349D01*
X4433Y-515719D01*
X4120Y-514984D01*
X3963Y-514144D01*
Y-513409D01*
X4120Y-512779D01*
X4433Y-512044D01*
X4903Y-511414D01*
X5373Y-510994D01*
X6000Y-510679D01*
X6548D01*
X7175Y-510889D01*
X7645Y-511309D01*
G01X10577Y-510679D02*
Y-515194D01*
X10890Y-516139D01*
X11517Y-516769D01*
X12300Y-516979D01*
X13083Y-516769D01*
X13710Y-516139D01*
X14023Y-515194D01*
Y-510679D01*
G01X17660D02*
X19540D01*
G01X18600D02*
Y-516979D01*
G01X17660D02*
X19540D01*
G01X23255Y-516139D02*
X23882Y-516664D01*
X24587Y-516979D01*
X25213D01*
X25840Y-516664D01*
X26310Y-516139D01*
X26545Y-515404D01*
X26388Y-514669D01*
X25997Y-514039D01*
X25292Y-513619D01*
X24352Y-513409D01*
X23803Y-512989D01*
X23568Y-512254D01*
X23725Y-511519D01*
X24117Y-510994D01*
X24665Y-510679D01*
X25213D01*
X25762Y-510889D01*
X26232Y-511414D01*
G01X29555Y-516979D02*
Y-510679D01*
G01X32845D02*
Y-516979D01*
G01Y-513829D02*
X29555D01*
G01X35542Y-516979D02*
X37500Y-510679D01*
X39458Y-516979D01*
G01X38753Y-514774D02*
X36247D01*
G01X41998Y-516979D02*
Y-510679D01*
X45602Y-516979D01*
Y-510679D01*
G01X54677Y-516979D02*
Y-510679D01*
X56243D01*
X56870Y-510994D01*
X57340Y-511414D01*
X57732Y-512044D01*
X58045Y-512779D01*
X58123Y-513829D01*
X58045Y-514879D01*
X57732Y-515614D01*
X57340Y-516244D01*
X56870Y-516664D01*
X56243Y-516979D01*
X54677D01*
G01X61760Y-510679D02*
X63640D01*
G01X62700D02*
Y-516979D01*
G01X61760D02*
X63640D01*
G01X67355Y-516139D02*
X67982Y-516664D01*
X68687Y-516979D01*
X69313D01*
X69940Y-516664D01*
X70410Y-516139D01*
X70645Y-515404D01*
X70488Y-514669D01*
X70097Y-514039D01*
X69392Y-513619D01*
X68452Y-513409D01*
X67903Y-512989D01*
X67668Y-512254D01*
X67825Y-511519D01*
X68217Y-510994D01*
X68765Y-510679D01*
X69313D01*
X69862Y-510889D01*
X70332Y-511414D01*
G01X75300Y-510679D02*
Y-516979D01*
G01X73498Y-510679D02*
X77102D01*
G01X81600Y-517189D02*
X81443Y-517084D01*
Y-516874D01*
X81600Y-516769D01*
X81757Y-516874D01*
Y-517084D01*
X81600Y-517189D01*
G01X87743Y-518134D02*
X88057Y-516769D01*
G01X94200Y-510679D02*
Y-516979D01*
G01X92398Y-510679D02*
X96002D01*
G01X98542Y-516979D02*
X100500Y-510679D01*
X102458Y-516979D01*
G01X101753Y-514774D02*
X99247D01*
G01X106800Y-516979D02*
X106173Y-516874D01*
X105625Y-516454D01*
X105155Y-515824D01*
X104842Y-515089D01*
X104685Y-514249D01*
Y-513409D01*
X104842Y-512569D01*
X105155Y-511834D01*
X105625Y-511204D01*
X106173Y-510784D01*
X106800Y-510679D01*
X107427Y-510784D01*
X107975Y-511204D01*
X108445Y-511834D01*
X108758Y-512569D01*
X108915Y-513409D01*
Y-514249D01*
X108758Y-515089D01*
X108445Y-515824D01*
X107975Y-516454D01*
X107427Y-516874D01*
X106800Y-516979D01*
G01X113100D02*
Y-514144D01*
X111533Y-510679D01*
G01X114667D02*
X113100Y-514144D01*
G01X117677Y-510679D02*
Y-515194D01*
X117990Y-516139D01*
X118617Y-516769D01*
X119400Y-516979D01*
X120183Y-516769D01*
X120810Y-516139D01*
X121123Y-515194D01*
Y-510679D01*
G01X123742Y-516979D02*
X125700Y-510679D01*
X127658Y-516979D01*
G01X126953Y-514774D02*
X124447D01*
G01X130198Y-516979D02*
Y-510679D01*
X133802Y-516979D01*
Y-510679D01*
G01X4198Y-506979D02*
Y-500679D01*
X7802Y-506979D01*
Y-500679D01*
G01X12300Y-506979D02*
X11673Y-506874D01*
X11125Y-506454D01*
X10655Y-505824D01*
X10342Y-505089D01*
X10185Y-504249D01*
Y-503409D01*
X10342Y-502569D01*
X10655Y-501834D01*
X11125Y-501204D01*
X11673Y-500784D01*
X12300Y-500679D01*
X12927Y-500784D01*
X13475Y-501204D01*
X13945Y-501834D01*
X14258Y-502569D01*
X14415Y-503409D01*
Y-504249D01*
X14258Y-505089D01*
X13945Y-505824D01*
X13475Y-506454D01*
X12927Y-506874D01*
X12300Y-506979D01*
G01X18600Y-507189D02*
X18443Y-507084D01*
Y-506874D01*
X18600Y-506769D01*
X18757Y-506874D01*
Y-507084D01*
X18600Y-507189D01*
G01X23412Y-501729D02*
X23882Y-501099D01*
X24430Y-500784D01*
X25057Y-500679D01*
X25840Y-500889D01*
X26388Y-501414D01*
X26545Y-502044D01*
X26467Y-502674D01*
X26153Y-503199D01*
X24587Y-504249D01*
X23882Y-504984D01*
X23412Y-506034D01*
X23255Y-506979D01*
X26545D01*
G01X31200D02*
Y-500679D01*
X30260Y-501939D01*
G01Y-506979D02*
X32140D01*
G01X37500D02*
Y-500679D01*
X36560Y-501939D01*
G01Y-506979D02*
X38440D01*
G01X43643Y-508134D02*
X43957Y-506769D01*
G01X47750Y-500679D02*
X48847Y-506979D01*
X50100Y-500679D01*
X51353Y-506979D01*
X52450Y-500679D01*
G01X57967Y-506979D02*
X54833D01*
Y-500679D01*
X57967D01*
G01X56713Y-503724D02*
X54833D01*
G01X60898Y-506979D02*
Y-500679D01*
X64502Y-506979D01*
Y-500679D01*
G01X67355Y-506979D02*
Y-500679D01*
G01X70645D02*
Y-506979D01*
G01Y-503829D02*
X67355D01*
G01X73577Y-500679D02*
Y-505194D01*
X73890Y-506139D01*
X74517Y-506769D01*
X75300Y-506979D01*
X76083Y-506769D01*
X76710Y-506139D01*
X77023Y-505194D01*
Y-500679D01*
G01X79642Y-506979D02*
X81600Y-500679D01*
X83558Y-506979D01*
G01X82853Y-504774D02*
X80347D01*
G01X92712Y-501729D02*
X93182Y-501099D01*
X93730Y-500784D01*
X94357Y-500679D01*
X95140Y-500889D01*
X95688Y-501414D01*
X95845Y-502044D01*
X95767Y-502674D01*
X95453Y-503199D01*
X93887Y-504249D01*
X93182Y-504984D01*
X92712Y-506034D01*
X92555Y-506979D01*
X95845D01*
G01X98698D02*
Y-500679D01*
X102302Y-506979D01*
Y-500679D01*
G01X105077Y-506979D02*
Y-500679D01*
X106643D01*
X107270Y-500994D01*
X107740Y-501414D01*
X108132Y-502044D01*
X108445Y-502779D01*
X108523Y-503829D01*
X108445Y-504879D01*
X108132Y-505614D01*
X107740Y-506244D01*
X107270Y-506664D01*
X106643Y-506979D01*
X105077D01*
G01X117833D02*
Y-500679D01*
X119792D01*
X120418Y-500994D01*
X120810Y-501414D01*
X120967Y-502254D01*
X120810Y-503094D01*
X120340Y-503619D01*
X119792Y-503934D01*
X117833D01*
G01X119792D02*
X120967Y-506979D01*
G01X123977D02*
Y-500679D01*
X125543D01*
X126170Y-500994D01*
X126640Y-501414D01*
X127032Y-502044D01*
X127345Y-502779D01*
X127423Y-503829D01*
X127345Y-504879D01*
X127032Y-505614D01*
X126640Y-506244D01*
X126170Y-506664D01*
X125543Y-506979D01*
X123977D01*
G01X132000Y-507189D02*
X131843Y-507084D01*
Y-506874D01*
X132000Y-506769D01*
X132157Y-506874D01*
Y-507084D01*
X132000Y-507189D01*
G01X28300Y-494279D02*
X25780Y-493862D01*
X23575Y-492196D01*
X21685Y-489696D01*
X20425Y-486779D01*
X19795Y-483446D01*
Y-480112D01*
X20425Y-476779D01*
X21685Y-473862D01*
X23575Y-471363D01*
X25780Y-469696D01*
X28300Y-469279D01*
X30820Y-469696D01*
X33025Y-471363D01*
X34915Y-473862D01*
X36175Y-476779D01*
X36805Y-480112D01*
Y-483446D01*
X36175Y-486779D01*
X34915Y-489696D01*
X33025Y-492196D01*
X30820Y-493862D01*
X28300Y-494279D01*
G01X30820Y-487612D02*
X34600Y-494279D01*
G01X48145Y-477613D02*
Y-489279D01*
X49405Y-492196D01*
X51295Y-493862D01*
X53500Y-494279D01*
X55705Y-493862D01*
X57595Y-492196D01*
X58855Y-489279D01*
G01Y-494279D02*
Y-477613D01*
G01X84370Y-494279D02*
Y-477613D01*
G01Y-480529D02*
X83110Y-478863D01*
X81220Y-478029D01*
X79015Y-477613D01*
X76810Y-478446D01*
X74920Y-480112D01*
X73660Y-482613D01*
X73030Y-485946D01*
X73660Y-489279D01*
X74920Y-491780D01*
X76810Y-493446D01*
X79015Y-494279D01*
X81220Y-493862D01*
X83110Y-492613D01*
X84370Y-490946D01*
G01X98545Y-494279D02*
Y-477613D01*
G01Y-481779D02*
X99805Y-479696D01*
X101695Y-478029D01*
X104215Y-477613D01*
X106420Y-478029D01*
X108310Y-479696D01*
X109255Y-482613D01*
Y-494279D01*
G01X129100Y-469279D02*
Y-494279D01*
G01X124690Y-477613D02*
X133510D01*
G01X159970Y-494279D02*
Y-477613D01*
G01Y-480529D02*
X158710Y-478863D01*
X156820Y-478029D01*
X154615Y-477613D01*
X152410Y-478446D01*
X150520Y-480112D01*
X149260Y-482613D01*
X148630Y-485946D01*
X149260Y-489279D01*
X150520Y-491780D01*
X152410Y-493446D01*
X154615Y-494279D01*
X156820Y-493862D01*
X158710Y-492613D01*
X159970Y-490946D01*
G01X199650Y-473979D02*
Y-481979D01*
X203650D01*
G01X211450D02*
Y-476646D01*
G01Y-477579D02*
X211050Y-477046D01*
X210450Y-476779D01*
X209750Y-476646D01*
X209050Y-476912D01*
X208450Y-477446D01*
X208050Y-478246D01*
X207850Y-479312D01*
X208050Y-480379D01*
X208450Y-481179D01*
X209050Y-481712D01*
X209750Y-481979D01*
X210450Y-481846D01*
X211050Y-481446D01*
X211450Y-480913D01*
G01X215550Y-484379D02*
X216150Y-484646D01*
X216950Y-484379D01*
X217450Y-483846D01*
X217850Y-483179D01*
X218450Y-481046D01*
X219750Y-476646D01*
G01X216550D02*
X218450Y-481046D01*
G01X224150Y-478379D02*
X227350D01*
X227050Y-477446D01*
X226550Y-476912D01*
X225850Y-476646D01*
X225150Y-476779D01*
X224550Y-477179D01*
X224150Y-478112D01*
X223950Y-478913D01*
Y-479712D01*
X224150Y-480512D01*
X224650Y-481312D01*
X225250Y-481846D01*
X225950Y-481979D01*
X226650Y-481712D01*
X227350Y-480913D01*
G01X232250Y-481979D02*
Y-476646D01*
G01Y-477712D02*
X232750Y-477179D01*
X233250Y-476779D01*
X233950Y-476646D01*
X234450Y-476779D01*
X235050Y-477179D01*
G01X223350Y-531979D02*
Y-523979D01*
X227950Y-531979D01*
Y-523979D01*
G01X233650Y-526646D02*
Y-531979D01*
G01Y-524512D02*
X233450Y-524379D01*
Y-524112D01*
X233650Y-523979D01*
X233850Y-524112D01*
Y-524379D01*
X233650Y-524512D01*
G01X239950Y-531979D02*
Y-526646D01*
G01Y-527979D02*
X240350Y-527312D01*
X240950Y-526779D01*
X241750Y-526646D01*
X242450Y-526779D01*
X243050Y-527312D01*
X243350Y-528246D01*
Y-531979D01*
G01X251450D02*
Y-526646D01*
G01Y-527579D02*
X251050Y-527046D01*
X250450Y-526779D01*
X249750Y-526646D01*
X249050Y-526912D01*
X248450Y-527446D01*
X248050Y-528246D01*
X247850Y-529312D01*
X248050Y-530379D01*
X248450Y-531179D01*
X249050Y-531712D01*
X249750Y-531979D01*
X250450Y-531846D01*
X251050Y-531446D01*
X251450Y-530913D01*
G01X229779Y-501936D02*
X231779D01*
Y-504336D01*
X231179Y-505136D01*
X230479Y-505669D01*
X229479Y-505936D01*
X228479Y-505669D01*
X227779Y-505136D01*
X227179Y-504336D01*
X226779Y-503403D01*
X226579Y-502336D01*
Y-501403D01*
X226779Y-500603D01*
X227179Y-499669D01*
X227779Y-498869D01*
X228379Y-498336D01*
X229179Y-497936D01*
X229879D01*
X230679Y-498203D01*
X231279Y-498736D01*
G01X234879Y-505936D02*
Y-497936D01*
X239479Y-505936D01*
Y-497936D01*
G01X242979Y-505936D02*
Y-497936D01*
X244979D01*
X245779Y-498336D01*
X246379Y-498869D01*
X246879Y-499669D01*
X247279Y-500603D01*
X247379Y-501936D01*
X247279Y-503269D01*
X246879Y-504203D01*
X246379Y-505003D01*
X245779Y-505536D01*
X244979Y-505936D01*
X242979D01*
G01X250979Y-504336D02*
X251579Y-505269D01*
X252379Y-505803D01*
X253279Y-505936D01*
X254079Y-505803D01*
X254879Y-505136D01*
X255379Y-504336D01*
X255479Y-503536D01*
X255279Y-502603D01*
X254579Y-501936D01*
X253879Y-501669D01*
X252979D01*
G01X253879D02*
X254479Y-501269D01*
X254979Y-500603D01*
X255179Y-499803D01*
X254979Y-499003D01*
X254479Y-498336D01*
X253579Y-497936D01*
X252679Y-498069D01*
X251779Y-498603D01*
G01X257179Y-483436D02*
X257879Y-483303D01*
X258679Y-482903D01*
X259179Y-482236D01*
X259379Y-481303D01*
X259179Y-480370D01*
X258579Y-479569D01*
X257679Y-479169D01*
X256679D01*
X256079Y-478903D01*
X255579Y-478236D01*
X255379Y-477303D01*
X255679Y-476369D01*
X256379Y-475703D01*
X257179Y-475436D01*
X257979Y-475703D01*
X258679Y-476369D01*
X258979Y-477303D01*
X258779Y-478236D01*
X258279Y-478903D01*
X257679Y-479169D01*
X256679D01*
X255779Y-479569D01*
X255179Y-480370D01*
X254979Y-481303D01*
X255179Y-482236D01*
X255679Y-482903D01*
X256479Y-483303D01*
X257179Y-483436D01*
G01X326250Y-525312D02*
X326850Y-524512D01*
X327550Y-524112D01*
X328350Y-523979D01*
X329350Y-524246D01*
X330050Y-524912D01*
X330250Y-525712D01*
X330150Y-526513D01*
X329750Y-527179D01*
X327750Y-528512D01*
X326850Y-529446D01*
X326250Y-530779D01*
X326050Y-531979D01*
X330250D01*
G01X336150Y-523979D02*
X335350Y-524246D01*
X334750Y-524912D01*
X334350Y-525712D01*
X334050Y-526779D01*
X333950Y-527979D01*
X334050Y-529179D01*
X334350Y-530246D01*
X334750Y-531046D01*
X335350Y-531712D01*
X336150Y-531979D01*
X336950Y-531712D01*
X337550Y-531046D01*
X337950Y-530246D01*
X338250Y-529179D01*
X338350Y-527979D01*
X338250Y-526779D01*
X337950Y-525712D01*
X337550Y-524912D01*
X336950Y-524246D01*
X336150Y-523979D01*
G01X342250Y-525312D02*
X342850Y-524512D01*
X343550Y-524112D01*
X344350Y-523979D01*
X345350Y-524246D01*
X346050Y-524912D01*
X346250Y-525712D01*
X346150Y-526513D01*
X345750Y-527179D01*
X343750Y-528512D01*
X342850Y-529446D01*
X342250Y-530779D01*
X342050Y-531979D01*
X346250D01*
G01X349950Y-530379D02*
X350550Y-531312D01*
X351350Y-531846D01*
X352250Y-531979D01*
X353050Y-531846D01*
X353850Y-531179D01*
X354350Y-530379D01*
X354450Y-529579D01*
X354250Y-528646D01*
X353550Y-527979D01*
X352850Y-527712D01*
X351950D01*
G01X352850D02*
X353450Y-527312D01*
X353950Y-526646D01*
X354150Y-525846D01*
X353950Y-525046D01*
X353450Y-524379D01*
X352550Y-523979D01*
X351650Y-524112D01*
X350750Y-524646D01*
G01X358350Y-532246D02*
X361950Y-523979D01*
G01X368150D02*
X367350Y-524246D01*
X366750Y-524912D01*
X366350Y-525712D01*
X366050Y-526779D01*
X365950Y-527979D01*
X366050Y-529179D01*
X366350Y-530246D01*
X366750Y-531046D01*
X367350Y-531712D01*
X368150Y-531979D01*
X368950Y-531712D01*
X369550Y-531046D01*
X369950Y-530246D01*
X370250Y-529179D01*
X370350Y-527979D01*
X370250Y-526779D01*
X369950Y-525712D01*
X369550Y-524912D01*
X368950Y-524246D01*
X368150Y-523979D01*
G01X373950Y-530379D02*
X374550Y-531312D01*
X375350Y-531846D01*
X376250Y-531979D01*
X377050Y-531846D01*
X377850Y-531179D01*
X378350Y-530379D01*
X378450Y-529579D01*
X378250Y-528646D01*
X377550Y-527979D01*
X376850Y-527712D01*
X375950D01*
G01X376850D02*
X377450Y-527312D01*
X377950Y-526646D01*
X378150Y-525846D01*
X377950Y-525046D01*
X377450Y-524379D01*
X376550Y-523979D01*
X375650Y-524112D01*
X374750Y-524646D01*
G01X382350Y-532246D02*
X385950Y-523979D01*
G01X390250Y-525312D02*
X390850Y-524512D01*
X391550Y-524112D01*
X392350Y-523979D01*
X393350Y-524246D01*
X394050Y-524912D01*
X394250Y-525712D01*
X394150Y-526513D01*
X393750Y-527179D01*
X391750Y-528512D01*
X390850Y-529446D01*
X390250Y-530779D01*
X390050Y-531979D01*
X394250D01*
G01X401350D02*
Y-523979D01*
X397650Y-529712D01*
X402650D01*
G01X325950Y-506979D02*
Y-498979D01*
X327950D01*
X328750Y-499379D01*
X329350Y-499912D01*
X329850Y-500712D01*
X330250Y-501646D01*
X330350Y-502979D01*
X330250Y-504312D01*
X329850Y-505246D01*
X329350Y-506046D01*
X328750Y-506579D01*
X327950Y-506979D01*
X325950D01*
G01X333650D02*
X336150Y-498979D01*
X338650Y-506979D01*
G01X337750Y-504179D02*
X334550D01*
G01X344150Y-498979D02*
X343350Y-499246D01*
X342750Y-499912D01*
X342350Y-500712D01*
X342050Y-501779D01*
X341950Y-502979D01*
X342050Y-504179D01*
X342350Y-505246D01*
X342750Y-506046D01*
X343350Y-506712D01*
X344150Y-506979D01*
X344950Y-506712D01*
X345550Y-506046D01*
X345950Y-505246D01*
X346250Y-504179D01*
X346350Y-502979D01*
X346250Y-501779D01*
X345950Y-500712D01*
X345550Y-499912D01*
X344950Y-499246D01*
X344150Y-498979D01*
G01X350250Y-506979D02*
Y-498979D01*
X354050D01*
G01X352650Y-502846D02*
X350250D01*
G01X360150Y-498979D02*
X359350Y-499246D01*
X358750Y-499912D01*
X358350Y-500712D01*
X358050Y-501779D01*
X357950Y-502979D01*
X358050Y-504179D01*
X358350Y-505246D01*
X358750Y-506046D01*
X359350Y-506712D01*
X360150Y-506979D01*
X360950Y-506712D01*
X361550Y-506046D01*
X361950Y-505246D01*
X362250Y-504179D01*
X362350Y-502979D01*
X362250Y-501779D01*
X361950Y-500712D01*
X361550Y-499912D01*
X360950Y-499246D01*
X360150Y-498979D01*
G01X368150D02*
Y-506979D01*
G01X365850Y-498979D02*
X370450D01*
G01X373550Y-506979D02*
Y-498979D01*
X376150Y-505646D01*
X378750Y-498979D01*
Y-506979D01*
G01X384950Y-502712D02*
X385350Y-502312D01*
X385650Y-501646D01*
X385850Y-500712D01*
X385650Y-499912D01*
X385250Y-499379D01*
X384550Y-498979D01*
X381850D01*
Y-506979D01*
X385150D01*
X385850Y-506446D01*
X386250Y-505646D01*
X386450Y-504712D01*
X386250Y-503779D01*
X385650Y-502979D01*
X384950Y-502712D01*
X381850D01*
G01X390950Y-498979D02*
X393350D01*
G01X392150D02*
Y-506979D01*
G01X390950D02*
X393350D01*
G01X398150Y-505379D02*
X398650Y-506179D01*
X399250Y-506712D01*
X399950Y-506979D01*
X400750Y-506712D01*
X401350Y-506179D01*
X401950Y-505379D01*
X402150Y-504312D01*
Y-498979D01*
G01X408150D02*
X407350Y-499246D01*
X406750Y-499912D01*
X406350Y-500712D01*
X406050Y-501779D01*
X405950Y-502979D01*
X406050Y-504179D01*
X406350Y-505246D01*
X406750Y-506046D01*
X407350Y-506712D01*
X408150Y-506979D01*
X408950Y-506712D01*
X409550Y-506046D01*
X409950Y-505246D01*
X410250Y-504179D01*
X410350Y-502979D01*
X410250Y-501779D01*
X409950Y-500712D01*
X409550Y-499912D01*
X408950Y-499246D01*
X408150Y-498979D01*
G01X343750Y-481979D02*
Y-473979D01*
X347550D01*
G01X346150Y-477846D02*
X343750D01*
G01X353650Y-473979D02*
X352850Y-474246D01*
X352250Y-474912D01*
X351850Y-475712D01*
X351550Y-476779D01*
X351450Y-477979D01*
X351550Y-479179D01*
X351850Y-480246D01*
X352250Y-481046D01*
X352850Y-481712D01*
X353650Y-481979D01*
X354450Y-481712D01*
X355050Y-481046D01*
X355450Y-480246D01*
X355750Y-479179D01*
X355850Y-477979D01*
X355750Y-476779D01*
X355450Y-475712D01*
X355050Y-474912D01*
X354450Y-474246D01*
X353650Y-473979D01*
G01X361650D02*
Y-481979D01*
G01X359350Y-473979D02*
X363950D01*
G01X366650Y-484646D02*
X372650D01*
G01X375050Y-481979D02*
Y-473979D01*
X377650Y-480646D01*
X380250Y-473979D01*
Y-481979D01*
G01X386450Y-477712D02*
X386850Y-477312D01*
X387150Y-476646D01*
X387350Y-475712D01*
X387150Y-474912D01*
X386750Y-474379D01*
X386050Y-473979D01*
X383350D01*
Y-481979D01*
X386650D01*
X387350Y-481446D01*
X387750Y-480646D01*
X387950Y-479712D01*
X387750Y-478779D01*
X387150Y-477979D01*
X386450Y-477712D01*
X383350D01*
G01X390650Y-484646D02*
X396650D01*
G01X403650Y-481979D02*
X399650D01*
Y-473979D01*
X403650D01*
G01X402050Y-477846D02*
X399650D01*
G01X407050Y-481979D02*
Y-473979D01*
X409650Y-480646D01*
X412250Y-473979D01*
Y-481979D01*
G01X417650D02*
X418350Y-481846D01*
X419150Y-481446D01*
X419650Y-480779D01*
X419850Y-479846D01*
X419650Y-478913D01*
X419050Y-478112D01*
X418150Y-477712D01*
X417150D01*
X416550Y-477446D01*
X416050Y-476779D01*
X415850Y-475846D01*
X416150Y-474912D01*
X416850Y-474246D01*
X417650Y-473979D01*
X418450Y-474246D01*
X419150Y-474912D01*
X419450Y-475846D01*
X419250Y-476779D01*
X418750Y-477446D01*
X418150Y-477712D01*
X417150D01*
X416250Y-478112D01*
X415650Y-478913D01*
X415450Y-479846D01*
X415650Y-480779D01*
X416150Y-481446D01*
X416950Y-481846D01*
X417650Y-481979D01*
G01X423950Y-481046D02*
X424650Y-481712D01*
X425450Y-481979D01*
X426250Y-481712D01*
X426950Y-480913D01*
X427450Y-479712D01*
X427650Y-478512D01*
Y-477046D01*
X427450Y-475846D01*
X426950Y-474779D01*
X426350Y-474246D01*
X425650Y-473979D01*
X424850Y-474246D01*
X424250Y-474779D01*
X423850Y-475579D01*
X423650Y-476646D01*
X423850Y-477579D01*
X424350Y-478512D01*
X424950Y-479046D01*
X425650Y-479179D01*
X426450Y-478913D01*
X427050Y-478246D01*
X427650Y-477046D01*
G01X433650Y-473979D02*
X432850Y-474246D01*
X432250Y-474912D01*
X431850Y-475712D01*
X431550Y-476779D01*
X431450Y-477979D01*
X431550Y-479179D01*
X431850Y-480246D01*
X432250Y-481046D01*
X432850Y-481712D01*
X433650Y-481979D01*
X434450Y-481712D01*
X435050Y-481046D01*
X435450Y-480246D01*
X435750Y-479179D01*
X435850Y-477979D01*
X435750Y-476779D01*
X435450Y-475712D01*
X435050Y-474912D01*
X434450Y-474246D01*
X433650Y-473979D01*
G01X439450Y-481979D02*
Y-473979D01*
G01X443250D02*
X439450Y-478913D01*
G01X443850Y-481979D02*
X441150Y-476646D01*
G01X414650Y-534979D02*
Y-526979D01*
X413450Y-528579D01*
G01Y-534979D02*
X415850D01*
G01X420750Y-531646D02*
X421450Y-530712D01*
X422050Y-530179D01*
X422850Y-529912D01*
X423550Y-530179D01*
X424050Y-530712D01*
X424450Y-531512D01*
X424550Y-532446D01*
X424450Y-533246D01*
X424050Y-534046D01*
X423450Y-534712D01*
X422750Y-534979D01*
X421950Y-534712D01*
X421250Y-533913D01*
X420850Y-532712D01*
X420750Y-531379D01*
X420950Y-529646D01*
X421250Y-528712D01*
X421750Y-527779D01*
X422450Y-527112D01*
X423150Y-526979D01*
X423850Y-527246D01*
X424350Y-527912D01*
G01X430650Y-535246D02*
X430450Y-535112D01*
Y-534846D01*
X430650Y-534712D01*
X430850Y-534846D01*
Y-535112D01*
X430650Y-535246D01*
G01X436750Y-531646D02*
X437450Y-530712D01*
X438050Y-530179D01*
X438850Y-529912D01*
X439550Y-530179D01*
X440050Y-530712D01*
X440450Y-531512D01*
X440550Y-532446D01*
X440450Y-533246D01*
X440050Y-534046D01*
X439450Y-534712D01*
X438750Y-534979D01*
X437950Y-534712D01*
X437250Y-533913D01*
X436850Y-532712D01*
X436750Y-531379D01*
X436950Y-529646D01*
X437250Y-528712D01*
X437750Y-527779D01*
X438450Y-527112D01*
X439150Y-526979D01*
X439850Y-527246D01*
X440350Y-527912D01*
G01X459650Y-534979D02*
Y-526979D01*
X458450Y-528579D01*
G01Y-534979D02*
X460850D01*
G01X467450D02*
X467650Y-533246D01*
X467950Y-531779D01*
X468350Y-530446D01*
X468850Y-528979D01*
X469650Y-526979D01*
X465650D01*
G01X475650Y-535246D02*
X475450Y-535112D01*
Y-534846D01*
X475650Y-534712D01*
X475850Y-534846D01*
Y-535112D01*
X475650Y-535246D01*
G01X481750Y-528312D02*
X482350Y-527512D01*
X483050Y-527112D01*
X483850Y-526979D01*
X484850Y-527246D01*
X485550Y-527912D01*
X485750Y-528712D01*
X485650Y-529513D01*
X485250Y-530179D01*
X483250Y-531512D01*
X482350Y-532446D01*
X481750Y-533779D01*
X481550Y-534979D01*
X485750D01*
G01X479650Y-508379D02*
X480150Y-509179D01*
X480750Y-509712D01*
X481450Y-509979D01*
X482250Y-509712D01*
X482850Y-509179D01*
X483450Y-508379D01*
X483650Y-507312D01*
Y-501979D01*
M02*
